G04 ================== begin FILE IDENTIFICATION RECORD ==================*
G04 Layout Name:  9324_DA0F0TMBIJ0_F0T_Motherboard_J_v01_20230324_0910.brd*
G04 Film Name:    pmt*
G04 File Format:  Gerber RS274X*
G04 File Origin:  Cadence Allegro 17.2-S081*
G04 Origin Date:  Sat Mar 25 08:44:53 2023*
G04 *
G04 Layer:  DRAWING FORMAT/TITLE_BLOCK_A*
G04 Layer:  VIA CLASS/PASTEMASK_TOP*
G04 Layer:  PACKAGE GEOMETRY/PASTEMASK_TOP*
G04 Layer:  DRAWING FORMAT/TITLE_BLOCK*
G04 Layer:  PIN/PASTEMASK_TOP*
G04 Layer:  MANUFACTURING/PHOTOPLOT_OUTLINE*
G04 Layer:  DRAWING FORMAT/TITLE_DATA_PMT*
G04 *
G04 Offset:    (0.00 0.00)*
G04 Mirror:    No*
G04 Mode:      Positive*
G04 Rotation:  0*
G04 FullContactRelief:  No*
G04 UndefLineWidth:     6.00*
G04 ================== end FILE IDENTIFICATION RECORD ====================*
%FSLAX25Y25*MOIN*%
%IR0*IPPOS*OFA0.00000B0.00000*MIA0B0*SFA1.00000B1.00000*%
%AMMACRO288*
4,1,28,.00051,-.00748,
.00051,-.00984,
.00602,-.00985,
.006695,-.009788,
.00735,-.009614,
.007964,-.009329,
.00852,-.008942,
.009,-.008464,
.00939,-.00791,
.009677,-.007296,
.009854,-.006642,
.009915,-.005967,
.00991,-.00592,
.00993,.0059,
.009875,.006576,
.009708,.007232,
.009429,.00785,
.009047,.008409,
.008574,.008894,
.008024,.009289,
.007413,.009583,
.006761,.009767,
.006087,.009834,
.00604,.00983,
.00053,.00984,
.00053,.00748,
-.0099,.00749,
-.00992,-.00747,
.00051,-.00748,
0.0*
%
%ADD288MACRO288*%
%AMMACRO285*
4,1,5,.00591,-.01772,
.00591,.01772,
0.0,.01772,
-.00591,.01181,
-.00591,-.01772,
.00591,-.01772,
0.0*
%
%ADD285MACRO285*%
%AMMACRO229*
4,1,32,-.06201,-.01575,
-.0502,-.01575,
-.0502,.00197,
-.04035,.00197,
-.04035,-.01575,
-.03248,-.01575,
-.03248,.00197,
-.02461,.00197,
-.02461,-.01575,
-.01673,-.01575,
-.01673,.00197,
-.00886,.00197,
-.00886,-.01575,
-.00098,-.01575,
-.00098,.00197,
.00689,.00197,
.00689,-.01575,
.01476,-.01575,
.01476,.00197,
.02264,.00197,
.02264,-.01575,
.03051,-.01575,
.03051,.00197,
.03839,.00197,
.03839,-.01575,
.04626,-.01575,
.04626,.00197,
.05413,.00197,
.05413,-.01575,
.06201,-.01575,
.06201,.01575,
-.06201,.01575,
-.06201,-.01575,
0.0*
%
%ADD229MACRO229*%
%ADD26O,.111X.062*%
%ADD265R,.017X.1*%
%AMMACRO227*
4,1,5,-.10039,-.10039,
-.10039,.08858,
-.08858,.10039,
.10039,.10039,
.10039,-.10039,
-.10039,-.10039,
0.0*
%
%ADD227MACRO227*%
%AMMACRO168*
4,1,5,-.01772,-.00591,
.01772,-.00591,
.01772,0.0,
.01181,.00591,
-.01772,.00591,
-.01772,-.00591,
0.0*
%
%ADD168MACRO168*%
%AMMACRO55*
4,1,8,.06299,-.02953,
.06299,.02953,
-.06299,.02953,
-.06299,-.02953,
-.01968,-.02953,
-.01968,.01771,
.01968,.01771,
.01968,-.02953,
.06299,-.02953,
0.0*
%
%ADD55MACRO55*%
%AMMACRO246*
21,1,.04,.071,0.0,0.0,135.*%
%ADD246MACRO246*%
%ADD82R,.17X.024*%
%AMMACRO287*
4,1,28,-.00052,-.00748,
-.00052,-.00984,
-.00603,-.00983,
-.006705,-.009775,
-.007359,-.0096,
-.007973,-.009313,
-.008528,-.008925,
-.009007,-.008446,
-.009395,-.007891,
-.009682,-.007277,
-.009857,-.006622,
-.009916,-.005948,
-.00992,-.0059,
-.0099,.00592,
-.009852,.006595,
-.009684,.007251,
-.009404,.007868,
-.009021,.008427,
-.008546,.008911,
-.007996,.009305,
-.007384,.009598,
-.006732,.00978,
-.006058,.009845,
-.00601,.00985,
-.0005,.00984,
-.0005,.00748,
.00993,.00747,
.00991,-.00749,
-.00052,-.00748,
0.0*
%
%ADD287MACRO287*%
%AMMACRO278*
4,1,32,-.05512,-.01181,
-.04331,-.01181,
-.04331,.00098,
-.03543,.00098,
-.03543,-.01181,
-.02362,-.01181,
-.02362,.00098,
-.01575,.00098,
-.01575,-.01181,
-.00394,-.01181,
-.00394,.00098,
.00394,.00098,
.00394,-.01181,
.01575,-.01181,
.01575,.00098,
.02362,.00098,
.02362,-.01181,
.03543,-.01181,
.03543,.00098,
.04331,.00098,
.04331,-.01181,
.05512,-.01181,
.05512,.00098,
.06299,.00098,
.06299,-.01181,
.0748,-.01181,
.0748,.01181,
-.0748,.01181,
-.0748,-.01181,
-.06299,-.01181,
-.06299,.00098,
-.05512,.00098,
-.05512,-.01181,
0.0*
%
%ADD278MACRO278*%
%ADD239R,.035X.231*%
%ADD183R,.11X.049*%
%ADD179R,.126X.06*%
%ADD111R,.024X.17*%
%AMMACRO90*
4,1,44,.01181,-.00295,
.01181,.00295,
.01178,.003292,
.011692,.003623,
.011548,.003934,
.011351,.004215,
.011109,.004458,
.010828,.004655,
.010517,.004801,
.010186,.00489,
.009845,.00492,
.00984,.00492,
-.00984,.00492,
-.010182,.00489,
-.010513,.004802,
-.010824,.004658,
-.011105,.004461,
-.011348,.004219,
-.011545,.003938,
-.011691,.003627,
-.01178,.003296,
-.01181,.002955,
-.01181,.00295,
-.01181,-.00295,
-.01178,-.003292,
-.011692,-.003623,
-.011548,-.003934,
-.011351,-.004215,
-.011109,-.004458,
-.010828,-.004655,
-.010517,-.004801,
-.010186,-.00489,
-.009845,-.00492,
-.00984,-.00492,
.00984,-.00492,
.010182,-.00489,
.010513,-.004802,
.010824,-.004658,
.011105,-.004461,
.011348,-.004219,
.011545,-.003938,
.011691,-.003627,
.01178,-.003296,
.01181,-.002955,
.01181,-.00295,
0.0*
%
%ADD90MACRO90*%
%ADD272R,.06X.126*%
%ADD224R,.022X.007*%
%ADD256C,.012*%
%ADD233R,.0041X.016*%
%ADD223R,.007X.022*%
%ADD169R,.032X.007*%
%ADD17C,.03*%
%ADD234R,.095X.111*%
%ADD232R,.007X.032*%
%ADD208O,.137X.064*%
%ADD158R,.031X.009*%
%ADD77R,.016X.0041*%
%ADD71R,.024X.007*%
%ADD157R,.009X.031*%
%ADD107R,.008X.014*%
%ADD70R,.007X.024*%
%ADD30R,.109X.036*%
%ADD274R,.119X.063*%
%ADD257C,.015*%
%ADD186R,.015X.009*%
%ADD149R,.026X.007*%
%ADD93C,.06*%
%ADD87R,.024X.009*%
%ADD222R,.063X.119*%
%ADD187R,.009X.015*%
%ADD182C,.016*%
%ADD153C,.061*%
%ADD148R,.007X.026*%
%AMMACRO109*
4,1,6,-.03,.08661,
-.03,-.01752,
-.00244,-.01752,
-.00244,-.08661,
.03,-.08661,
.03,.08661,
-.03,.08661,
0.0*
%
%ADD109MACRO109*%
%ADD85R,.009X.024*%
%AMMACRO62*
4,1,21,-.0035,-.0085,
-.0035,.012,
.0035,.012,
.0035,-.0085,
.003447,-.009108,
.003289,-.009697,
.003031,-.01025,
.002681,-.01075,
.00225,-.011181,
.00175,-.011531,
.001197,-.011789,
.000608,-.011947,
0.0,-.012,
-.000608,-.011947,
-.001197,-.011789,
-.00175,-.011531,
-.00225,-.011181,
-.002681,-.01075,
-.003031,-.01025,
-.003289,-.009697,
-.003447,-.009108,
-.0035,-.0085,
0.0*
%
%ADD62MACRO62*%
%ADD60R,.126X.048*%
%AMMACRO40*
4,1,21,.0085,-.0035,
-.012,-.0035,
-.012,.0035,
.0085,.0035,
.009108,.003447,
.009697,.003289,
.01025,.003031,
.01075,.002681,
.011181,.00225,
.011531,.00175,
.011789,.001197,
.011947,.000608,
.012,0.0,
.011947,-.000608,
.011789,-.001197,
.011531,-.00175,
.011181,-.00225,
.01075,-.002681,
.01025,-.003031,
.009697,-.003289,
.009108,-.003447,
.0085,-.0035,
0.0*
%
%ADD40MACRO40*%
%ADD139C,.026*%
%ADD79C,.062*%
%ADD266R,.017X.185*%
%ADD170R,.13X.0848*%
%AMMACRO146*
21,1,.016,.0041,0.0,0.0,45.322*%
%ADD146MACRO146*%
%ADD133C,.019*%
%ADD28C,.064*%
%ADD128R,.178X.054*%
%ADD73R,.0848X.13*%
%ADD195R,.032X.032*%
%ADD13C,.039*%
%ADD137R,.185X.085*%
%ADD94R,.06X.06*%
%ADD161R,.061X.061*%
%ADD175R,.166X.079*%
%ADD81R,.062X.062*%
%ADD127R,.178X.095*%
%ADD112R,.079X.166*%
%ADD241R,.064X.064*%
%AMMACRO279*
4,1,24,.01051,-.04391,
.01188,-.04527,
.03394,-.04527,
.03394,-.03346,
.02016,-.03348,
.02016,-.02559,
.03394,-.02559,
.03394,-.01379,
.02016,-.0138,
.02016,-.0059,
.03394,-.00592,
.03394,.00591,
.02016,.00589,
.02016,.01378,
.03394,.01378,
.03394,.0256,
.02016,.02557,
.02016,.03347,
.03394,.03347,
.03394,.04527,
.01188,.04527,
.00913,.04255,
-.03394,.04255,
-.03394,-.04391,
.01051,-.04391,
0.0*
%
%ADD279MACRO279*%
%ADD121R,.067X.067*%
%AMMACRO255*
4,1,28,-.00566,.00492,
-.00733,.00659,
-.01122,.00269,
-.011659,.002174,
-.011998,.001588,
-.01223,.000951,
-.012348,.000284,
-.012348,-.000393,
-.012231,-.001061,
-.012,-.001697,
-.011661,-.002284,
-.011226,-.002803,
-.01119,-.00284,
-.00284,-.01119,
-.002326,-.011631,
-.001744,-.011978,
-.00111,-.012217,
-.000444,-.012343,
.000233,-.012352,
.000902,-.012243,
.001541,-.012019,
.002132,-.011688,
.002656,-.011259,
.00269,-.01122,
.00659,-.00733,
.00492,-.00566,
.0123,.00172,
.00172,.0123,
-.00566,.00492,
0.0*
%
%ADD255MACRO255*%
%AMMACRO20*
4,1,28,-.00748,-.00052,
-.00984,-.00052,
-.00984,-.00603,
-.009782,-.006705,
-.009607,-.007359,
-.009321,-.007974,
-.008933,-.008529,
-.008455,-.009009,
-.0079,-.009398,
-.007286,-.009685,
-.006632,-.009861,
-.005957,-.00992,
-.00591,-.00992,
.00591,-.00992,
.006585,-.009869,
.007242,-.009701,
.007859,-.009421,
.008418,-.009039,
.008903,-.008565,
.009297,-.008015,
.009591,-.007404,
.009773,-.006751,
.00984,-.006077,
.00984,-.00603,
.00984,-.00052,
.00748,-.00052,
.00748,.00991,
-.00748,.00991,
-.00748,-.00052,
0.0*
%
%ADD20MACRO20*%
%AMMACRO120*
4,1,5,.00492,.01673,
-.00492,.01673,
-.00492,-.01673,
.00098,-.01673,
.00492,-.0128,
.00492,.01673,
0.0*
%
%ADD120MACRO120*%
%AMMACRO52*
4,1,5,.01378,.00098,
.01378,-.00492,
-.01378,-.00492,
-.01378,.00492,
.00984,.00492,
.01378,.00098,
0.0*
%
%ADD52MACRO52*%
%AMMACRO48*
4,1,5,.00098,-.01378,
-.00492,-.01378,
-.00492,.01378,
.00492,.01378,
.00492,-.00984,
.00098,-.01378,
0.0*
%
%ADD48MACRO48*%
%AMMACRO16*
4,1,28,-.00052,.00748,
-.00052,.00984,
-.00603,.00984,
-.006705,.009782,
-.007359,.009607,
-.007974,.009321,
-.008529,.008933,
-.009009,.008455,
-.009398,.0079,
-.009685,.007286,
-.009861,.006632,
-.00992,.005957,
-.00992,.00591,
-.00992,-.00591,
-.009869,-.006585,
-.009701,-.007242,
-.009421,-.007859,
-.009039,-.008418,
-.008565,-.008903,
-.008015,-.009297,
-.007404,-.009591,
-.006751,-.009773,
-.006077,-.00984,
-.00603,-.00984,
-.00052,-.00984,
-.00052,-.00748,
.00991,-.00748,
.00991,.00748,
-.00052,.00748,
0.0*
%
%ADD16MACRO16*%
%AMMACRO270*
4,1,5,.03378,-.03452,
.03378,.02664,
.02591,.03452,
-.03378,.03452,
-.03378,-.03452,
.03378,-.03452,
0.0*
%
%ADD270MACRO270*%
%AMMACRO254*
4,1,28,-.00493,.00565,
-.0066,.00732,
-.0027,.01121,
-.002185,.011649,
-.001599,.011989,
-.000962,.012222,
-.000295,.01234,
.000382,.012342,
.001049,.012225,
.001686,.011994,
.002273,.011657,
.002793,.011222,
.00283,.01119,
.01119,.00283,
.011629,.002313,
.011974,.00173,
.012212,.001096,
.012337,.00043,
.012344,-.000247,
.012234,-.000915,
.012009,-.001554,
.011677,-.002145,
.011247,-.002668,
.01121,-.0027,
.00732,-.0066,
.00565,-.00493,
-.00173,-.0123,
-.0123,-.00173,
-.00493,.00565,
0.0*
%
%ADD254MACRO254*%
%AMMACRO21*
4,1,28,-.00748,.00051,
-.00984,.00051,
-.00984,.00602,
-.009782,.006695,
-.009607,.007349,
-.009321,.007964,
-.008933,.008519,
-.008455,.008998,
-.0079,.009388,
-.007287,.009675,
-.006632,.009851,
-.005958,.00991,
-.00591,.00991,
.00591,.00991,
.006585,.009859,
.007242,.009691,
.007859,.009411,
.008418,.009029,
.008903,.008555,
.009297,.008005,
.00959,.007394,
.009773,.006742,
.00984,.006068,
.00984,.00602,
.00984,.00051,
.00748,.00051,
.00748,-.00992,
-.00748,-.00992,
-.00748,.00051,
0.0*
%
%ADD21MACRO21*%
%AMMACRO47*
4,1,5,-.00098,-.01378,
.00492,-.01378,
.00492,.01378,
-.00492,.01378,
-.00492,-.00984,
-.00098,-.01378,
0.0*
%
%ADD47MACRO47*%
%AMMACRO46*
4,1,5,.01378,-.00098,
.01378,.00492,
-.01378,.00492,
-.01378,-.00492,
.00984,-.00492,
.01378,-.00098,
0.0*
%
%ADD46MACRO46*%
%AMMACRO19*
4,1,28,.00051,.00748,
.00051,.00984,
.00602,.00984,
.006695,.009782,
.007349,.009607,
.007964,.009321,
.008519,.008933,
.008998,.008455,
.009388,.0079,
.009675,.007287,
.009851,.006632,
.00991,.005958,
.00991,.00591,
.00991,-.00591,
.009859,-.006585,
.009691,-.007242,
.009411,-.007859,
.009029,-.008418,
.008555,-.008903,
.008005,-.009297,
.007394,-.00959,
.006742,-.009773,
.006068,-.00984,
.00602,-.00984,
.00051,-.00984,
.00051,-.00748,
-.00992,-.00748,
-.00992,.00748,
.00051,.00748,
0.0*
%
%ADD19MACRO19*%
%AMMACRO119*
4,1,8,-.01821,.0246,
.01821,.0246,
.01821,.01476,
-.00837,.01476,
-.00837,-.01477,
.01821,-.01477,
.01821,-.02461,
-.01821,-.02461,
-.01821,.0246,
0.0*
%
%ADD119MACRO119*%
%AMMACRO56*
4,1,13,-.012,.00002,
-.011943,.000627,
-.011782,.001216,
-.011521,.001767,
-.011168,.002265,
-.010734,.002694,
-.010233,.003041,
-.009678,.003296,
-.009088,.00345,
-.0085,.0035,
.012,.0035,
.012,-.0035,
-.00848,-.0035,
-.012,.00002,
0.0*
%
%ADD56MACRO56*%
%AMMACRO59*
4,1,13,.00002,.012,
.000627,.011943,
.001216,.011782,
.001767,.011521,
.002265,.011168,
.002694,.010734,
.003041,.010233,
.003296,.009678,
.00345,.009088,
.0035,.0085,
.0035,-.012,
-.0035,-.012,
-.0035,.00848,
.00002,.012,
0.0*
%
%ADD59MACRO59*%
%AMMACRO83*
4,1,6,-.1063,-.04134,
-.1063,.01378,
-.03543,.01378,
-.03543,.04134,
.1063,.04134,
.1063,-.04134,
-.1063,-.04134,
0.0*
%
%ADD83MACRO83*%
%AMMACRO268*
4,1,6,-.04134,.1063,
.01378,.1063,
.01378,.03543,
.04134,.03543,
.04134,-.1063,
-.04134,-.1063,
-.04134,.1063,
0.0*
%
%ADD268MACRO268*%
%AMMACRO64*
4,1,13,-.00849,.0035,
.012,.0035,
.012,-.0035,
-.0085,-.0035,
-.009108,-.003447,
-.009697,-.003289,
-.01025,-.003031,
-.01075,-.002681,
-.011181,-.00225,
-.011531,-.00175,
-.011789,-.001197,
-.011947,-.000608,
-.012,-.00001,
-.00849,.0035,
0.0*
%
%ADD64MACRO64*%
%AMMACRO57*
4,1,13,.0035,.00849,
.0035,-.012,
-.0035,-.012,
-.0035,.0085,
-.003447,.009108,
-.003289,.009697,
-.003031,.01025,
-.002681,.01075,
-.00225,.011181,
-.00175,.011531,
-.001197,.011789,
-.000608,.011947,
-.00001,.012,
.0035,.00849,
0.0*
%
%ADD57MACRO57*%
%ADD258O,.013X.01*%
%ADD259O,.01X.013*%
%ADD218R,.02X.01*%
%ADD275R,.13X.13*%
%AMMACRO231*
4,1,5,-.00591,.01772,
-.00591,-.01772,
0.0,-.01772,
.00591,-.01181,
.00591,.01772,
-.00591,.01772,
0.0*
%
%ADD231MACRO231*%
%AMMACRO210*
4,1,5,-.05512,-.05512,
.04134,-.05512,
.05512,-.04134,
.05512,.05512,
-.05512,.05512,
-.05512,-.05512,
0.0*
%
%ADD210MACRO210*%
%ADD205R,.02X.011*%
%ADD131R,.02X.02*%
%ADD280R,.02X.012*%
%ADD163R,.02X.02*%
%ADD162R,.031X.01*%
%ADD102R,.022X.01*%
%ADD220R,.05X.01*%
%ADD206R,.021X.012*%
%ADD199R,.014X.01*%
%ADD113R,.032X.01*%
%ADD103R,.01X.022*%
%ADD282R,.023X.011*%
%ADD200R,.015X.01*%
%ADD198R,.01X.014*%
%ADD115R,.01X.05*%
%ADD114R,.01X.032*%
%ADD284R,.011X.023*%
%ADD281R,.024X.011*%
%ADD242R,.04X.022*%
%ADD197R,.01X.015*%
%ADD167R,.032X.012*%
%ADD110R,.061X.01*%
%ADD51R,.052X.01*%
%AMMACRO286*
4,1,32,.06201,.01575,
.0502,.01575,
.0502,-.00197,
.04035,-.00197,
.04035,.01575,
.03248,.01575,
.03248,-.00197,
.02461,-.00197,
.02461,.01575,
.01673,.01575,
.01673,-.00197,
.00886,-.00197,
.00886,.01575,
.00098,.01575,
.00098,-.00197,
-.00689,-.00197,
-.00689,.01575,
-.01476,.01575,
-.01476,-.00197,
-.02264,-.00197,
-.02264,.01575,
-.03051,.01575,
-.03051,-.00197,
-.03839,-.00197,
-.03839,.01575,
-.04626,.01575,
-.04626,-.00197,
-.05413,-.00197,
-.05413,.01575,
-.06201,.01575,
-.06201,-.01575,
.06201,-.01575,
.06201,.01575,
0.0*
%
%ADD286MACRO286*%
%ADD283R,.011X.024*%
%ADD238R,.02X.06*%
%ADD230R,.012X.032*%
%ADD189R,.022X.04*%
%ADD135R,.032X.022*%
%ADD106R,.126X.122*%
%ADD75R,.02X.016*%
%ADD38R,.05X.04*%
%ADD29R,.015X.012*%
%ADD11R,.034X.02*%
%ADD269R,.032X.04*%
%ADD184R,.012X.015*%
%AMMACRO165*
4,1,32,.01575,-.06201,
.01575,-.0502,
-.00197,-.0502,
-.00197,-.04035,
.01575,-.04035,
.01575,-.03248,
-.00197,-.03248,
-.00197,-.02461,
.01575,-.02461,
.01575,-.01673,
-.00197,-.01673,
-.00197,-.00886,
.01575,-.00886,
.01575,-.00098,
-.00197,-.00098,
-.00197,.00689,
.01575,.00689,
.01575,.01476,
-.00197,.01476,
-.00197,.02264,
.01575,.02264,
.01575,.03051,
-.00197,.03051,
-.00197,.03839,
.01575,.03839,
.01575,.04626,
-.00197,.04626,
-.00197,.05413,
.01575,.05413,
.01575,.06201,
-.01575,.06201,
-.01575,-.06201,
.01575,-.06201,
0.0*
%
%ADD165MACRO165*%
%ADD130R,.022X.032*%
%AMMACRO89*
4,1,44,.00295,.01181,
-.00295,.01181,
-.003292,.01178,
-.003623,.011692,
-.003934,.011548,
-.004215,.011351,
-.004458,.011109,
-.004655,.010828,
-.004801,.010517,
-.00489,.010186,
-.00492,.009845,
-.00492,.00984,
-.00492,-.00984,
-.00489,-.010182,
-.004802,-.010513,
-.004658,-.010824,
-.004461,-.011105,
-.004219,-.011348,
-.003938,-.011545,
-.003627,-.011691,
-.003296,-.01178,
-.002955,-.01181,
-.00295,-.01181,
.00295,-.01181,
.003292,-.01178,
.003623,-.011692,
.003934,-.011548,
.004215,-.011351,
.004458,-.011109,
.004655,-.010828,
.004801,-.010517,
.00489,-.010186,
.00492,-.009845,
.00492,-.00984,
.00492,.00984,
.00489,.010182,
.004802,.010513,
.004658,.010824,
.004461,.011105,
.004219,.011348,
.003938,.011545,
.003627,.011691,
.003296,.01178,
.002955,.01181,
.00295,.01181,
0.0*
%
%ADD89MACRO89*%
%ADD74R,.02X.017*%
%ADD68R,.061X.012*%
%ADD67R,.04X.05*%
%ADD49R,.036X.01*%
%ADD264R,.09X.011*%
%ADD226R,.018X.011*%
%ADD209R,.05X.015*%
%ADD192R,.028X.01*%
%ADD181R,.063X.011*%
%ADD160R,.04X.015*%
%ADD138R,.017X.02*%
%ADD25R,.02X.018*%
%ADD243R,.042X.024*%
%ADD225R,.011X.018*%
%ADD118R,.01X.028*%
%ADD84R,.018X.012*%
%ADD80R,.166X.13*%
%AMMACRO69*
21,1,.016,.0041,0.0,0.0,135.*%
%ADD69MACRO69*%
%ADD66R,.018X.02*%
%AMMACRO53*
4,1,8,-.06299,.02953,
-.06299,-.02953,
.06299,-.02953,
.06299,.02953,
.01968,.02953,
.01968,-.01771,
-.01968,-.01771,
-.01968,.02953,
-.06299,.02953,
0.0*
%
%ADD53MACRO53*%
%ADD22R,.029X.01*%
%ADD237R,.05X.035*%
%ADD216R,.27X.126*%
%ADD188R,.024X.042*%
%ADD177R,.063X.04*%
%ADD151R,.052X.024*%
%ADD147R,.044X.014*%
%ADD132R,.024X.016*%
%ADD104R,.012X.018*%
%ADD31R,.01X.029*%
%ADD244R,.014X.044*%
%ADD203R,.044X.024*%
%ADD172R,.036X.032*%
%ADD164R,.016X.024*%
%ADD140R,.024X.052*%
%ADD42R,.024X.017*%
%ADD18R,.036X.04*%
%ADD12R,.034X.016*%
%ADD267R,.052X.061*%
%ADD262R,.059X.01*%
%AMMACRO247*
21,1,.028,.032,0.0,0.0,45.*%
%ADD247MACRO247*%
%ADD236R,.024X.044*%
%AMMACRO193*
4,1,8,.01476,-.01771,
.01476,.01772,
-.01476,.01772,
-.01476,-.01771,
-.00492,-.01771,
-.00492,.00394,
.00492,.00394,
.00492,-.01771,
.01476,-.01771,
0.0*
%
%ADD193MACRO193*%
%ADD178R,.032X.036*%
%ADD176R,.044X.016*%
%ADD173R,.054X.024*%
%ADD155R,.017X.024*%
%ADD136R,.056X.04*%
%AMMACRO116*
4,1,8,.01771,.01476,
-.01772,.01476,
-.01772,-.01476,
.01771,-.01476,
.01771,-.00492,
-.00394,-.00492,
-.00394,.00492,
.01771,.00492,
.01771,.01476,
0.0*
%
%ADD116MACRO116*%
%ADD76R,.063X.015*%
%ADD37R,.032X.028*%
%ADD212R,.056X.05*%
%ADD196R,.048X.04*%
%ADD174R,.054X.016*%
%ADD159R,.04X.056*%
%ADD145R,.028X.032*%
%ADD141R,.046X.024*%
%ADD134R,.052X.018*%
%ADD78R,.056X.014*%
%ADD54R,.016X.044*%
%ADD35R,.024X.054*%
%ADD180R,.014X.056*%
%ADD91R,.024X.028*%
%ADD34R,.016X.054*%
%AMMACRO33*
4,1,40,.02165,-.00984,
.02165,.00984,
.021621,.010182,
.021532,.010513,
.021388,.010824,
.021192,.011105,
.02095,.011348,
.020669,.011545,
.020359,.01169,
.020028,.01178,
.01969,.01181,
-.01969,.01181,
-.020031,.011779,
-.020362,.011689,
-.020673,.011543,
-.020953,.011345,
-.021194,.011102,
-.02139,.01082,
-.021534,.010509,
-.021621,.010178,
-.02165,.00984,
-.02165,-.00984,
-.021621,-.010182,
-.021532,-.010513,
-.021388,-.010824,
-.021192,-.011105,
-.02095,-.011348,
-.020669,-.011545,
-.020359,-.01169,
-.020028,-.01178,
-.01969,-.01181,
.01969,-.01181,
.020031,-.011779,
.020362,-.011689,
.020673,-.011543,
.020953,-.011345,
.021194,-.011102,
.02139,-.01082,
.021534,-.010509,
.021621,-.010178,
.02165,-.00984,
0.0*
%
%ADD33MACRO33*%
%ADD245R,.044X.054*%
%ADD204R,.058X.014*%
%ADD143R,.049X.014*%
%ADD142R,.046X.017*%
%ADD129C,.315*%
%ADD123R,.056X.052*%
%ADD101R,.06X.057*%
%ADD235R,.028X.018*%
%ADD228R,.079X.012*%
%ADD207R,.022X.068*%
%ADD202R,.048X.025*%
%ADD190R,.052X.056*%
%ADD185R,.063X.046*%
%ADD144R,.059X.014*%
%ADD126R,.038X.026*%
%ADD96R,.091X.081*%
%ADD95R,.036X.063*%
%ADD36R,.015X.057*%
%ADD263R,.026X.038*%
%ADD166R,.012X.079*%
%ADD154R,.014X.059*%
%ADD152R,.018X.028*%
%ADD124R,.066X.017*%
%ADD99R,.081X.091*%
%AMMACRO65*
4,1,21,-.0085,.0035,
.012,.0035,
.012,-.0035,
-.0085,-.0035,
-.009108,-.003447,
-.009697,-.003289,
-.01025,-.003031,
-.01075,-.002681,
-.011181,-.00225,
-.011531,-.00175,
-.011789,-.001197,
-.011947,-.000608,
-.012,0.0,
-.011947,.000608,
-.011789,.001197,
-.011531,.00175,
-.011181,.00225,
-.01075,.002681,
-.01025,.003031,
-.009697,.003289,
-.009108,.003447,
-.0085,.0035,
0.0*
%
%ADD65MACRO65*%
%ADD32R,.14X.14*%
%AMMACRO277*
4,1,30,.08089,-.09065,
.08227,-.09203,
.10433,-.09203,
.10433,-.08022,
.08309,-.08022,
.08171,-.07884,
.02464,-.07884,
.02464,.02608,
.06988,.02609,
.06988,.09203,
-.06988,.09203,
-.06988,.01427,
-.04035,.01427,
-.04035,-.02116,
-.10433,-.02117,
-.10433,-.03298,
-.09055,-.03298,
-.09055,-.04085,
-.10433,-.04084,
-.10433,-.05261,
-.09055,-.05266,
-.09055,-.06053,
-.10433,-.06054,
-.10433,-.07237,
-.09055,-.07237,
-.09055,-.08022,
-.10433,-.08022,
-.10433,-.09203,
-.08227,-.09203,
-.08089,-.09065,
.08089,-.09065,
0.0*
%
%ADD277MACRO277*%
%AMMACRO271*
4,1,6,.03,-.08661,
.03,.01752,
.00244,.01752,
.00244,.08661,
-.03,.08661,
-.03,-.08661,
.03,-.08661,
0.0*
%
%ADD271MACRO271*%
%ADD240R,.059X.017*%
%AMMACRO58*
4,1,21,.0035,.0085,
.0035,-.012,
-.0035,-.012,
-.0035,.0085,
-.003447,.009108,
-.003289,.009697,
-.003031,.01025,
-.002681,.01075,
-.00225,.011181,
-.00175,.011531,
-.001197,.011789,
-.000608,.011947,
0.0,.012,
.000608,.011947,
.001197,.011789,
.00175,.011531,
.00225,.011181,
.002681,.01075,
.003031,.01025,
.003289,.009697,
.003447,.009108,
.0035,.0085,
0.0*
%
%ADD58MACRO58*%
%ADD276R,.197X.128*%
%ADD260R,.056X.048*%
%ADD156R,.124X.124*%
%ADD125C,.009*%
%ADD191R,.134X.134*%
%ADD108R,.024X.089*%
%ADD92R,.099X.042*%
%ADD171R,.069X.046*%
%ADD97R,.042X.099*%
%ADD72R,.144X.144*%
%ADD10C,.394*%
%ADD201R,.059X.048*%
%ADD214R,.048X.059*%
%ADD27R,.059X.02047*%
%ADD213R,.189X.186*%
%ADD150R,.174X.174*%
%ADD98R,.077X.069*%
%AMMACRO253*
4,1,28,.00492,.00566,
.00659,.00733,
.00269,.01122,
.002174,.011659,
.001588,.011998,
.000951,.01223,
.000284,.012348,
-.000393,.012348,
-.001061,.012231,
-.001697,.012,
-.002284,.011661,
-.002803,.011226,
-.00284,.01119,
-.01119,.00284,
-.011631,.002326,
-.011978,.001744,
-.012217,.00111,
-.012343,.000444,
-.012352,-.000233,
-.012243,-.000902,
-.012019,-.001541,
-.011688,-.002132,
-.011259,-.002656,
-.01122,-.00269,
-.00733,-.00659,
-.00566,-.00492,
.00172,-.0123,
.0123,-.00172,
.00492,.00566,
0.0*
%
%ADD253MACRO253*%
%AMMACRO251*
4,1,28,-.00492,-.00566,
-.00659,-.00733,
-.00269,-.01122,
-.002174,-.011659,
-.001588,-.011998,
-.000951,-.01223,
-.000284,-.012348,
.000393,-.012348,
.001061,-.012231,
.001697,-.012,
.002284,-.011661,
.002803,-.011226,
.00284,-.01119,
.01119,-.00284,
.011631,-.002326,
.011978,-.001744,
.012217,-.00111,
.012343,-.000444,
.012352,.000233,
.012243,.000902,
.012019,.001541,
.011688,.002132,
.011259,.002656,
.01122,.00269,
.00733,.00659,
.00566,.00492,
-.00172,.0123,
-.0123,.00172,
-.00492,-.00566,
0.0*
%
%ADD251MACRO251*%
%AMMACRO249*
4,1,28,.00566,-.00492,
.00733,-.00659,
.01122,-.00269,
.011659,-.002174,
.011998,-.001588,
.01223,-.000951,
.012348,-.000284,
.012348,.000393,
.012231,.001061,
.012,.001697,
.011661,.002284,
.011226,.002803,
.01119,.00284,
.00284,.01119,
.002326,.011631,
.001744,.011978,
.00111,.012217,
.000444,.012343,
-.000233,.012352,
-.000902,.012243,
-.001541,.012019,
-.002132,.011688,
-.002656,.011259,
-.00269,.01122,
-.00659,.00733,
-.00492,.00566,
-.0123,-.00172,
-.00172,-.0123,
.00566,-.00492,
0.0*
%
%ADD249MACRO249*%
%ADD86R,.069X.077*%
%AMMACRO24*
4,1,28,.00748,.00052,
.00984,.00052,
.00984,.00603,
.009782,.006705,
.009607,.007359,
.009321,.007974,
.008933,.008529,
.008455,.009009,
.0079,.009398,
.007286,.009685,
.006632,.009861,
.005957,.00992,
.00591,.00992,
-.00591,.00992,
-.006585,.009869,
-.007242,.009701,
-.007859,.009421,
-.008418,.009039,
-.008903,.008565,
-.009297,.008015,
-.009591,.007404,
-.009773,.006751,
-.00984,.006077,
-.00984,.00603,
-.00984,.00052,
-.00748,.00052,
-.00748,-.00991,
.00748,-.00991,
.00748,.00052,
0.0*
%
%ADD24MACRO24*%
%AMMACRO15*
4,1,28,.00052,-.00748,
.00052,-.00984,
.00603,-.00984,
.006705,-.009782,
.007359,-.009607,
.007974,-.009321,
.008529,-.008933,
.009009,-.008455,
.009398,-.0079,
.009685,-.007286,
.009861,-.006632,
.00992,-.005957,
.00992,-.00591,
.00992,.00591,
.009869,.006585,
.009701,.007242,
.009421,.007859,
.009039,.008418,
.008565,.008903,
.008015,.009297,
.007404,.009591,
.006751,.009773,
.006077,.00984,
.00603,.00984,
.00052,.00984,
.00052,.00748,
-.00991,.00748,
-.00991,-.00748,
.00052,-.00748,
0.0*
%
%ADD15MACRO15*%
%AMMACRO261*
21,1,.016,.0041,0.0,0.0,134.695*%
%ADD261MACRO261*%
%ADD122R,.099X.067*%
%ADD217R,.067X.099*%
%AMMACRO100*
4,1,5,-.03378,.03452,
-.03378,-.02664,
-.02591,-.03452,
.03378,-.03452,
.03378,.03452,
-.03378,.03452,
0.0*
%
%ADD100MACRO100*%
%AMMACRO211*
4,1,5,.04823,-.03445,
.04823,.04823,
-.04823,.04823,
-.04823,-.04823,
.03445,-.04823,
.04823,-.03445,
0.0*
%
%ADD211MACRO211*%
%AMMACRO252*
4,1,28,.00565,.00493,
.00732,.0066,
.01121,.0027,
.011649,.002185,
.011989,.001599,
.012222,.000962,
.01234,.000295,
.012342,-.000382,
.012225,-.001049,
.011994,-.001686,
.011657,-.002273,
.011222,-.002793,
.01119,-.00283,
.00283,-.01119,
.002313,-.011629,
.00173,-.011974,
.001096,-.012212,
.00043,-.012337,
-.000247,-.012344,
-.000915,-.012234,
-.001554,-.012009,
-.002145,-.011677,
-.002668,-.011247,
-.0027,-.01121,
-.0066,-.00732,
-.00493,-.00565,
-.0123,.00173,
-.00173,.0123,
.00565,.00493,
0.0*
%
%ADD252MACRO252*%
%AMMACRO250*
4,1,28,-.00565,-.00493,
-.00732,-.0066,
-.01121,-.0027,
-.011649,-.002185,
-.011989,-.001599,
-.012222,-.000962,
-.01234,-.000295,
-.012342,.000382,
-.012225,.001049,
-.011994,.001686,
-.011657,.002273,
-.011222,.002793,
-.01119,.00283,
-.00283,.01119,
-.002313,.011629,
-.00173,.011974,
-.001096,.012212,
-.00043,.012337,
.000247,.012344,
.000915,.012234,
.001554,.012009,
.002145,.011677,
.002668,.011247,
.0027,.01121,
.0066,.00732,
.00493,.00565,
.0123,-.00173,
.00173,-.0123,
-.00565,-.00493,
0.0*
%
%ADD250MACRO250*%
%AMMACRO248*
4,1,28,.00493,-.00565,
.0066,-.00732,
.0027,-.01121,
.002185,-.011649,
.001599,-.011989,
.000962,-.012222,
.000295,-.01234,
-.000382,-.012342,
-.001049,-.012225,
-.001686,-.011994,
-.002273,-.011657,
-.002793,-.011222,
-.00283,-.01119,
-.01119,-.00283,
-.011629,-.002313,
-.011974,-.00173,
-.012212,-.001096,
-.012337,-.00043,
-.012344,.000247,
-.012234,.000915,
-.012009,.001554,
-.011677,.002145,
-.011247,.002668,
-.01121,.0027,
-.00732,.0066,
-.00565,.00493,
.00173,.0123,
.0123,.00173,
.00493,-.00565,
0.0*
%
%ADD248MACRO248*%
%AMMACRO221*
4,1,5,.01673,-.00492,
.01673,.00492,
-.01673,.00492,
-.01673,-.00098,
-.0128,-.00492,
.01673,-.00492,
0.0*
%
%ADD221MACRO221*%
%AMMACRO43*
4,1,5,-.01378,-.00098,
-.01378,.00492,
.01378,.00492,
.01378,-.00492,
-.00984,-.00492,
-.01378,-.00098,
0.0*
%
%ADD43MACRO43*%
%AMMACRO23*
4,1,28,.00748,-.00051,
.00984,-.00051,
.00984,-.00602,
.009782,-.006695,
.009607,-.007349,
.009321,-.007964,
.008933,-.008519,
.008455,-.008998,
.0079,-.009388,
.007287,-.009675,
.006632,-.009851,
.005958,-.00991,
.00591,-.00991,
-.00591,-.00991,
-.006585,-.009859,
-.007242,-.009691,
-.007859,-.009411,
-.008418,-.009029,
-.008903,-.008555,
-.009297,-.008005,
-.00959,-.007394,
-.009773,-.006742,
-.00984,-.006068,
-.00984,-.00602,
-.00984,-.00051,
-.00748,-.00051,
-.00748,.00992,
.00748,.00992,
.00748,-.00051,
0.0*
%
%ADD23MACRO23*%
%AMMACRO14*
4,1,28,-.00051,-.00748,
-.00051,-.00984,
-.00602,-.00984,
-.006695,-.009782,
-.007349,-.009607,
-.007964,-.009321,
-.008519,-.008933,
-.008998,-.008455,
-.009388,-.0079,
-.009675,-.007287,
-.009851,-.006632,
-.00991,-.005958,
-.00991,-.00591,
-.00991,.00591,
-.009859,.006585,
-.009691,.007242,
-.009411,.007859,
-.009029,.008418,
-.008555,.008903,
-.008005,.009297,
-.007394,.00959,
-.006742,.009773,
-.006068,.00984,
-.00602,.00984,
-.00051,.00984,
-.00051,.00748,
.00992,.00748,
.00992,-.00748,
-.00051,-.00748,
0.0*
%
%ADD14MACRO14*%
%AMMACRO45*
4,1,5,-.00098,.01378,
.00492,.01378,
.00492,-.01378,
-.00492,-.01378,
-.00492,.00984,
-.00098,.01378,
0.0*
%
%ADD45MACRO45*%
%AMMACRO63*
4,1,13,-.00002,-.012,
-.000627,-.011943,
-.001216,-.011782,
-.001767,-.011521,
-.002265,-.011168,
-.002694,-.010734,
-.003041,-.010233,
-.003296,-.009678,
-.00345,-.009088,
-.0035,-.0085,
-.0035,.012,
.0035,.012,
.0035,-.00848,
-.00002,-.012,
0.0*
%
%ADD63MACRO63*%
%AMMACRO41*
4,1,13,.012,-.00002,
.011943,-.000627,
.011782,-.001216,
.011521,-.001767,
.011168,-.002265,
.010734,-.002694,
.010233,-.003041,
.009678,-.003296,
.009088,-.00345,
.0085,-.0035,
-.012,-.0035,
-.012,.0035,
.00848,.0035,
.012,-.00002,
0.0*
%
%ADD41MACRO41*%
%AMMACRO105*
4,1,6,.04134,-.1063,
-.01378,-.1063,
-.01378,-.03543,
-.04134,-.03543,
-.04134,.1063,
.04134,.1063,
.04134,-.1063,
0.0*
%
%ADD105MACRO105*%
%AMMACRO50*
4,1,5,-.01378,.00098,
-.01378,-.00492,
.01378,-.00492,
.01378,.00492,
-.00984,.00492,
-.01378,.00098,
0.0*
%
%ADD50MACRO50*%
%AMMACRO219*
4,1,8,.0246,.01821,
.0246,-.01821,
.01476,-.01821,
.01476,.00837,
-.01477,.00837,
-.01477,-.01821,
-.02461,-.01821,
-.02461,.01821,
.0246,.01821,
0.0*
%
%ADD219MACRO219*%
%AMMACRO117*
4,1,9,.01181,.01476,
-.01771,.01476,
-.01771,.00492,
.00394,.00492,
.00394,-.00492,
-.01771,-.00492,
-.01771,-.01476,
.01772,-.01476,
.01772,.00886,
.01181,.01476,
0.0*
%
%ADD117MACRO117*%
%AMMACRO44*
4,1,5,.00098,.01378,
-.00492,.01378,
-.00492,-.01378,
.00492,-.01378,
.00492,.00984,
.00098,.01378,
0.0*
%
%ADD44MACRO44*%
%AMMACRO194*
4,1,9,.01476,-.01181,
.01476,.01771,
.00492,.01771,
.00492,-.00394,
-.00492,-.00394,
-.00492,.01771,
-.01476,.01771,
-.01476,-.01772,
.00886,-.01772,
.01476,-.01181,
0.0*
%
%ADD194MACRO194*%
%AMMACRO61*
4,1,13,-.0035,-.00849,
-.0035,.012,
.0035,.012,
.0035,-.0085,
.003447,-.009108,
.003289,-.009697,
.003031,-.01025,
.002681,-.01075,
.00225,-.011181,
.00175,-.011531,
.001197,-.011789,
.000608,-.011947,
.00001,-.012,
-.0035,-.00849,
0.0*
%
%ADD61MACRO61*%
%AMMACRO39*
4,1,13,.00849,-.0035,
-.012,-.0035,
-.012,.0035,
.0085,.0035,
.009108,.003447,
.009697,.003289,
.01025,.003031,
.01075,.002681,
.011181,.00225,
.011531,.00175,
.011789,.001197,
.011947,.000608,
.012,.00001,
.00849,-.0035,
0.0*
%
%ADD39MACRO39*%
%ADD289C,.006*%
G75*
%LPD*%
G75*
G54D100*
X205439Y684016D03*
G54D101*
X205161Y691777D03*
X1651812Y596805D03*
G54D110*
X229825Y423824D03*
Y426383D03*
Y428942D03*
Y431501D03*
Y434060D03*
Y436619D03*
Y439179D03*
Y441738D03*
Y444297D03*
Y446856D03*
Y449415D03*
Y451974D03*
X251873Y428942D03*
Y426383D03*
Y423824D03*
Y444297D03*
Y441738D03*
Y439179D03*
Y436619D03*
Y434060D03*
Y431501D03*
Y451974D03*
Y449415D03*
Y446856D03*
X464994Y513372D03*
Y515931D03*
Y518490D03*
Y521049D03*
Y523608D03*
Y526167D03*
Y528727D03*
Y531286D03*
Y533845D03*
Y536404D03*
Y538963D03*
Y541522D03*
X487042Y526167D03*
Y523608D03*
Y521049D03*
Y518490D03*
Y515931D03*
Y513372D03*
Y541522D03*
Y538963D03*
Y536404D03*
Y533845D03*
Y531286D03*
Y528727D03*
G54D200*
X779270Y1580602D03*
Y1582570D03*
Y1584539D03*
Y1586507D03*
Y1588476D03*
Y1590444D03*
X796888Y1582570D03*
Y1580602D03*
Y1590444D03*
Y1588476D03*
Y1586507D03*
Y1584539D03*
X821270Y1580602D03*
Y1582570D03*
Y1584539D03*
Y1586507D03*
Y1588476D03*
Y1590444D03*
X838888Y1582570D03*
Y1580602D03*
Y1590444D03*
Y1588476D03*
Y1586507D03*
Y1584539D03*
X863270Y1580602D03*
Y1582570D03*
Y1584539D03*
Y1586507D03*
Y1588476D03*
Y1590444D03*
X880888Y1582570D03*
Y1580602D03*
Y1590444D03*
Y1588476D03*
Y1586507D03*
Y1584539D03*
X905270Y1580602D03*
Y1582570D03*
Y1584539D03*
Y1586507D03*
Y1588476D03*
Y1590444D03*
X922888Y1582570D03*
Y1580602D03*
Y1590444D03*
Y1588476D03*
Y1586507D03*
Y1584539D03*
G54D201*
X841742Y105951D03*
Y99651D03*
X850088Y105951D03*
Y99651D03*
X970738Y344659D03*
Y350959D03*
X979084Y344659D03*
Y350959D03*
G54D102*
X199866Y680633D03*
Y682602D03*
Y684570D03*
Y686539D03*
Y688507D03*
Y690476D03*
Y692444D03*
X432640Y1632513D03*
Y1630545D03*
Y1628576D03*
Y1626608D03*
Y1624639D03*
Y1622671D03*
Y1620702D03*
Y1634482D03*
X451340Y1632513D03*
Y1630545D03*
Y1628576D03*
Y1626608D03*
Y1624639D03*
Y1622671D03*
Y1620702D03*
Y1634482D03*
X919407Y981813D03*
Y983781D03*
Y985750D03*
Y987718D03*
Y989687D03*
Y991655D03*
X934171Y981813D03*
Y991655D03*
Y989687D03*
Y987718D03*
Y985750D03*
Y983781D03*
X1657107Y607949D03*
Y605980D03*
Y604012D03*
Y602043D03*
Y600075D03*
Y598106D03*
Y596138D03*
G54D210*
X925189Y499086D03*
G54D120*
X274301Y115216D03*
X707457Y119341D03*
X1749422Y116340D03*
G54D111*
X227557Y582055D03*
Y616055D03*
Y650055D03*
X1626416Y638527D03*
Y672527D03*
Y706527D03*
G54D211*
X926789Y986734D03*
G54D10*
X27559Y87795D03*
X40708Y631890D03*
Y1368897D03*
X51181Y1714961D03*
X373622Y87795D03*
X395670Y1714961D03*
X661023Y631890D03*
X707677Y1714961D03*
X800787Y87795D03*
X931692Y757874D03*
Y1072834D03*
Y1387795D03*
X1045865Y87795D03*
X1155708Y1714961D03*
X1271260Y631890D03*
X1461805Y1714961D03*
X1499606Y87795D03*
X1816771Y631890D03*
Y1368897D03*
X1806299Y1714961D03*
X1829921Y87795D03*
G54D202*
X842684Y389140D03*
Y392880D03*
Y396620D03*
X852998D03*
Y392880D03*
Y389140D03*
G54D130*
X336240Y147638D03*
X332500D03*
X328760D03*
Y157086D03*
X336240D03*
X513444Y460733D03*
Y470181D03*
X517184D03*
X520924Y460733D03*
Y470181D03*
X762013Y1703816D03*
X754533D03*
Y1713264D03*
X758273D03*
X762013D03*
X1542401Y147711D03*
Y138263D03*
X1549881Y147711D03*
Y138263D03*
X1546141D03*
X1729954Y411578D03*
X1737434D03*
Y402130D03*
X1733694D03*
X1729954D03*
X1765670Y444538D03*
Y453986D03*
X1769410D03*
X1773150Y444538D03*
Y453986D03*
G54D103*
X207996Y678369D03*
X206027D03*
X204059D03*
X202090D03*
X209964D03*
X435100Y1618242D03*
Y1636942D03*
X437069Y1618242D03*
X439037D03*
X441006D03*
X442974D03*
X444943D03*
X446911D03*
X448880D03*
X437069Y1636942D03*
X439037D03*
X441006D03*
X442974D03*
X444943D03*
X446911D03*
X448880D03*
X923836Y979352D03*
X921868D03*
Y994116D03*
X923836D03*
X931710Y979352D03*
X929742D03*
X927773D03*
X925805D03*
Y994116D03*
X927773D03*
X929742D03*
X931710D03*
X1647009Y610213D03*
X1648977D03*
X1650946D03*
X1652914D03*
X1654883D03*
G54D220*
X999455Y201049D03*
Y197506D03*
Y193962D03*
Y204592D03*
G54D121*
X286253Y154803D03*
X601156Y205978D03*
X823514Y136898D03*
X847479Y214391D03*
X1174681Y1625220D03*
X1734992Y370384D03*
G54D112*
X236435Y582055D03*
Y616055D03*
Y650055D03*
X254545Y582055D03*
Y616055D03*
Y650055D03*
X1599428Y638527D03*
Y672527D03*
Y706527D03*
X1617538Y638527D03*
Y672527D03*
Y706527D03*
G54D221*
X1004868Y190419D03*
G54D122*
X285803Y243637D03*
X301551D03*
X312693Y59753D03*
X328441D03*
X747269Y79238D03*
X763017D03*
X890259Y256240D03*
X906007D03*
X1655999Y385598D03*
X1671747D03*
X1784364Y61037D03*
X1800112D03*
G54D212*
X925102Y1531780D03*
X933290D03*
G54D140*
X386824Y1657204D03*
Y1678070D03*
X401824Y1657204D03*
X396824D03*
X391824D03*
Y1678070D03*
X396824D03*
X401824D03*
X1457757Y1655836D03*
X1452757D03*
Y1676702D03*
X1457757D03*
X1467757Y1655836D03*
X1462757D03*
Y1676702D03*
X1467757D03*
G54D203*
X842470Y407020D03*
Y410760D03*
Y414500D03*
X853100Y410760D03*
Y407020D03*
Y414500D03*
G54D104*
X217124Y576051D03*
Y610051D03*
Y644051D03*
X1636849Y644531D03*
Y678531D03*
Y712531D03*
G54D11*
X14092Y290137D03*
Y298207D03*
X28068Y290137D03*
Y298207D03*
X44692Y290637D03*
Y298707D03*
X58668Y290637D03*
Y298707D03*
X1744422Y151527D03*
Y159597D03*
X1758398Y151527D03*
Y159597D03*
G54D230*
X1037026Y275752D03*
X1023640Y286776D03*
X1795857Y1521592D03*
X1809243Y1510568D03*
G54D113*
X256978Y107835D03*
Y111771D03*
X690134Y111960D03*
Y115896D03*
X993943Y190419D03*
Y192387D03*
Y194356D03*
Y196325D03*
Y198293D03*
Y200261D03*
X1004967D03*
Y198293D03*
Y196325D03*
Y194356D03*
Y192387D03*
X993943Y202230D03*
Y204199D03*
Y206167D03*
X1004967D03*
Y204199D03*
Y202230D03*
X1732099Y108959D03*
Y112895D03*
G54D131*
X333568Y388690D03*
Y394596D03*
Y400628D03*
Y406534D03*
X340654Y394596D03*
Y388690D03*
Y406534D03*
Y400628D03*
X366714Y363438D03*
Y369344D03*
Y375696D03*
Y381602D03*
Y400628D03*
Y406534D03*
X373800Y363438D03*
Y369344D03*
Y375696D03*
Y381602D03*
Y406534D03*
Y400628D03*
G54D20*
X42809Y363429D03*
X39008D03*
X36524Y392288D03*
X54620Y58834D03*
X50308D03*
X59322Y363429D03*
X51114D03*
X56163Y414020D03*
X59833Y1615851D03*
Y1606851D03*
X50333Y1615851D03*
X54333D03*
X47333Y1656851D03*
X53700Y1674717D03*
X63429Y363429D03*
X67681D03*
X69523Y414020D03*
X77588Y656669D03*
X75274Y1546611D03*
X74100Y1615817D03*
X78000D03*
X73833Y1683751D03*
X77833Y1683651D03*
X69833D03*
X86302Y637122D03*
X89461Y660648D03*
X85565Y660656D03*
X93547Y685662D03*
X82311Y709866D03*
X84048Y1571478D03*
X88048D03*
X92251D03*
X81900Y1615817D03*
X85800D03*
X81833Y1683651D03*
X110987Y541732D03*
X97549Y685582D03*
X100931Y702294D03*
X100914Y709264D03*
X107170Y1517259D03*
X96251Y1571478D03*
X104900Y1608917D03*
X124170Y480330D03*
X120060D03*
X115060Y541739D03*
X127377Y541972D03*
X123257Y541902D03*
X119087Y541812D03*
X114021Y663874D03*
X118021D03*
X135006Y490632D03*
X130006D03*
X141103Y480330D03*
X145213D03*
X149568Y1400187D03*
X155098Y1563182D03*
X159107Y1563110D03*
X158118Y1708534D03*
X166631Y1409462D03*
X191267Y699543D03*
X187711Y1400187D03*
X176793Y1579491D03*
X195888Y575488D03*
X199941Y597590D03*
X195888Y609488D03*
X199941Y631590D03*
X195888Y643488D03*
X193461Y666660D03*
X195467Y699543D03*
X204174Y1408762D03*
X200720Y1710379D03*
X222907Y318773D03*
X247487Y104777D03*
X243487D03*
X254297Y124060D03*
X250297D03*
X246297D03*
X242297D03*
X254756Y156819D03*
X271797Y124060D03*
X261297D03*
X268297Y127560D03*
X259933Y143819D03*
X260100Y153979D03*
X263240Y239299D03*
X289357Y116020D03*
X277240Y239299D03*
X303573Y1358370D03*
X313995Y232266D03*
X306956Y559884D03*
X320614Y1366708D03*
X325617Y81260D03*
X332700Y138879D03*
X328700D03*
X338249Y224026D03*
X328965Y231756D03*
X332465D03*
X324106Y599390D03*
X328106D03*
X335673Y1336070D03*
X339811Y123194D03*
X342285Y210626D03*
X346203Y210644D03*
X346249Y224026D03*
X342249D03*
X352742Y1343910D03*
X367807Y1322109D03*
X386004Y1329935D03*
X385123Y1643266D03*
X378547Y1643272D03*
X374391Y1650968D03*
X374509Y1682676D03*
X399935Y1322109D03*
X391563Y1642736D03*
X414595Y944490D03*
X418595D03*
X410795D03*
X414616Y936165D03*
X414626Y959273D03*
X410826D03*
X418626D03*
X418671Y973774D03*
X414626D03*
X410871D03*
X410800Y988185D03*
X414600D03*
X418600D03*
X414550Y1002667D03*
X410838D03*
X418550D03*
X418591Y1017127D03*
X410816D03*
X414591D03*
X417104Y1329935D03*
X407125Y1419520D03*
X407557Y1655402D03*
X422395Y944490D03*
X422426Y959273D03*
X422471Y973774D03*
X422400Y988185D03*
X422350Y1002667D03*
X422391Y1017127D03*
X432063Y1322109D03*
X429383Y1597171D03*
X433383D03*
X437840Y122288D03*
X452071Y261006D03*
X445720Y399279D03*
X451720Y408279D03*
X451520Y479354D03*
X442520D03*
X437520D03*
X447520D03*
X448873Y1329935D03*
X446258Y1436148D03*
X449778D03*
X438020Y1564954D03*
X450020D03*
X437990Y1644294D03*
X441990D03*
X468323Y261088D03*
X455720Y408279D03*
X462720Y399279D03*
X466520Y470354D03*
X456520Y479354D03*
X461520D03*
X462704Y944490D03*
X466704Y936165D03*
X462704D03*
X458904D03*
X466704Y944490D03*
X458904D03*
X466704Y959273D03*
X458904D03*
X462704D03*
X466704Y973774D03*
X458904D03*
X462704D03*
X466704Y988185D03*
X462704D03*
X458904D03*
X466704Y1002667D03*
X458904D03*
X462704D03*
X466704Y1017127D03*
X458904D03*
X462704D03*
X464191Y1322109D03*
X468620Y1404479D03*
X459520Y1549454D03*
X456020Y1574954D03*
X464020D03*
X457220Y1586512D03*
X464930Y1651749D03*
X473500Y234879D03*
X475252Y261027D03*
X481500Y293879D03*
X478720Y363379D03*
X482720D03*
X479169Y479213D03*
X474169D03*
X484169D03*
X470504Y936165D03*
Y944490D03*
Y959273D03*
Y973774D03*
Y988185D03*
Y1002667D03*
Y1017127D03*
X481254Y1329927D03*
X477368Y1404487D03*
X472701D03*
X481468D03*
X476281Y1416010D03*
X480252D03*
X499096Y261731D03*
X492936Y261774D03*
X485500Y293879D03*
X494720Y363379D03*
X488169Y479213D03*
X498169D03*
X493169D03*
X496319Y1335535D03*
X485712Y1421994D03*
X517020Y83379D03*
X512220D03*
X515804Y261980D03*
X509496Y262056D03*
X514720Y363379D03*
X510720D03*
X502720D03*
X504040Y378419D03*
X513720Y392879D03*
X509720D03*
X503169Y470213D03*
X513382Y1343910D03*
X525720Y290879D03*
X527720Y363379D03*
X520830Y380899D03*
X529720Y392879D03*
X525720D03*
X528447Y1358333D03*
X535720Y363379D03*
X545510Y1366708D03*
X552720Y164879D03*
X559300Y417274D03*
X552000Y1456879D03*
X569300Y408424D03*
X589330Y88037D03*
X593240D03*
X597220Y88379D03*
X598724Y150388D03*
X593220Y179379D03*
Y187379D03*
X596800Y502049D03*
X614384Y121909D03*
X610104D03*
X602278D03*
X599720Y179379D03*
Y187379D03*
X614095Y275147D03*
X608895D03*
X611609Y320937D03*
X603822Y320887D03*
X622000Y88379D03*
X630951Y121909D03*
X626699D03*
X622592D03*
X627064Y253219D03*
X619496Y320987D03*
X627236Y320968D03*
X647725Y1646211D03*
X643725D03*
X653820Y84279D03*
X655000Y91879D03*
X661865Y508571D03*
X654927Y525197D03*
X659039Y518108D03*
X663187Y1400212D03*
X650225Y1702711D03*
X676643Y108902D03*
X680623D03*
X670220Y498379D03*
X675220D03*
X680220D03*
X675220Y511379D03*
X680250Y1408587D03*
X694453Y128185D03*
X687453D03*
X683453D03*
X688290Y382439D03*
X690220Y511379D03*
X685220D03*
X704000Y76379D03*
X704953Y128185D03*
X700963Y128245D03*
X713220Y380879D03*
X711220Y511379D03*
X705220D03*
X701330Y1400212D03*
X711780Y1617447D03*
X723933Y135505D03*
X727000Y368242D03*
X722500D03*
X718393Y1408587D03*
X725552Y1602610D03*
X719612Y1602700D03*
X722630Y1649987D03*
X726720Y1644457D03*
X735800Y368242D03*
X731400D03*
X745220Y498379D03*
Y524879D03*
X730680Y1644457D03*
X760193Y100745D03*
X758220Y441879D03*
X751220Y524879D03*
X761700Y511979D03*
X759859Y1689112D03*
X765160Y281339D03*
X776000Y363879D03*
X764000D03*
X771960Y363999D03*
X767960D03*
X777220Y445379D03*
X772952Y1584210D03*
X763359Y1723612D03*
X789720Y425379D03*
X787520Y516999D03*
X798400Y363217D03*
X806000D03*
X796546Y413143D03*
X819114Y117715D03*
X827114D03*
X823114D03*
X826614Y147215D03*
X813800Y383117D03*
X818000D03*
X824220Y425379D03*
X816670Y502439D03*
X812810Y516899D03*
X815252Y1585110D03*
X839360Y117599D03*
X831114Y117715D03*
X840220Y184879D03*
Y197879D03*
X836300Y421417D03*
X844935Y90268D03*
X844220Y184879D03*
Y197879D03*
X856190Y187127D03*
X845505Y284508D03*
Y294794D03*
X849000Y438217D03*
X857252Y1585110D03*
X886503Y278804D03*
X891747Y867871D03*
X887897D03*
X881372Y914972D03*
X899252Y1585110D03*
X921757Y964704D03*
X916974D03*
X926823Y964669D03*
X957027Y195914D03*
X947348Y985594D03*
X961137Y195866D03*
X981445Y175600D03*
X977195Y203940D03*
X981789Y360977D03*
X987139Y424473D03*
X1005699Y167360D03*
X996415Y175090D03*
X999915D03*
X1005395Y214440D03*
X991140Y424473D03*
X1009735Y153960D03*
X1015275Y153966D03*
X1016506Y424321D03*
X1012506D03*
X1023220Y182116D03*
X1034835Y296227D03*
X1031025D03*
X1025958Y362681D03*
X1029922Y362686D03*
X1043424Y283015D03*
X1038606Y296227D03*
X1091457Y1641367D03*
X1103457D03*
X1113140Y1670008D03*
X1105457Y1669967D03*
X1122879Y1436516D03*
X1124862Y1617767D03*
X1124762Y1625427D03*
X1139942Y1444891D03*
X1152720Y183379D03*
X1156720D03*
X1161022Y1436516D03*
X1164830Y1657632D03*
X1159930D03*
X1173374Y170148D03*
X1178085Y1444891D03*
X1181930Y1657632D03*
X1175830D03*
X1170930D03*
X1191206Y136066D03*
X1185030Y1627478D03*
X1192500Y1657942D03*
X1197400D03*
X1186830Y1657632D03*
X1197240Y1703422D03*
X1192340D03*
X1211720Y207379D03*
X1207220D03*
X1215720D03*
X1212610Y219169D03*
X1207530Y219069D03*
X1216610Y219169D03*
X1209900Y244090D03*
X1216656D03*
X1203267Y1653002D03*
X1208010Y1703467D03*
X1203110D03*
X1213910Y1703732D03*
X1218810D03*
X1263150Y300033D03*
X1251150D03*
X1281940Y87789D03*
X1267322Y103681D03*
X1274864Y107229D03*
X1267150Y300033D03*
X1279834Y1358606D03*
X1286013Y79416D03*
X1297342Y287924D03*
X1293398D03*
X1290437Y749482D03*
X1296875Y1366944D03*
X1313788Y62317D03*
X1303264Y74807D03*
X1307542Y298334D03*
X1303542D03*
X1311820Y1335535D03*
X1328883Y1343910D03*
X1343948Y1322109D03*
X1362145Y1329935D03*
X1366369Y86587D03*
X1366001Y95612D03*
X1376076Y1322109D03*
X1394736Y944489D03*
X1390736D03*
X1390719Y936155D03*
X1386936Y944489D03*
X1386967Y959272D03*
X1390767D03*
X1394767D03*
X1390812Y973773D03*
X1394812D03*
X1387012D03*
X1394741Y988184D03*
X1390741D03*
X1386941D03*
X1390691Y1002666D03*
X1394691D03*
X1386891D03*
X1394732Y1017126D03*
X1386869D03*
X1390732D03*
X1393245Y1329935D03*
X1382347Y1394120D03*
X1385066Y1419520D03*
X1398536Y944489D03*
X1398567Y959272D03*
X1398612Y973773D03*
X1398541Y988184D03*
X1398491Y1002666D03*
X1398532Y1017126D03*
X1408204Y1322109D03*
X1402680Y1600289D03*
X1425014Y1329935D03*
X1427349Y1436658D03*
X1423519Y1436668D03*
X1422680Y1584917D03*
X1438845Y944489D03*
X1435045D03*
X1438845Y936164D03*
X1442845Y944489D03*
Y936164D03*
X1435045D03*
X1442845Y959272D03*
X1438845D03*
X1435045D03*
X1438845Y973773D03*
X1442845D03*
X1435045D03*
X1442845Y988184D03*
X1438845D03*
X1435045D03*
X1438845Y1002666D03*
X1435045D03*
X1442845D03*
X1438845Y1017126D03*
X1442845D03*
X1435045D03*
X1440332Y1322109D03*
X1444720Y1404479D03*
X1438547Y1640852D03*
X1443617Y1640832D03*
X1455600Y291217D03*
X1447800D03*
X1458300Y364479D03*
X1449777Y364513D03*
X1453777D03*
X1451780Y407439D03*
X1456777Y421088D03*
X1446645Y936164D03*
Y944489D03*
Y959272D03*
Y973773D03*
Y988184D03*
Y1002666D03*
Y1017126D03*
X1457395Y1329927D03*
X1453509Y1404487D03*
X1448842D03*
X1457609D03*
X1452422Y1416010D03*
X1456393D03*
X1454167Y1640932D03*
X1459127D03*
X1448507Y1640842D03*
X1463000Y155879D03*
X1466777Y364513D03*
X1470777D03*
X1472460Y1335535D03*
X1461803Y1422024D03*
X1472565Y1628119D03*
X1463767Y1640932D03*
X1493384Y413805D03*
X1481384D03*
X1489523Y1343910D03*
X1504602Y295274D03*
X1504278Y284972D03*
X1504602Y307273D03*
X1498184Y364215D03*
X1497384Y413805D03*
X1504588Y1358333D03*
X1524654Y54632D03*
X1517263Y193354D03*
X1521828Y299292D03*
X1521651Y1366708D03*
X1528654Y54632D03*
X1537746Y1303435D03*
X1547697Y121295D03*
X1543720Y584379D03*
X1548720D03*
X1557287Y628952D03*
X1563994Y581234D03*
X1567994D03*
X1624353Y1433808D03*
X1644360Y202757D03*
X1648400Y202747D03*
X1652610Y397219D03*
X1647110Y428719D03*
X1649291Y549252D03*
X1649220Y615179D03*
X1653220D03*
X1641416Y1442183D03*
X1661110Y428719D03*
X1664040Y564169D03*
X1672040D03*
X1668040D03*
X1657220Y615179D03*
X1662496Y1433808D03*
X1673872Y428162D03*
X1686154Y428702D03*
X1676040Y564169D03*
X1680040D03*
X1679559Y1442183D03*
X1703932Y226536D03*
X1704624Y428192D03*
X1701124D03*
X1703720Y503879D03*
X1698720D03*
X1702320Y536489D03*
X1695443Y713362D03*
X1718608Y105901D03*
X1717418Y125184D03*
X1721418D03*
X1715044Y407062D03*
X1718931Y407054D03*
X1710408Y420462D03*
X1708977Y465321D03*
X1713977D03*
X1708030Y688269D03*
X1713159Y688292D03*
X1714320Y704779D03*
X1714298Y711632D03*
X1709107Y722302D03*
X1722608Y105901D03*
X1736418Y125184D03*
X1729418D03*
X1725418D03*
X1725500Y377879D03*
X1722500Y368879D03*
X1733780Y393287D03*
X1729810D03*
X1737660D03*
X1730290Y417357D03*
X1734290D03*
X1736611Y490784D03*
X1746918Y125184D03*
X1743418Y128684D03*
X1746366Y283549D03*
X1743170Y405317D03*
X1764478Y117144D03*
X1769230Y304934D03*
X1758563D03*
X1765663D03*
X1762163D03*
X1754963D03*
X1772863D03*
X1778810Y452157D03*
X1790738Y82384D03*
X1819461Y150818D03*
X1813700Y1497304D03*
X1826075Y1504858D03*
X1843166Y238863D03*
G54D105*
X220668Y582055D03*
Y616055D03*
Y650055D03*
G54D150*
X427474Y1412789D03*
X1403615D03*
G54D213*
X929196Y1546760D03*
G54D240*
X1145335Y1605511D03*
Y1608070D03*
Y1610630D03*
Y1613189D03*
X1163839D03*
Y1610630D03*
Y1608070D03*
Y1605511D03*
G54D123*
X306757Y112844D03*
Y124262D03*
X1022484Y146805D03*
Y158223D03*
X1776878Y113968D03*
Y125386D03*
G54D204*
X839035Y512888D03*
Y515447D03*
Y518006D03*
X845483D03*
Y515447D03*
Y512888D03*
G54D141*
X400317Y120793D03*
Y129061D03*
X417443Y120793D03*
Y129061D03*
X842562Y168064D03*
Y176332D03*
X859688Y168064D03*
Y176332D03*
X1049186Y509790D03*
Y518058D03*
X1066312Y509790D03*
Y518058D03*
X1742907Y171733D03*
Y180001D03*
X1760033D03*
Y171733D03*
G54D12*
X14092Y292892D03*
Y295452D03*
X28068D03*
Y292892D03*
X44692Y293392D03*
Y295952D03*
X58668D03*
Y293392D03*
X1744422Y154282D03*
Y156842D03*
X1758398D03*
Y154282D03*
G54D132*
X333568Y391643D03*
Y403581D03*
X340654Y391643D03*
Y403581D03*
X366714Y366391D03*
Y378649D03*
Y403581D03*
X373800Y366391D03*
Y378649D03*
Y403581D03*
G54D114*
X272333Y104291D03*
X270364D03*
X268395D03*
X266427D03*
X264459D03*
X262490D03*
X260521D03*
X258553D03*
Y115315D03*
X260521D03*
X262490D03*
X264459D03*
X266427D03*
X268395D03*
X270364D03*
X272333D03*
X274301Y104291D03*
X695646Y108416D03*
X693677D03*
X691709D03*
Y119440D03*
X693677D03*
X695646D03*
X707457Y108416D03*
X705489D03*
X703520D03*
X701551D03*
X699583D03*
X697615D03*
Y119440D03*
X699583D03*
X701551D03*
X703520D03*
X705489D03*
X997487Y207742D03*
X1001423D03*
X1737611Y105415D03*
X1735642D03*
X1733674D03*
Y116439D03*
X1735642D03*
X1737611D03*
X1749422Y105415D03*
X1747454D03*
X1745485D03*
X1743516D03*
X1741548D03*
X1739580D03*
Y116439D03*
X1741548D03*
X1743516D03*
X1745485D03*
X1747454D03*
G54D231*
X1037026Y286579D03*
G54D21*
X42809Y366396D03*
X39008D03*
X36524Y395255D03*
X54620Y61801D03*
X50308D03*
X59322Y366396D03*
X51114D03*
X56163Y416987D03*
X59833Y1609818D03*
Y1618818D03*
X50333D03*
X54333D03*
X47333Y1659818D03*
X53700Y1677684D03*
X63429Y366396D03*
X67681D03*
X69523Y416987D03*
X77588Y659636D03*
X75274Y1549578D03*
X74100Y1618784D03*
X78000D03*
X73833Y1686718D03*
X77833Y1686618D03*
X69833D03*
X86302Y640089D03*
X89461Y663615D03*
X85565Y663623D03*
X93547Y688629D03*
X82311Y712833D03*
X84048Y1574445D03*
X88048D03*
X92251D03*
X81900Y1618784D03*
X85800D03*
X81833Y1686618D03*
X110987Y544699D03*
X97549Y688549D03*
X100931Y705261D03*
X100914Y712231D03*
X107170Y1520226D03*
X96251Y1574445D03*
X104900Y1611884D03*
X124170Y483297D03*
X120060D03*
X115060Y544706D03*
X127377Y544939D03*
X123257Y544869D03*
X119087Y544779D03*
X114021Y666841D03*
X118021D03*
X135006Y493599D03*
X130006D03*
X141103Y483297D03*
X145213D03*
X149568Y1403154D03*
X155098Y1566149D03*
X159107Y1566077D03*
X158118Y1711501D03*
X166631Y1412429D03*
X191267Y702510D03*
X187711Y1403154D03*
X176793Y1582458D03*
X195888Y578455D03*
X199941Y600557D03*
X195888Y612455D03*
X199941Y634557D03*
X195888Y646455D03*
X193461Y669627D03*
X195467Y702510D03*
X204174Y1411729D03*
X200720Y1713346D03*
X222907Y321740D03*
X247487Y107744D03*
X243487D03*
X254297Y127027D03*
X250297D03*
X246297D03*
X242297D03*
X254756Y159786D03*
X271797Y127027D03*
X261297D03*
X268297Y130527D03*
X259933Y146786D03*
X260100Y156946D03*
X263240Y242266D03*
X289357Y118987D03*
X277240Y242266D03*
X303573Y1361337D03*
X313995Y235233D03*
X306956Y562851D03*
X320614Y1369675D03*
X325617Y84227D03*
X332700Y141846D03*
X328700D03*
X338249Y226993D03*
X328965Y234723D03*
X332465D03*
X324106Y602357D03*
X328106D03*
X335673Y1339037D03*
X339811Y126161D03*
X342285Y213593D03*
X346203Y213611D03*
X346249Y226993D03*
X342249D03*
X352742Y1346877D03*
X367807Y1325076D03*
X386004Y1332902D03*
X385123Y1646233D03*
X378547Y1646239D03*
X374391Y1653935D03*
X374509Y1685643D03*
X399935Y1325076D03*
X391563Y1645703D03*
X414595Y947457D03*
X418595D03*
X410795D03*
X414616Y939132D03*
X414626Y962240D03*
X410826D03*
X418626D03*
X418671Y976741D03*
X414626D03*
X410871D03*
X410800Y991152D03*
X414600D03*
X418600D03*
X414550Y1005634D03*
X410838D03*
X418550D03*
X418591Y1020094D03*
X410816D03*
X414591D03*
X417104Y1332902D03*
X407125Y1422487D03*
X407557Y1658369D03*
X422395Y947457D03*
X422426Y962240D03*
X422471Y976741D03*
X422400Y991152D03*
X422350Y1005634D03*
X422391Y1020094D03*
X432063Y1325076D03*
X429383Y1600138D03*
X433383D03*
X437840Y125255D03*
X452071Y263973D03*
X445720Y402246D03*
X451720Y411246D03*
X451520Y482321D03*
X442520D03*
X437520D03*
X447520D03*
X448873Y1332902D03*
X446258Y1439115D03*
X449778D03*
X438020Y1567921D03*
X450020D03*
X437990Y1647261D03*
X441990D03*
X468323Y264055D03*
X455720Y411246D03*
X462720Y402246D03*
X466520Y473321D03*
X456520Y482321D03*
X461520D03*
X462704Y947457D03*
X466704Y939132D03*
X462704D03*
X458904D03*
X466704Y947457D03*
X458904D03*
X466704Y962240D03*
X458904D03*
X462704D03*
X466704Y976741D03*
X458904D03*
X462704D03*
X466704Y991152D03*
X462704D03*
X458904D03*
X466704Y1005634D03*
X458904D03*
X462704D03*
X466704Y1020094D03*
X458904D03*
X462704D03*
X464191Y1325076D03*
X468620Y1407446D03*
X459520Y1552421D03*
X456020Y1577921D03*
X464020D03*
X457220Y1589479D03*
X464930Y1654716D03*
X473500Y237846D03*
X475252Y263994D03*
X481500Y296846D03*
X478720Y366346D03*
X482720D03*
X479169Y482180D03*
X474169D03*
X484169D03*
X470504Y939132D03*
Y947457D03*
Y962240D03*
Y976741D03*
Y991152D03*
Y1005634D03*
Y1020094D03*
X481254Y1332894D03*
X476281Y1418977D03*
X477368Y1407454D03*
X480252Y1418977D03*
X472701Y1407454D03*
X481468D03*
X499096Y264698D03*
X492936Y264741D03*
X485500Y296846D03*
X494720Y366346D03*
X488169Y482180D03*
X498169D03*
X493169D03*
X496319Y1338502D03*
X485712Y1424961D03*
X517020Y86346D03*
X512220D03*
X515804Y264947D03*
X509496Y265023D03*
X514720Y366346D03*
X510720D03*
X502720D03*
X513720Y395846D03*
X504040Y381386D03*
X509720Y395846D03*
X503169Y473180D03*
X513382Y1346877D03*
X525720Y293846D03*
X527720Y366346D03*
X529720Y395846D03*
X520830Y383866D03*
X525720Y395846D03*
X528447Y1361300D03*
X535720Y366346D03*
X545510Y1369675D03*
X552720Y167846D03*
X559300Y420241D03*
X552000Y1459846D03*
X569300Y411391D03*
X597220Y91346D03*
X589330Y91004D03*
X593240D03*
X598724Y153355D03*
X593220Y182346D03*
Y190346D03*
X596800Y505016D03*
X614384Y124876D03*
X610104D03*
X602278D03*
X599720Y182346D03*
Y190346D03*
X614095Y278114D03*
X608895D03*
X611609Y323904D03*
X603822Y323854D03*
X622000Y91346D03*
X630951Y124876D03*
X626699D03*
X622592D03*
X627064Y256186D03*
X619496Y323954D03*
X627236Y323935D03*
X647725Y1649178D03*
X643725D03*
X653820Y87246D03*
X655000Y94846D03*
X661865Y511538D03*
X659039Y521075D03*
X654927Y528164D03*
X663187Y1403179D03*
X650225Y1705678D03*
X676643Y111869D03*
X680623D03*
X670220Y501346D03*
X675220D03*
X680220D03*
X675220Y514346D03*
X680250Y1411554D03*
X694453Y131152D03*
X687453D03*
X683453D03*
X688290Y385406D03*
X690220Y514346D03*
X685220D03*
X704000Y79346D03*
X704953Y131152D03*
X700963Y131212D03*
X713220Y383846D03*
X711220Y514346D03*
X705220D03*
X701330Y1403179D03*
X711780Y1620414D03*
X723933Y138472D03*
X727000Y371209D03*
X722500D03*
X718393Y1411554D03*
X725552Y1605577D03*
X719612Y1605667D03*
X726720Y1647424D03*
X722630Y1652954D03*
X735800Y371209D03*
X731400D03*
X745220Y501346D03*
Y527846D03*
X730680Y1647424D03*
X760193Y103712D03*
X758220Y444846D03*
X761700Y514946D03*
X751220Y527846D03*
X759859Y1692079D03*
X765160Y284306D03*
X776000Y366846D03*
X764000D03*
X771960Y366966D03*
X767960D03*
X777220Y448346D03*
X772952Y1587177D03*
X763359Y1726579D03*
X789720Y428346D03*
X787520Y519966D03*
X798400Y366184D03*
X806000D03*
X796546Y416110D03*
X819114Y120682D03*
X827114D03*
X823114D03*
X826614Y150182D03*
X813800Y386084D03*
X818000D03*
X824220Y428346D03*
X816670Y505406D03*
X812810Y519866D03*
X815252Y1588077D03*
X839360Y120566D03*
X831114Y120682D03*
X840220Y200846D03*
Y187846D03*
X836300Y424384D03*
X844935Y93235D03*
X844220Y200846D03*
Y187846D03*
X856190Y190094D03*
X845505Y287475D03*
Y297761D03*
X849000Y441184D03*
X857252Y1588077D03*
X886503Y281771D03*
X891747Y870838D03*
X887897D03*
X881372Y917939D03*
X899252Y1588077D03*
X921757Y967671D03*
X916974D03*
X926823Y967636D03*
X957027Y198881D03*
X947348Y988561D03*
X961137Y198833D03*
X981445Y178567D03*
X977195Y206907D03*
X981789Y363944D03*
X987139Y427440D03*
X1005699Y170327D03*
X996415Y178057D03*
X999915D03*
X1005395Y217407D03*
X991140Y427440D03*
X1009735Y156927D03*
X1015275Y156933D03*
X1016506Y427288D03*
X1012506D03*
X1023220Y185083D03*
X1034835Y299194D03*
X1031025D03*
X1025958Y365648D03*
X1029922Y365653D03*
X1043424Y285982D03*
X1038606Y299194D03*
X1091457Y1644334D03*
X1103457D03*
X1113140Y1672975D03*
X1105457Y1672934D03*
X1122879Y1439483D03*
X1124862Y1620734D03*
X1124762Y1628394D03*
X1139942Y1447858D03*
X1152720Y186346D03*
X1156720D03*
X1161022Y1439483D03*
X1164830Y1660599D03*
X1159930D03*
X1173374Y173115D03*
X1178085Y1447858D03*
X1181930Y1660599D03*
X1175830D03*
X1170930D03*
X1191206Y139033D03*
X1185030Y1630445D03*
X1192500Y1660909D03*
X1197400D03*
X1186830Y1660599D03*
X1197240Y1706389D03*
X1192340D03*
X1211720Y210346D03*
X1207220D03*
X1215720D03*
X1212610Y222136D03*
X1207530Y222036D03*
X1216610Y222136D03*
X1209900Y247057D03*
X1216656D03*
X1203267Y1655969D03*
X1208010Y1706434D03*
X1203110D03*
X1213910Y1706699D03*
X1218810D03*
X1263150Y303000D03*
X1251150D03*
X1281940Y90756D03*
X1274864Y110196D03*
X1267322Y106648D03*
X1267150Y303000D03*
X1279834Y1361573D03*
X1286013Y82383D03*
X1297342Y290891D03*
X1293398D03*
X1290437Y752449D03*
X1296875Y1369911D03*
X1313788Y65284D03*
X1303264Y77774D03*
X1307542Y301301D03*
X1303542D03*
X1311820Y1338502D03*
X1328883Y1346877D03*
X1343948Y1325076D03*
X1362145Y1332902D03*
X1366001Y98579D03*
X1366369Y89554D03*
X1376076Y1325076D03*
X1394736Y947456D03*
X1390736D03*
X1390719Y939122D03*
X1386936Y947456D03*
X1386967Y962239D03*
X1390767D03*
X1394767D03*
X1390812Y976740D03*
X1394812D03*
X1387012D03*
X1394741Y991151D03*
X1390741D03*
X1386941D03*
X1390691Y1005633D03*
X1394691D03*
X1386891D03*
X1394732Y1020093D03*
X1386869D03*
X1390732D03*
X1393245Y1332902D03*
X1382347Y1397087D03*
X1385066Y1422487D03*
X1398536Y947456D03*
X1398567Y962239D03*
X1398612Y976740D03*
X1398541Y991151D03*
X1398491Y1005633D03*
X1398532Y1020093D03*
X1408204Y1325076D03*
X1402680Y1603256D03*
X1425014Y1332902D03*
X1427349Y1439625D03*
X1423519Y1439635D03*
X1422680Y1587884D03*
X1438845Y947456D03*
X1435045D03*
X1438845Y939131D03*
X1442845Y947456D03*
Y939131D03*
X1435045D03*
X1442845Y962239D03*
X1438845D03*
X1435045D03*
X1438845Y976740D03*
X1442845D03*
X1435045D03*
X1442845Y991151D03*
X1438845D03*
X1435045D03*
X1438845Y1005633D03*
X1435045D03*
X1442845D03*
X1438845Y1020093D03*
X1442845D03*
X1435045D03*
X1440332Y1325076D03*
X1444720Y1407446D03*
X1438547Y1643819D03*
X1443617Y1643799D03*
X1455600Y294184D03*
X1447800D03*
X1458300Y367446D03*
X1449777Y367480D03*
X1453777D03*
X1451780Y410406D03*
X1456777Y424055D03*
X1446645Y939131D03*
Y947456D03*
Y962239D03*
Y976740D03*
Y991151D03*
Y1005633D03*
Y1020093D03*
X1457395Y1332894D03*
X1453509Y1407454D03*
X1452422Y1418977D03*
X1448842Y1407454D03*
X1457609D03*
X1456393Y1418977D03*
X1454167Y1643899D03*
X1459127D03*
X1448507Y1643809D03*
X1463000Y158846D03*
X1466777Y367480D03*
X1470777D03*
X1472460Y1338502D03*
X1461803Y1424991D03*
X1472565Y1631086D03*
X1463767Y1643899D03*
X1493384Y416772D03*
X1481384D03*
X1489523Y1346877D03*
X1504602Y298241D03*
X1504278Y287939D03*
X1504602Y310240D03*
X1498184Y367182D03*
X1497384Y416772D03*
X1504588Y1361300D03*
X1524654Y57599D03*
X1517263Y196321D03*
X1521828Y302259D03*
X1521651Y1369675D03*
X1528654Y57599D03*
X1537746Y1306402D03*
X1547697Y124262D03*
X1543720Y587346D03*
X1548720D03*
X1557287Y631919D03*
X1563994Y584201D03*
X1567994D03*
X1624353Y1436775D03*
X1644360Y205724D03*
X1648400Y205714D03*
X1652610Y400186D03*
X1647110Y431686D03*
X1649291Y552219D03*
X1649220Y618146D03*
X1653220D03*
X1641416Y1445150D03*
X1661110Y431686D03*
X1664040Y567136D03*
X1672040D03*
X1668040D03*
X1657220Y618146D03*
X1662496Y1436775D03*
X1673872Y431129D03*
X1686154Y431669D03*
X1676040Y567136D03*
X1680040D03*
X1679559Y1445150D03*
X1703932Y229503D03*
X1704624Y431159D03*
X1701124D03*
X1703720Y506846D03*
X1698720D03*
X1702320Y539456D03*
X1695443Y716329D03*
X1718608Y108868D03*
X1717418Y128151D03*
X1721418D03*
X1715044Y410029D03*
X1718931Y410021D03*
X1710408Y423429D03*
X1708977Y468288D03*
X1713977D03*
X1708030Y691236D03*
X1713159Y691259D03*
X1714298Y714599D03*
X1714320Y707746D03*
X1709107Y725269D03*
X1722608Y108868D03*
X1736418Y128151D03*
X1729418D03*
X1725418D03*
X1725500Y380846D03*
X1722500Y371846D03*
X1733780Y396254D03*
X1729810D03*
X1737660D03*
X1730290Y420324D03*
X1734290D03*
X1736611Y493751D03*
X1746918Y128151D03*
X1743418Y131651D03*
X1746366Y286516D03*
X1743170Y408284D03*
X1764478Y120111D03*
X1769230Y307901D03*
X1758563D03*
X1765663D03*
X1762163D03*
X1754963D03*
X1772863D03*
X1778810Y455124D03*
X1790738Y85351D03*
X1819461Y153785D03*
X1813700Y1500271D03*
X1826075Y1507825D03*
X1843166Y241830D03*
G54D222*
X1005878Y291426D03*
Y308748D03*
G54D30*
X62106Y169291D03*
Y177165D03*
Y185039D03*
Y192913D03*
Y200787D03*
Y208661D03*
Y216535D03*
Y224409D03*
Y232283D03*
Y240157D03*
X78838Y169291D03*
Y177165D03*
Y185039D03*
Y192913D03*
Y200787D03*
Y208661D03*
Y216535D03*
Y224409D03*
Y232283D03*
Y240157D03*
G54D250*
X1278150Y135612D03*
G54D214*
X953235Y977250D03*
Y985596D03*
X959535Y977250D03*
Y985596D03*
G54D124*
X303147Y572658D03*
Y575158D03*
Y577658D03*
Y580158D03*
Y582658D03*
Y585158D03*
Y587658D03*
Y590158D03*
X324347Y572658D03*
Y575158D03*
Y577658D03*
Y580158D03*
Y582658D03*
Y585158D03*
Y587658D03*
Y590158D03*
G54D142*
X400317Y123647D03*
Y126207D03*
X417443D03*
Y123647D03*
X842562Y170918D03*
Y173478D03*
X859688D03*
Y170918D03*
X1049186Y512644D03*
Y515204D03*
X1066312D03*
Y512644D03*
X1742907Y174587D03*
Y177147D03*
X1760033D03*
Y174587D03*
G54D31*
X61280Y380803D03*
X59311D03*
X57342D03*
X55374D03*
X53406D03*
X51437D03*
X49468D03*
Y399799D03*
X51437D03*
X53406D03*
X55374D03*
X57342D03*
X59311D03*
X61280D03*
X614707Y139283D03*
X612738D03*
Y158279D03*
X614707D03*
X624550Y139283D03*
X622581D03*
X620612D03*
X618644D03*
X616676D03*
Y158279D03*
X618644D03*
X620612D03*
X622581D03*
X624550D03*
G54D151*
X435262Y55016D03*
Y60016D03*
Y65016D03*
Y70016D03*
X456128Y55016D03*
Y70016D03*
Y65016D03*
Y60016D03*
X1138512Y52926D03*
Y57926D03*
Y62926D03*
Y67926D03*
X1159378Y52926D03*
Y67926D03*
Y62926D03*
Y57926D03*
G54D22*
X45876Y384395D03*
Y386364D03*
Y388333D03*
Y390301D03*
Y392269D03*
Y394238D03*
Y396207D03*
X64872D03*
Y394238D03*
Y392269D03*
Y390301D03*
Y388333D03*
Y386364D03*
Y384395D03*
X609146Y142875D03*
Y144844D03*
Y146813D03*
Y148781D03*
Y150749D03*
Y152718D03*
Y154687D03*
X628142Y152718D03*
Y150749D03*
Y148781D03*
Y146813D03*
Y144844D03*
Y142875D03*
Y154687D03*
G54D160*
X478316Y152187D03*
Y147069D03*
X471316D03*
Y149628D03*
Y152187D03*
G54D106*
X228840Y685948D03*
X255218D03*
X1054629Y281400D03*
X1081007D03*
X1601355Y602634D03*
X1627733D03*
G54D115*
X260128Y109803D03*
X263671D03*
X267214D03*
X270758D03*
X693284Y113928D03*
X696827D03*
X700370D03*
X703914D03*
X1735249Y110927D03*
X1738792D03*
X1742335D03*
X1745879D03*
G54D205*
X837875Y525849D03*
X834922D03*
Y527817D03*
X837875Y529786D03*
Y527817D03*
G54D241*
X1156378Y133866D03*
G54D13*
X25320Y146662D03*
X40600Y1580802D03*
X493180Y647432D03*
X932820Y1310432D03*
X1112670Y541642D03*
X1807990Y1656032D03*
X1835620Y210432D03*
G54D133*
X335928Y859899D03*
Y866307D03*
X337779Y856694D03*
Y863103D03*
X334079Y869511D03*
X335928Y872716D03*
X337779Y869511D03*
X334079Y875920D03*
Y882329D03*
X335928Y879124D03*
X337779Y875920D03*
Y882329D03*
X334079Y888737D03*
Y895146D03*
X335928Y885533D03*
Y891942D03*
Y898350D03*
X337779Y888737D03*
Y895146D03*
Y901555D03*
X334079D03*
Y907963D03*
Y914372D03*
X335928Y904759D03*
Y911167D03*
Y917576D03*
X337779Y907963D03*
Y914372D03*
X334079Y920780D03*
Y927189D03*
Y933598D03*
X335928Y923985D03*
Y930393D03*
X337779Y920780D03*
Y927189D03*
Y933598D03*
X334079Y940006D03*
Y946414D03*
X335928Y936801D03*
Y943210D03*
Y949619D03*
X337779Y940006D03*
Y946414D03*
X334079Y952823D03*
Y959232D03*
X335928Y956027D03*
Y962436D03*
X337779Y952823D03*
Y959232D03*
X334079Y965640D03*
X337779D03*
X334079Y972049D03*
Y978457D03*
X335928Y968845D03*
Y975253D03*
Y981662D03*
X337779Y972049D03*
Y978457D03*
Y984866D03*
X334512Y1007187D03*
Y1013595D03*
X336361Y1003983D03*
Y1010391D03*
X338211Y1000778D03*
Y1007187D03*
Y1013595D03*
X334512Y1020004D03*
X336361Y1016800D03*
Y1023208D03*
X338211Y1020004D03*
X334512Y1026413D03*
X336361Y1029617D03*
X338211Y1026413D03*
X334512Y1032821D03*
Y1039230D03*
Y1045639D03*
X336361Y1036026D03*
Y1042434D03*
X338211Y1032821D03*
Y1039230D03*
Y1045639D03*
X334512Y1052047D03*
X336361Y1048842D03*
X338211Y1052047D03*
X336361Y1055251D03*
Y1061660D03*
X338211Y1058455D03*
X336361Y1068068D03*
Y1074477D03*
X338211Y1064864D03*
Y1071273D03*
Y1077681D03*
X336361Y1080885D03*
Y1087294D03*
Y1093703D03*
X338211Y1084090D03*
Y1090498D03*
X336361Y1100111D03*
Y1106520D03*
Y1112929D03*
X338211Y1096907D03*
Y1103316D03*
Y1109724D03*
X336361Y1119337D03*
Y1125746D03*
X338211Y1116133D03*
Y1122541D03*
Y1128950D03*
X347029Y847081D03*
X348879Y850286D03*
X350728Y847081D03*
X352579Y850286D03*
X354428Y847081D03*
X345179Y850286D03*
X347029Y853490D03*
Y859899D03*
Y866307D03*
X348879Y856694D03*
Y863103D03*
X350728Y853490D03*
Y859899D03*
Y866307D03*
X352579Y856694D03*
Y863103D03*
X354428Y853490D03*
Y859899D03*
Y866307D03*
X339629Y853490D03*
Y859899D03*
Y866307D03*
X341479Y856694D03*
Y863103D03*
X343328Y853490D03*
Y859899D03*
Y866307D03*
X345179Y856694D03*
Y863103D03*
X347029Y872716D03*
X348879Y869511D03*
X350728Y872716D03*
X352579Y869511D03*
X354428Y872716D03*
X339629D03*
X341479Y869511D03*
X343328Y872716D03*
X345179Y869511D03*
X347029Y879124D03*
X348879Y875920D03*
Y882329D03*
X350728Y879124D03*
X352579Y875920D03*
Y882329D03*
X354428Y879124D03*
X339629D03*
X341479Y875920D03*
Y882329D03*
X343328Y879124D03*
X345179Y875920D03*
Y882329D03*
X347029Y885533D03*
Y891942D03*
Y898350D03*
X348879Y888737D03*
Y895146D03*
Y901555D03*
X350728Y885533D03*
Y891942D03*
Y898350D03*
X352579Y888737D03*
Y895146D03*
Y901555D03*
X354428Y885533D03*
Y891942D03*
Y898350D03*
X339629Y885533D03*
Y891942D03*
Y898350D03*
X341479Y888737D03*
Y895146D03*
Y901555D03*
X343328Y885533D03*
Y891942D03*
Y898350D03*
X345179Y888737D03*
Y895146D03*
Y901555D03*
X347029Y904759D03*
Y911167D03*
Y917576D03*
X348879Y907963D03*
Y914372D03*
X350728Y904759D03*
Y911167D03*
Y917576D03*
X352579Y907963D03*
Y914372D03*
X354428Y904759D03*
Y911167D03*
Y917576D03*
X339629Y904759D03*
Y911167D03*
Y917576D03*
X341479Y907963D03*
Y914372D03*
X343328Y904759D03*
Y911167D03*
Y917576D03*
X345179Y907963D03*
Y914372D03*
X347029Y923985D03*
Y930393D03*
X348879Y920780D03*
Y927189D03*
Y933598D03*
X350728Y923985D03*
Y930393D03*
X352579Y920780D03*
Y927189D03*
Y933598D03*
X354428Y923985D03*
Y930393D03*
X339629Y923985D03*
Y930393D03*
X341479Y920780D03*
Y927189D03*
Y933598D03*
X343328Y923985D03*
Y930393D03*
X345179Y920780D03*
Y927189D03*
Y933598D03*
X347029Y936801D03*
Y943210D03*
Y949619D03*
X348879Y940006D03*
Y946414D03*
X350728Y936801D03*
Y943210D03*
Y949619D03*
X352579Y940006D03*
Y946414D03*
X354428Y936801D03*
Y943210D03*
Y949619D03*
X339629Y936801D03*
Y943210D03*
Y949619D03*
X341479Y940006D03*
Y946414D03*
X343328Y936801D03*
Y943210D03*
Y949619D03*
X345179Y940006D03*
Y946414D03*
X347029Y956027D03*
Y962436D03*
X348879Y952823D03*
Y959232D03*
X350728Y956027D03*
Y962436D03*
X352579Y952823D03*
Y959232D03*
X354428Y956027D03*
Y962436D03*
X339629Y956027D03*
Y962436D03*
X341479Y952823D03*
Y959232D03*
X343328Y956027D03*
Y962436D03*
X345179Y952823D03*
Y959232D03*
X348879Y965640D03*
X352579D03*
X341479D03*
X345179D03*
X347029Y968845D03*
Y975253D03*
Y981662D03*
X348879Y972049D03*
Y978457D03*
X350728Y968845D03*
Y975253D03*
Y981662D03*
X352579Y972049D03*
Y978457D03*
X354428Y968845D03*
Y975253D03*
Y981662D03*
X339629Y968845D03*
Y975253D03*
Y981662D03*
X341479Y972049D03*
Y978457D03*
X343328Y968845D03*
Y975253D03*
Y981662D03*
X345179Y972049D03*
Y978457D03*
X348879Y984866D03*
X352579D03*
X341479D03*
X345179D03*
X347461Y997574D03*
X351161D03*
X354861D03*
X340061D03*
X343761D03*
X347461Y1003983D03*
Y1010391D03*
X349312Y1000778D03*
Y1007187D03*
Y1013595D03*
X351161Y1003983D03*
Y1010391D03*
X353011Y1000778D03*
Y1007187D03*
Y1013595D03*
X354861Y1003983D03*
Y1010391D03*
X340061Y1003983D03*
Y1010391D03*
X341912Y1000778D03*
Y1007187D03*
Y1013595D03*
X343761Y1003983D03*
Y1010391D03*
X345611Y1000778D03*
Y1007187D03*
Y1013595D03*
X347461Y1016800D03*
Y1023208D03*
X349312Y1020004D03*
X351161Y1016800D03*
Y1023208D03*
X353011Y1020004D03*
X354861Y1016800D03*
Y1023208D03*
X340061Y1016800D03*
Y1023208D03*
X341912Y1020004D03*
X343761Y1016800D03*
Y1023208D03*
X345611Y1020004D03*
X347461Y1029617D03*
X349312Y1026413D03*
X351161Y1029617D03*
X353011Y1026413D03*
X354861Y1029617D03*
X340061D03*
X341912Y1026413D03*
X343761Y1029617D03*
X345611Y1026413D03*
X347461Y1036026D03*
Y1042434D03*
X349312Y1032821D03*
Y1039230D03*
Y1045639D03*
X351161Y1036026D03*
Y1042434D03*
X353011Y1032821D03*
Y1039230D03*
Y1045639D03*
X354861Y1036026D03*
Y1042434D03*
X340061Y1036026D03*
Y1042434D03*
X341912Y1032821D03*
Y1039230D03*
Y1045639D03*
X343761Y1036026D03*
Y1042434D03*
X345611Y1032821D03*
Y1039230D03*
Y1045639D03*
X347461Y1048842D03*
X349312Y1052047D03*
X351161Y1048842D03*
X353011Y1052047D03*
X354861Y1048842D03*
X340061D03*
X341912Y1052047D03*
X343761Y1048842D03*
X345611Y1052047D03*
X347461Y1055251D03*
Y1061660D03*
X349312Y1058455D03*
X351161Y1055251D03*
Y1061660D03*
X353011Y1058455D03*
X354861Y1055251D03*
Y1061660D03*
X340061Y1055251D03*
Y1061660D03*
X341912Y1058455D03*
X343761Y1055251D03*
Y1061660D03*
X345611Y1058455D03*
X347461Y1068068D03*
Y1074477D03*
X349312Y1064864D03*
Y1071273D03*
Y1077681D03*
X351161Y1068068D03*
Y1074477D03*
X353011Y1064864D03*
Y1071273D03*
Y1077681D03*
X354861Y1068068D03*
Y1074477D03*
X340061Y1068068D03*
Y1074477D03*
X341912Y1064864D03*
Y1071273D03*
Y1077681D03*
X343761Y1068068D03*
Y1074477D03*
X345611Y1064864D03*
Y1071273D03*
Y1077681D03*
X347461Y1080885D03*
X351161D03*
X354861D03*
X340061D03*
X343761D03*
X347461Y1087294D03*
Y1093703D03*
X349312Y1084090D03*
Y1090498D03*
X351161Y1087294D03*
Y1093703D03*
X353011Y1084090D03*
Y1090498D03*
X354861Y1087294D03*
Y1093703D03*
X340061Y1087294D03*
Y1093703D03*
X341912Y1084090D03*
Y1090498D03*
X343761Y1087294D03*
Y1093703D03*
X345611Y1084090D03*
Y1090498D03*
X347461Y1100111D03*
Y1106520D03*
Y1112929D03*
X349312Y1096907D03*
Y1103316D03*
Y1109724D03*
X351161Y1100111D03*
Y1106520D03*
Y1112929D03*
X353011Y1096907D03*
Y1103316D03*
Y1109724D03*
X354861Y1100111D03*
Y1106520D03*
Y1112929D03*
X340061Y1100111D03*
Y1106520D03*
Y1112929D03*
X341912Y1096907D03*
Y1103316D03*
Y1109724D03*
X343761Y1100111D03*
Y1106520D03*
Y1112929D03*
X345611Y1096907D03*
Y1103316D03*
Y1109724D03*
X347461Y1119337D03*
Y1125746D03*
X349312Y1116133D03*
Y1122541D03*
Y1128950D03*
X351161Y1119337D03*
Y1125746D03*
X353011Y1116133D03*
Y1122541D03*
Y1128950D03*
X354861Y1119337D03*
Y1125746D03*
X340061Y1119337D03*
Y1125746D03*
X341912Y1116133D03*
Y1122541D03*
Y1128950D03*
X343761Y1119337D03*
Y1125746D03*
X345611Y1116133D03*
Y1122541D03*
Y1128950D03*
X347461Y1132154D03*
X349312Y1135359D03*
X351161Y1132154D03*
X353011Y1135359D03*
X354861Y1132154D03*
X343761D03*
X345611Y1135359D03*
X371079Y843877D03*
X356279D03*
X359979D03*
X363679D03*
X367379D03*
X371079Y850286D03*
X356279D03*
X358128Y847081D03*
X359979Y850286D03*
X361828Y847081D03*
X363679Y850286D03*
X365528Y847081D03*
X367379Y850286D03*
X369228Y847081D03*
X371079Y856694D03*
Y863103D03*
X356279Y856694D03*
Y863103D03*
X358128Y853490D03*
Y859899D03*
Y866307D03*
X359979Y856694D03*
Y863103D03*
X361828Y853490D03*
Y859899D03*
Y866307D03*
X363679Y856694D03*
Y863103D03*
X365528Y853490D03*
Y859899D03*
Y866307D03*
X367379Y856694D03*
Y863103D03*
X369228Y853490D03*
Y859899D03*
Y866307D03*
X371079Y869511D03*
X356279D03*
X358128Y872716D03*
X359979Y869511D03*
X361828Y872716D03*
X363679Y869511D03*
X365528Y872716D03*
X367379Y869511D03*
X369228Y872716D03*
X371079Y875920D03*
Y882329D03*
X356279Y875920D03*
Y882329D03*
X358128Y879124D03*
X359979Y875920D03*
Y882329D03*
X361828Y879124D03*
X363679Y875920D03*
Y882329D03*
X365528Y879124D03*
X367379Y875920D03*
Y882329D03*
X369228Y879124D03*
X371079Y888737D03*
Y895146D03*
Y901555D03*
X356279Y888737D03*
Y895146D03*
Y901555D03*
X358128Y885533D03*
Y891942D03*
Y898350D03*
X359979Y888737D03*
Y895146D03*
Y901555D03*
X361828Y885533D03*
Y891942D03*
Y898350D03*
X363679Y888737D03*
Y895146D03*
Y901555D03*
X365528Y885533D03*
Y891942D03*
Y898350D03*
X367379Y888737D03*
Y895146D03*
Y901555D03*
X369228Y885533D03*
Y891942D03*
Y898350D03*
X371079Y907963D03*
Y914372D03*
X356279Y907963D03*
Y914372D03*
X358128Y904759D03*
Y911167D03*
Y917576D03*
X359979Y907963D03*
Y914372D03*
X361828Y904759D03*
Y911167D03*
Y917576D03*
X363679Y907963D03*
Y914372D03*
X365528Y904759D03*
Y911167D03*
Y917576D03*
X367379Y907963D03*
Y914372D03*
X369228Y904759D03*
Y911167D03*
Y917576D03*
X371079Y920780D03*
Y927189D03*
X356279Y920780D03*
Y927189D03*
Y933598D03*
X358128Y923985D03*
Y930393D03*
X359979Y920780D03*
Y927189D03*
Y933598D03*
X361828Y923985D03*
Y930393D03*
X363679Y920780D03*
Y927189D03*
Y933598D03*
X365528Y923985D03*
Y930393D03*
X367379Y920780D03*
Y927189D03*
Y933598D03*
X369228Y923985D03*
Y930393D03*
X371079Y933598D03*
Y940006D03*
Y946414D03*
X356279Y940006D03*
Y946414D03*
X358128Y936801D03*
Y943210D03*
Y949619D03*
X359979Y940006D03*
Y946414D03*
X361828Y936801D03*
Y943210D03*
Y949619D03*
X363679Y940006D03*
Y946414D03*
X365528Y936801D03*
Y943210D03*
Y949619D03*
X367379Y940006D03*
Y946414D03*
X369228Y936801D03*
Y943210D03*
Y949619D03*
X371079Y952823D03*
Y959232D03*
X356279Y952823D03*
Y959232D03*
X358128Y956027D03*
Y962436D03*
X359979Y952823D03*
Y959232D03*
X361828Y956027D03*
Y962436D03*
X363679Y952823D03*
Y959232D03*
X365528Y956027D03*
Y962436D03*
X367379Y952823D03*
Y959232D03*
X369228Y956027D03*
Y962436D03*
X371079Y965640D03*
X356279D03*
X359979D03*
X363679D03*
X367379D03*
X371079Y972049D03*
Y978457D03*
X356279Y972049D03*
Y978457D03*
X358128Y968845D03*
Y975253D03*
Y981662D03*
X359979Y972049D03*
Y978457D03*
X361828Y968845D03*
Y975253D03*
Y981662D03*
X363679Y972049D03*
Y978457D03*
X365528Y968845D03*
Y975253D03*
Y981662D03*
X367379Y972049D03*
Y978457D03*
X369228Y968845D03*
Y975253D03*
Y981662D03*
X371079Y984866D03*
X356279D03*
X359979D03*
X363679D03*
X367379D03*
X358561Y997574D03*
X362261D03*
X365961D03*
X369661D03*
X356712Y1000778D03*
Y1007187D03*
Y1013595D03*
X358561Y1003983D03*
Y1010391D03*
X360412Y1000778D03*
Y1007187D03*
Y1013595D03*
X362261Y1003983D03*
Y1010391D03*
X364112Y1000778D03*
Y1007187D03*
Y1013595D03*
X365961Y1003983D03*
Y1010391D03*
X367812Y1000778D03*
Y1007187D03*
Y1013595D03*
X369661Y1003983D03*
Y1010391D03*
X356712Y1020004D03*
X358561Y1016800D03*
Y1023208D03*
X360412Y1020004D03*
X362261Y1016800D03*
Y1023208D03*
X364112Y1020004D03*
X365961Y1016800D03*
Y1023208D03*
X367812Y1020004D03*
X369661Y1016800D03*
Y1023208D03*
X356712Y1026413D03*
X358561Y1029617D03*
X360412Y1026413D03*
X362261Y1029617D03*
X364112Y1026413D03*
X365961Y1029617D03*
X367812Y1026413D03*
X369661Y1029617D03*
X356712Y1032821D03*
Y1039230D03*
Y1045639D03*
X358561Y1036026D03*
Y1042434D03*
X360412Y1032821D03*
Y1039230D03*
Y1045639D03*
X362261Y1036026D03*
Y1042434D03*
X364112Y1032821D03*
Y1039230D03*
Y1045639D03*
X365961Y1036026D03*
Y1042434D03*
X367812Y1032821D03*
Y1039230D03*
Y1045639D03*
X369661Y1036026D03*
Y1042434D03*
X356712Y1052047D03*
X358561Y1048842D03*
X360412Y1052047D03*
X362261Y1048842D03*
X364112Y1052047D03*
X365961Y1048842D03*
X367812Y1052047D03*
X369661Y1048842D03*
X356712Y1058455D03*
X358561Y1055251D03*
Y1061660D03*
X360412Y1058455D03*
X362261Y1055251D03*
Y1061660D03*
X364112Y1058455D03*
X365961Y1055251D03*
Y1061660D03*
X367812Y1058455D03*
X369661Y1055251D03*
Y1061660D03*
X356712Y1064864D03*
Y1071273D03*
Y1077681D03*
X358561Y1068068D03*
Y1074477D03*
X360412Y1064864D03*
Y1071273D03*
Y1077681D03*
X362261Y1068068D03*
Y1074477D03*
X364112Y1064864D03*
Y1071273D03*
Y1077681D03*
X365961Y1068068D03*
Y1074477D03*
X367812Y1064864D03*
Y1071273D03*
Y1077681D03*
X369661Y1068068D03*
Y1074477D03*
X358561Y1080885D03*
X362261D03*
X365961D03*
X369661D03*
X356712Y1084090D03*
Y1090498D03*
X358561Y1087294D03*
Y1093703D03*
X360412Y1084090D03*
Y1090498D03*
X362261Y1087294D03*
Y1093703D03*
X364112Y1084090D03*
Y1090498D03*
X365961Y1087294D03*
Y1093703D03*
X367812Y1084090D03*
Y1090498D03*
X369661Y1087294D03*
Y1093703D03*
X356712Y1096907D03*
Y1103316D03*
Y1109724D03*
X358561Y1100111D03*
Y1106520D03*
Y1112929D03*
X360412Y1096907D03*
Y1103316D03*
Y1109724D03*
X362261Y1100111D03*
Y1106520D03*
Y1112929D03*
X364112Y1096907D03*
Y1103316D03*
Y1109724D03*
X365961Y1100111D03*
Y1106520D03*
Y1112929D03*
X367812Y1096907D03*
Y1103316D03*
Y1109724D03*
X369661Y1100111D03*
Y1106520D03*
Y1112929D03*
X356712Y1116133D03*
Y1122541D03*
Y1128950D03*
X358561Y1119337D03*
Y1125746D03*
X360412Y1116133D03*
Y1122541D03*
Y1128950D03*
X362261Y1119337D03*
Y1125746D03*
X364112Y1116133D03*
Y1122541D03*
Y1128950D03*
X365961Y1119337D03*
Y1125746D03*
X367812Y1116133D03*
Y1122541D03*
Y1128950D03*
X369661Y1119337D03*
Y1125746D03*
X356712Y1135359D03*
X358561Y1132154D03*
Y1138563D03*
X360412Y1135359D03*
X362261Y1132154D03*
Y1138563D03*
X364112Y1135359D03*
X365961Y1132154D03*
Y1138563D03*
X367812Y1135359D03*
X369661Y1132154D03*
Y1138563D03*
X378479Y843877D03*
X382179D03*
X385879D03*
X374779D03*
X376628Y847081D03*
X378479Y850286D03*
X380328Y847081D03*
X382179Y850286D03*
X384028Y847081D03*
X385879Y850286D03*
X387728Y847081D03*
X372928D03*
X374779Y850286D03*
X376628Y853490D03*
Y859899D03*
Y866307D03*
X378479Y856694D03*
Y863103D03*
X380328Y853490D03*
Y859899D03*
Y866307D03*
X382179Y856694D03*
Y863103D03*
X384028Y853490D03*
Y859899D03*
Y866307D03*
X385879Y856694D03*
Y863103D03*
X387728Y853490D03*
Y859899D03*
Y866307D03*
X372928Y853490D03*
Y859899D03*
Y866307D03*
X374779Y856694D03*
Y863103D03*
X376628Y872716D03*
X378479Y869511D03*
X380328Y872716D03*
X382179Y869511D03*
X384028Y872716D03*
X385879Y869511D03*
X387728Y872716D03*
X372928D03*
X374779Y869511D03*
X376628Y879124D03*
X378479Y875920D03*
Y882329D03*
X380328Y879124D03*
X382179Y875920D03*
Y882329D03*
X384028Y879124D03*
X385879Y875920D03*
Y882329D03*
X387728Y879124D03*
X372928D03*
X374779Y875920D03*
Y882329D03*
X376628Y885533D03*
Y891942D03*
Y898350D03*
X378479Y888737D03*
Y895146D03*
Y901555D03*
X380328Y885533D03*
Y891942D03*
Y898350D03*
X382179Y888737D03*
Y895146D03*
Y901555D03*
X384028Y885533D03*
Y891942D03*
Y898350D03*
X385879Y888737D03*
Y895146D03*
Y901555D03*
X387728Y885533D03*
Y891942D03*
Y898350D03*
X372928Y885533D03*
Y891942D03*
Y898350D03*
X374779Y888737D03*
Y895146D03*
Y901555D03*
X376628Y904759D03*
Y911167D03*
Y917576D03*
X378479Y907963D03*
Y914372D03*
X380328Y904759D03*
Y911167D03*
Y917576D03*
X382179Y907963D03*
Y914372D03*
X384028Y904759D03*
Y911167D03*
Y917576D03*
X385879Y907963D03*
Y914372D03*
X387728Y904759D03*
Y911167D03*
Y917576D03*
X372928Y904759D03*
Y911167D03*
Y917576D03*
X374779Y907963D03*
Y914372D03*
X376628Y923985D03*
Y930393D03*
X378479Y920780D03*
Y927189D03*
X380328Y923985D03*
Y930393D03*
X382179Y920780D03*
Y927189D03*
X384028Y923985D03*
Y930393D03*
X385879Y920780D03*
Y927189D03*
X387728Y923985D03*
Y930393D03*
X372928Y923985D03*
Y930393D03*
X374779Y920780D03*
Y927189D03*
X378479Y933598D03*
X382179D03*
X385879D03*
X374779D03*
X376628Y936801D03*
Y943210D03*
Y949619D03*
X378479Y940006D03*
Y946414D03*
X380328Y936801D03*
Y943210D03*
Y949619D03*
X382179Y940006D03*
Y946414D03*
X384028Y936801D03*
Y943210D03*
Y949619D03*
X385879Y940006D03*
Y946414D03*
X387728Y936801D03*
Y943210D03*
Y949619D03*
X372928Y936801D03*
Y943210D03*
Y949619D03*
X374779Y940006D03*
Y946414D03*
X376628Y956027D03*
Y962436D03*
X378479Y952823D03*
Y959232D03*
X380328Y956027D03*
Y962436D03*
X382179Y952823D03*
Y959232D03*
X384028Y956027D03*
Y962436D03*
X385879Y952823D03*
Y959232D03*
X387728Y956027D03*
Y962436D03*
X372928Y956027D03*
Y962436D03*
X374779Y952823D03*
Y959232D03*
X378479Y965640D03*
X382179D03*
X385879D03*
X374779D03*
X376628Y968845D03*
Y975253D03*
Y981662D03*
X378479Y972049D03*
Y978457D03*
X380328Y968845D03*
Y975253D03*
Y981662D03*
X382179Y972049D03*
Y978457D03*
X384028Y968845D03*
Y975253D03*
Y981662D03*
X385879Y972049D03*
Y978457D03*
X387728Y968845D03*
Y975253D03*
Y981662D03*
X372928Y968845D03*
Y975253D03*
Y981662D03*
X374779Y972049D03*
Y978457D03*
X378479Y984866D03*
X382179D03*
X385879D03*
X374779D03*
X377061Y997574D03*
X380761D03*
X384461D03*
X373361D03*
X377061Y1003983D03*
Y1010391D03*
X378912Y1000778D03*
Y1007187D03*
Y1013595D03*
X380761Y1003983D03*
Y1010391D03*
X382612Y1000778D03*
Y1007187D03*
Y1013595D03*
X384461Y1003983D03*
Y1010391D03*
X386312Y1000778D03*
Y1007187D03*
Y1013595D03*
X371512Y1000778D03*
Y1007187D03*
Y1013595D03*
X373361Y1003983D03*
Y1010391D03*
X375212Y1000778D03*
Y1007187D03*
Y1013595D03*
X377061Y1016800D03*
X378912Y1020004D03*
X380761Y1016800D03*
X382612Y1020004D03*
X384461Y1016800D03*
X386312Y1020004D03*
X371512D03*
X373361Y1016800D03*
X375212Y1020004D03*
X377061Y1023208D03*
Y1029617D03*
X378912Y1026413D03*
X380761Y1023208D03*
Y1029617D03*
X382612Y1026413D03*
X384461Y1023208D03*
Y1029617D03*
X386312Y1026413D03*
X371512D03*
X373361Y1023208D03*
Y1029617D03*
X375212Y1026413D03*
X377061Y1036026D03*
Y1042434D03*
X378912Y1032821D03*
Y1039230D03*
Y1045639D03*
X380761Y1036026D03*
Y1042434D03*
X382612Y1032821D03*
Y1039230D03*
Y1045639D03*
X384461Y1036026D03*
Y1042434D03*
X386312Y1032821D03*
Y1039230D03*
Y1045639D03*
X371512Y1032821D03*
Y1039230D03*
Y1045639D03*
X373361Y1036026D03*
Y1042434D03*
X375212Y1032821D03*
Y1039230D03*
Y1045639D03*
X377061Y1048842D03*
X378912Y1052047D03*
X380761Y1048842D03*
X382612Y1052047D03*
X384461Y1048842D03*
X386312Y1052047D03*
X371512D03*
X373361Y1048842D03*
X375212Y1052047D03*
X377061Y1055251D03*
Y1061660D03*
X378912Y1058455D03*
X380761Y1055251D03*
Y1061660D03*
X382612Y1058455D03*
X384461Y1055251D03*
Y1061660D03*
X386312Y1058455D03*
X371512D03*
X373361Y1055251D03*
Y1061660D03*
X375212Y1058455D03*
X377061Y1068068D03*
Y1074477D03*
X378912Y1064864D03*
Y1071273D03*
Y1077681D03*
X380761Y1068068D03*
Y1074477D03*
X382612Y1064864D03*
Y1071273D03*
Y1077681D03*
X384461Y1068068D03*
Y1074477D03*
X386312Y1064864D03*
Y1071273D03*
Y1077681D03*
X371512Y1064864D03*
Y1071273D03*
Y1077681D03*
X373361Y1068068D03*
Y1074477D03*
X375212Y1064864D03*
Y1071273D03*
Y1077681D03*
X377061Y1080885D03*
X380761D03*
X384461D03*
X373361D03*
X377061Y1087294D03*
Y1093703D03*
X378912Y1084090D03*
Y1090498D03*
X380761Y1087294D03*
Y1093703D03*
X382612Y1084090D03*
Y1090498D03*
X384461Y1087294D03*
Y1093703D03*
X386312Y1084090D03*
Y1090498D03*
X371512Y1084090D03*
Y1090498D03*
X373361Y1087294D03*
Y1093703D03*
X375212Y1084090D03*
Y1090498D03*
X377061Y1100111D03*
Y1106520D03*
X378912Y1096907D03*
Y1103316D03*
Y1109724D03*
X380761Y1100111D03*
Y1106520D03*
X382612Y1096907D03*
Y1103316D03*
Y1109724D03*
X384461Y1100111D03*
Y1106520D03*
X386312Y1096907D03*
Y1103316D03*
Y1109724D03*
X371512Y1096907D03*
Y1103316D03*
Y1109724D03*
X373361Y1100111D03*
Y1106520D03*
X375212Y1096907D03*
Y1103316D03*
Y1109724D03*
X377061Y1112929D03*
X380761D03*
X384461D03*
X373361D03*
X377061Y1119337D03*
Y1125746D03*
X378912Y1116133D03*
Y1122541D03*
Y1128950D03*
X380761Y1119337D03*
Y1125746D03*
X382612Y1116133D03*
Y1122541D03*
Y1128950D03*
X384461Y1119337D03*
Y1125746D03*
X386312Y1116133D03*
Y1122541D03*
Y1128950D03*
X371512Y1116133D03*
Y1122541D03*
Y1128950D03*
X373361Y1119337D03*
Y1125746D03*
X375212Y1116133D03*
Y1122541D03*
Y1128950D03*
X377061Y1132154D03*
Y1138563D03*
X378912Y1135359D03*
X380761Y1132154D03*
Y1138563D03*
X382612Y1135359D03*
X384461Y1132154D03*
Y1138563D03*
X386312Y1135359D03*
X371512D03*
X373361Y1132154D03*
Y1138563D03*
X375212Y1135359D03*
X389579Y843877D03*
X393279D03*
X396979D03*
X400679D03*
X389579Y850286D03*
X391428Y847081D03*
X393279Y850286D03*
X395128Y847081D03*
X396979Y850286D03*
X398828Y847081D03*
X400679Y850286D03*
X402528Y847081D03*
X389579Y856694D03*
Y863103D03*
X391428Y853490D03*
Y859899D03*
Y866307D03*
X393279Y856694D03*
Y863103D03*
X395128Y853490D03*
Y859899D03*
Y866307D03*
X396979Y856694D03*
Y863103D03*
X398828Y853490D03*
Y859899D03*
Y866307D03*
X400679Y856694D03*
Y863103D03*
X402528Y853490D03*
Y859899D03*
Y866307D03*
X389579Y869511D03*
X391428Y872716D03*
X393279Y869511D03*
X395128Y872716D03*
X396979Y869511D03*
X398828Y872716D03*
X400679Y869511D03*
X402528Y872716D03*
X389579Y875920D03*
Y882329D03*
X391428Y879124D03*
X393279Y875920D03*
Y882329D03*
X395128Y879124D03*
X396979Y875920D03*
Y882329D03*
X398828Y879124D03*
X400679Y875920D03*
Y882329D03*
X402528Y879124D03*
X389579Y888737D03*
Y895146D03*
Y901555D03*
X391428Y885533D03*
Y891942D03*
Y898350D03*
X393279Y888737D03*
Y895146D03*
Y901555D03*
X395128Y885533D03*
Y891942D03*
Y898350D03*
X396979Y888737D03*
Y895146D03*
Y901555D03*
X398828Y885533D03*
Y891942D03*
Y898350D03*
X400679Y888737D03*
Y895146D03*
Y901555D03*
X402528Y885533D03*
Y891942D03*
Y898350D03*
X389579Y907963D03*
Y914372D03*
X391428Y904759D03*
Y911167D03*
Y917576D03*
X393279Y907963D03*
Y914372D03*
X395128Y904759D03*
Y911167D03*
Y917576D03*
X396979Y907963D03*
Y914372D03*
X398828Y904759D03*
Y911167D03*
Y917576D03*
X400679Y907963D03*
Y914372D03*
X402528Y904759D03*
Y911167D03*
Y917576D03*
X389579Y920780D03*
Y927189D03*
X391428Y923985D03*
Y930393D03*
X393279Y920780D03*
Y927189D03*
X395128Y923985D03*
Y930393D03*
X396979Y920780D03*
Y927189D03*
X398828Y923985D03*
Y930393D03*
X400679Y920780D03*
Y927189D03*
X402528Y923985D03*
Y930393D03*
X389579Y933598D03*
X393279D03*
X396979D03*
X400679D03*
X389579Y940006D03*
Y946414D03*
X391428Y936801D03*
Y943210D03*
Y949619D03*
X393279Y940006D03*
Y946414D03*
X395128Y936801D03*
Y943210D03*
Y949619D03*
X396979Y940006D03*
Y946414D03*
X398828Y936801D03*
Y943210D03*
Y949619D03*
X400679Y940006D03*
Y946414D03*
X402528Y936801D03*
Y943210D03*
Y949619D03*
X389579Y952823D03*
Y959232D03*
X391428Y956027D03*
Y962436D03*
X393279Y952823D03*
Y959232D03*
X395128Y956027D03*
Y962436D03*
X396979Y952823D03*
Y959232D03*
X398828Y956027D03*
Y962436D03*
X400679Y952823D03*
Y959232D03*
X402528Y956027D03*
Y962436D03*
X389579Y965640D03*
X393279D03*
X396979D03*
X400679D03*
X389579Y972049D03*
Y978457D03*
X391428Y968845D03*
Y975253D03*
Y981662D03*
X393279Y972049D03*
Y978457D03*
X395128Y968845D03*
Y975253D03*
Y981662D03*
X396979Y972049D03*
Y978457D03*
X398828Y968845D03*
Y975253D03*
Y981662D03*
X400679Y972049D03*
Y978457D03*
X402528Y968845D03*
Y975253D03*
Y981662D03*
X389579Y984866D03*
X393279D03*
X396979D03*
X400679D03*
X388161Y997574D03*
X391861D03*
X395561D03*
X399261D03*
X402961D03*
X388161Y1003983D03*
Y1010391D03*
X390012Y1000778D03*
Y1007187D03*
Y1013595D03*
X391861Y1003983D03*
Y1010391D03*
X393712Y1000778D03*
Y1007187D03*
Y1013595D03*
X395561Y1003983D03*
Y1010391D03*
X397412Y1000778D03*
Y1007187D03*
Y1013595D03*
X399261Y1003983D03*
Y1010391D03*
X401112Y1000778D03*
Y1007187D03*
Y1013595D03*
X402961Y1003983D03*
Y1010391D03*
X388161Y1016800D03*
X390012Y1020004D03*
X391861Y1016800D03*
X393712Y1020004D03*
X395561Y1016800D03*
X397412Y1020004D03*
X399261Y1016800D03*
X401112Y1020004D03*
X402961Y1016800D03*
X388161Y1023208D03*
Y1029617D03*
X390012Y1026413D03*
X391861Y1023208D03*
Y1029617D03*
X393712Y1026413D03*
X395561Y1023208D03*
Y1029617D03*
X397412Y1026413D03*
X399261Y1023208D03*
Y1029617D03*
X401112Y1026413D03*
X402961Y1023208D03*
Y1029617D03*
X388161Y1036026D03*
Y1042434D03*
X390012Y1032821D03*
Y1039230D03*
Y1045639D03*
X391861Y1036026D03*
Y1042434D03*
X393712Y1032821D03*
Y1039230D03*
Y1045639D03*
X395561Y1036026D03*
Y1042434D03*
X397412Y1032821D03*
Y1039230D03*
Y1045639D03*
X399261Y1036026D03*
Y1042434D03*
X401112Y1032821D03*
Y1039230D03*
Y1045639D03*
X402961Y1036026D03*
Y1042434D03*
X388161Y1048842D03*
X390012Y1052047D03*
X391861Y1048842D03*
X393712Y1052047D03*
X395561Y1048842D03*
X397412Y1052047D03*
X399261Y1048842D03*
X401112Y1052047D03*
X402961Y1048842D03*
X388161Y1055251D03*
Y1061660D03*
X390012Y1058455D03*
X391861Y1055251D03*
Y1061660D03*
X393712Y1058455D03*
X395561Y1055251D03*
Y1061660D03*
X397412Y1058455D03*
X399261Y1055251D03*
Y1061660D03*
X401112Y1058455D03*
X402961Y1055251D03*
Y1061660D03*
X388161Y1068068D03*
Y1074477D03*
X390012Y1064864D03*
Y1071273D03*
Y1077681D03*
X391861Y1068068D03*
Y1074477D03*
X393712Y1064864D03*
Y1071273D03*
Y1077681D03*
X395561Y1068068D03*
Y1074477D03*
X397412Y1064864D03*
Y1071273D03*
Y1077681D03*
X399261Y1068068D03*
Y1074477D03*
X401112Y1064864D03*
Y1071273D03*
Y1077681D03*
X402961Y1068068D03*
Y1074477D03*
X388161Y1080885D03*
X391861D03*
X395561D03*
X399261D03*
X402961D03*
X388161Y1087294D03*
Y1093703D03*
X390012Y1084090D03*
Y1090498D03*
X391861Y1087294D03*
Y1093703D03*
X393712Y1084090D03*
Y1090498D03*
X395561Y1087294D03*
Y1093703D03*
X397412Y1084090D03*
Y1090498D03*
X399261Y1087294D03*
Y1093703D03*
X401112Y1084090D03*
Y1090498D03*
X402961Y1087294D03*
Y1093703D03*
X388161Y1100111D03*
Y1106520D03*
X390012Y1096907D03*
Y1103316D03*
Y1109724D03*
X391861Y1100111D03*
Y1106520D03*
X393712Y1096907D03*
Y1103316D03*
Y1109724D03*
X395561Y1100111D03*
Y1106520D03*
X397412Y1096907D03*
Y1103316D03*
Y1109724D03*
X399261Y1100111D03*
Y1106520D03*
X401112Y1096907D03*
Y1103316D03*
Y1109724D03*
X402961Y1100111D03*
Y1106520D03*
X388161Y1112929D03*
X391861D03*
X395561D03*
X399261D03*
X402961D03*
X388161Y1119337D03*
Y1125746D03*
X390012Y1116133D03*
Y1122541D03*
Y1128950D03*
X391861Y1119337D03*
Y1125746D03*
X393712Y1116133D03*
Y1122541D03*
Y1128950D03*
X395561Y1119337D03*
Y1125746D03*
X397412Y1116133D03*
Y1122541D03*
Y1128950D03*
X399261Y1119337D03*
Y1125746D03*
X401112Y1116133D03*
Y1122541D03*
Y1128950D03*
X402961Y1119337D03*
Y1125746D03*
X388161Y1132154D03*
Y1138563D03*
X390012Y1135359D03*
X391861Y1132154D03*
Y1138563D03*
X393712Y1135359D03*
X395561Y1132154D03*
Y1138563D03*
X397412Y1135359D03*
X399261Y1132154D03*
Y1138563D03*
X401112Y1135359D03*
X402961Y1132154D03*
Y1138563D03*
X408079Y843877D03*
X411779D03*
X415479D03*
X419179D03*
X404379D03*
X406228Y847081D03*
X408079Y850286D03*
X409928Y847081D03*
X411779Y850286D03*
X413628Y847081D03*
X415479Y850286D03*
X417328Y847081D03*
X419179Y850286D03*
X404379D03*
X406228Y853490D03*
Y859899D03*
Y866307D03*
X408079Y856694D03*
Y863103D03*
X409928Y853490D03*
Y859899D03*
Y866307D03*
X411779Y856694D03*
Y863103D03*
X413628Y853490D03*
Y859899D03*
Y866307D03*
X415479Y856694D03*
Y863103D03*
X417328Y853490D03*
Y859899D03*
Y866307D03*
X419179Y856694D03*
Y863103D03*
X404379Y856694D03*
Y863103D03*
X406228Y872716D03*
X408079Y869511D03*
X409928Y872716D03*
X411779Y869511D03*
X413628Y872716D03*
X415479Y869511D03*
X417328Y872716D03*
X419179Y869511D03*
X404379D03*
X406228Y879124D03*
X408079Y875920D03*
Y882329D03*
X409928Y879124D03*
X411779Y875920D03*
Y882329D03*
X413628Y879124D03*
X415479Y875920D03*
Y882329D03*
X417328Y879124D03*
X419179Y875920D03*
Y882329D03*
X404379Y875920D03*
Y882329D03*
X406228Y885533D03*
Y891942D03*
Y898350D03*
X408079Y888737D03*
Y895146D03*
Y901555D03*
X409928Y885533D03*
Y891942D03*
Y898350D03*
X411779Y888737D03*
Y895146D03*
Y901555D03*
X413628Y885533D03*
Y891942D03*
Y898350D03*
X415479Y888737D03*
Y895146D03*
Y901555D03*
X417328Y885533D03*
Y891942D03*
Y898350D03*
X419179Y888737D03*
Y895146D03*
Y901555D03*
X404379Y888737D03*
Y895146D03*
Y901555D03*
X406228Y904759D03*
Y911167D03*
Y917576D03*
X408079Y907963D03*
Y914372D03*
X409928Y904759D03*
Y911167D03*
Y917576D03*
X411779Y907963D03*
Y914372D03*
X413628Y904759D03*
Y911167D03*
Y917576D03*
X415479Y907963D03*
Y914372D03*
X417328Y904759D03*
Y911167D03*
Y917576D03*
X419179Y907963D03*
Y914372D03*
X404379Y907963D03*
Y914372D03*
X406228Y923985D03*
X408079Y920780D03*
X409928Y923985D03*
X411779Y920780D03*
X413628Y923985D03*
X415479Y920780D03*
X417328Y923985D03*
X419179Y920780D03*
X404379D03*
X406661Y1042434D03*
X408512Y1039230D03*
Y1045639D03*
X410361Y1042434D03*
X412212Y1039230D03*
Y1045639D03*
X414061Y1042434D03*
X415912Y1039230D03*
Y1045639D03*
X417761Y1042434D03*
X419612Y1039230D03*
Y1045639D03*
X404812Y1039230D03*
Y1045639D03*
X406661Y1048842D03*
X408512Y1052047D03*
X410361Y1048842D03*
X412212Y1052047D03*
X414061Y1048842D03*
X415912Y1052047D03*
X417761Y1048842D03*
X419612Y1052047D03*
X404812D03*
X406661Y1055251D03*
Y1061660D03*
X408512Y1058455D03*
X410361Y1055251D03*
Y1061660D03*
X412212Y1058455D03*
X414061Y1055251D03*
Y1061660D03*
X415912Y1058455D03*
X417761Y1055251D03*
Y1061660D03*
X419612Y1058455D03*
X404812D03*
X406661Y1068068D03*
Y1074477D03*
X408512Y1064864D03*
Y1071273D03*
Y1077681D03*
X410361Y1068068D03*
Y1074477D03*
X412212Y1064864D03*
Y1071273D03*
Y1077681D03*
X414061Y1068068D03*
Y1074477D03*
X415912Y1064864D03*
Y1071273D03*
Y1077681D03*
X417761Y1068068D03*
Y1074477D03*
X419612Y1064864D03*
Y1071273D03*
Y1077681D03*
X404812Y1064864D03*
Y1071273D03*
Y1077681D03*
X406661Y1080885D03*
X410361D03*
X414061D03*
X417761D03*
X406661Y1087294D03*
Y1093703D03*
X408512Y1084090D03*
Y1090498D03*
X410361Y1087294D03*
Y1093703D03*
X412212Y1084090D03*
Y1090498D03*
X414061Y1087294D03*
Y1093703D03*
X415912Y1084090D03*
Y1090498D03*
X417761Y1087294D03*
Y1093703D03*
X419612Y1084090D03*
Y1090498D03*
X404812Y1084090D03*
Y1090498D03*
X406661Y1100111D03*
Y1106520D03*
X408512Y1096907D03*
Y1103316D03*
Y1109724D03*
X410361Y1100111D03*
Y1106520D03*
X412212Y1096907D03*
Y1103316D03*
Y1109724D03*
X414061Y1100111D03*
Y1106520D03*
X415912Y1096907D03*
Y1103316D03*
Y1109724D03*
X417761Y1100111D03*
Y1106520D03*
X419612Y1096907D03*
Y1103316D03*
Y1109724D03*
X404812Y1096907D03*
Y1103316D03*
Y1109724D03*
X406661Y1112929D03*
X410361D03*
X414061D03*
X417761D03*
X406661Y1119337D03*
Y1125746D03*
X408512Y1116133D03*
Y1122541D03*
Y1128950D03*
X410361Y1119337D03*
Y1125746D03*
X412212Y1116133D03*
Y1122541D03*
Y1128950D03*
X414061Y1119337D03*
Y1125746D03*
X415912Y1116133D03*
Y1122541D03*
Y1128950D03*
X417761Y1119337D03*
Y1125746D03*
X419612Y1116133D03*
Y1122541D03*
Y1128950D03*
X404812Y1116133D03*
Y1122541D03*
Y1128950D03*
X406661Y1132154D03*
Y1138563D03*
X408512Y1135359D03*
X410361Y1132154D03*
Y1138563D03*
X412212Y1135359D03*
X414061Y1132154D03*
Y1138563D03*
X415912Y1135359D03*
X417761Y1132154D03*
Y1138563D03*
X419612Y1135359D03*
X404812D03*
X422879Y843877D03*
X426579D03*
X421028Y847081D03*
X422879Y850286D03*
X424728Y847081D03*
X426579Y850286D03*
X428428Y847081D03*
X430279Y850286D03*
X432128Y847081D03*
X433979Y850286D03*
X435829Y847081D03*
X421028Y853490D03*
Y859899D03*
Y866307D03*
X422879Y856694D03*
Y863103D03*
X424728Y853490D03*
Y859899D03*
Y866307D03*
X426579Y856694D03*
Y863103D03*
X428428Y853490D03*
Y859899D03*
Y866307D03*
X430279Y856694D03*
Y863103D03*
X432128Y853490D03*
Y859899D03*
Y866307D03*
X433979Y856694D03*
Y863103D03*
X435829Y853490D03*
Y859899D03*
Y866307D03*
X421028Y872716D03*
X422879Y869511D03*
X424728Y872716D03*
X426579Y869511D03*
X428428Y872716D03*
X430279Y869511D03*
X432128Y872716D03*
X433979Y869511D03*
X435829Y872716D03*
X421028Y879124D03*
X422879Y875920D03*
Y882329D03*
X424728Y879124D03*
X426579Y875920D03*
Y882329D03*
X428428Y879124D03*
X430279Y875920D03*
Y882329D03*
X432128Y879124D03*
X433979Y875920D03*
Y882329D03*
X435829Y879124D03*
X421028Y885533D03*
Y891942D03*
Y898350D03*
X422879Y888737D03*
Y895146D03*
Y901555D03*
X424728Y885533D03*
Y891942D03*
Y898350D03*
X426579Y888737D03*
Y895146D03*
Y901555D03*
X428428Y885533D03*
Y891942D03*
Y898350D03*
X430279Y888737D03*
Y895146D03*
Y901555D03*
X432128Y885533D03*
Y891942D03*
Y898350D03*
X433979Y888737D03*
Y895146D03*
Y901555D03*
X435829Y885533D03*
Y891942D03*
Y898350D03*
Y904759D03*
X421028D03*
Y911167D03*
Y917576D03*
X422879Y907963D03*
Y914372D03*
X424728Y904759D03*
Y911167D03*
Y917576D03*
X426579Y907963D03*
Y914372D03*
X428428Y904759D03*
Y911167D03*
Y917576D03*
X430279Y907963D03*
Y914372D03*
X432128Y904759D03*
Y911167D03*
Y917576D03*
X433979Y907963D03*
Y914372D03*
X435829Y911167D03*
Y917576D03*
X421028Y923985D03*
X422879Y920780D03*
X424728Y923985D03*
X426579Y920780D03*
X428428Y923985D03*
X430279Y920780D03*
Y927189D03*
X432128Y923985D03*
Y930393D03*
X433979Y920780D03*
Y927189D03*
X435829Y923985D03*
Y930393D03*
X430279Y933598D03*
X433979D03*
X430279Y940006D03*
Y946414D03*
X432128Y936801D03*
Y943210D03*
Y949619D03*
X433979Y940006D03*
Y946414D03*
X435829Y936801D03*
Y943210D03*
Y949619D03*
X430279Y952823D03*
Y959232D03*
X432128Y956027D03*
Y962436D03*
X433979Y952823D03*
Y959232D03*
X435829Y956027D03*
Y962436D03*
X430279Y965640D03*
X433979D03*
X430279Y972049D03*
Y978457D03*
X432128Y968845D03*
Y975253D03*
Y981662D03*
X433979Y972049D03*
Y978457D03*
X435829Y968845D03*
Y975253D03*
Y981662D03*
X430279Y984866D03*
X433979D03*
X436261Y997574D03*
X432561D03*
X436261Y1003983D03*
Y1010391D03*
X430711Y1000778D03*
Y1007187D03*
Y1013595D03*
X432561Y1003983D03*
Y1010391D03*
X434412Y1000778D03*
Y1007187D03*
Y1013595D03*
X436261Y1016800D03*
X430711Y1020004D03*
X432561Y1016800D03*
X434412Y1020004D03*
X436261Y1023208D03*
Y1029617D03*
X430711Y1026413D03*
X432561Y1023208D03*
Y1029617D03*
X434412Y1026413D03*
X436261Y1036026D03*
Y1042434D03*
X421461D03*
X423312Y1039230D03*
Y1045639D03*
X425161Y1042434D03*
X427012Y1039230D03*
Y1045639D03*
X428861Y1042434D03*
X430711Y1032821D03*
Y1039230D03*
Y1045639D03*
X432561Y1036026D03*
Y1042434D03*
X434412Y1032821D03*
Y1039230D03*
Y1045639D03*
X436261Y1048842D03*
X421461D03*
X423312Y1052047D03*
X425161Y1048842D03*
X427012Y1052047D03*
X428861Y1048842D03*
X430711Y1052047D03*
X432561Y1048842D03*
X434412Y1052047D03*
X436261Y1055251D03*
Y1061660D03*
X421461Y1055251D03*
Y1061660D03*
X423312Y1058455D03*
X425161Y1055251D03*
Y1061660D03*
X427012Y1058455D03*
X428861Y1055251D03*
Y1061660D03*
X430711Y1058455D03*
X432561Y1055251D03*
Y1061660D03*
X434412Y1058455D03*
X436261Y1068068D03*
Y1074477D03*
X421461Y1068068D03*
Y1074477D03*
X423312Y1064864D03*
Y1071273D03*
Y1077681D03*
X425161Y1068068D03*
Y1074477D03*
X427012Y1064864D03*
Y1071273D03*
Y1077681D03*
X428861Y1068068D03*
Y1074477D03*
X430711Y1064864D03*
Y1071273D03*
Y1077681D03*
X432561Y1068068D03*
Y1074477D03*
X434412Y1064864D03*
Y1071273D03*
Y1077681D03*
X436261Y1080885D03*
X421461D03*
X425161D03*
X428861D03*
X432561D03*
X436261Y1087294D03*
Y1093703D03*
X421461Y1087294D03*
Y1093703D03*
X423312Y1084090D03*
Y1090498D03*
X425161Y1087294D03*
Y1093703D03*
X427012Y1084090D03*
Y1090498D03*
X428861Y1087294D03*
Y1093703D03*
X430711Y1084090D03*
Y1090498D03*
X432561Y1087294D03*
Y1093703D03*
X434412Y1084090D03*
Y1090498D03*
X436261Y1100111D03*
Y1106520D03*
X421461Y1100111D03*
Y1106520D03*
X423312Y1096907D03*
Y1103316D03*
Y1109724D03*
X425161Y1100111D03*
Y1106520D03*
X427012Y1096907D03*
Y1103316D03*
Y1109724D03*
X428861Y1100111D03*
Y1106520D03*
X430711Y1096907D03*
Y1103316D03*
Y1109724D03*
X432561Y1100111D03*
Y1106520D03*
X434412Y1096907D03*
Y1103316D03*
Y1109724D03*
X436261Y1112929D03*
X421461D03*
X425161D03*
X428861D03*
X432561D03*
X436261Y1119337D03*
Y1125746D03*
X421461Y1119337D03*
Y1125746D03*
X423312Y1116133D03*
Y1122541D03*
Y1128950D03*
X425161Y1119337D03*
Y1125746D03*
X427012Y1116133D03*
Y1122541D03*
Y1128950D03*
X428861Y1119337D03*
Y1125746D03*
X430711Y1116133D03*
Y1122541D03*
Y1128950D03*
X432561Y1119337D03*
Y1125746D03*
X434412Y1116133D03*
Y1122541D03*
Y1128950D03*
X436261Y1132154D03*
X421461D03*
Y1138563D03*
X423312Y1135359D03*
X425161Y1132154D03*
Y1138563D03*
X427012Y1135359D03*
X428861Y1132154D03*
Y1138563D03*
X430711Y1135359D03*
X432561Y1132154D03*
X434412Y1135359D03*
X452479Y843877D03*
X437679Y850286D03*
X439528Y847081D03*
X441379Y850286D03*
X443228Y847081D03*
X445079Y850286D03*
X446928Y847081D03*
X448779Y850286D03*
X450629Y847081D03*
X452479Y850286D03*
X437679Y856694D03*
Y863103D03*
X439528Y853490D03*
Y859899D03*
Y866307D03*
X441379Y856694D03*
Y863103D03*
X443228Y853490D03*
Y859899D03*
Y866307D03*
X445079Y856694D03*
Y863103D03*
X446928Y853490D03*
Y859899D03*
Y866307D03*
X448779Y856694D03*
Y863103D03*
X450629Y853490D03*
Y859899D03*
Y866307D03*
X452479Y856694D03*
Y863103D03*
X437679Y869511D03*
X439528Y872716D03*
X441379Y869511D03*
X443228Y872716D03*
X445079Y869511D03*
X446928Y872716D03*
X448779Y869511D03*
X450629Y872716D03*
X452479Y869511D03*
X437679Y875920D03*
Y882329D03*
X439528Y879124D03*
X441379Y875920D03*
Y882329D03*
X443228Y879124D03*
X445079Y875920D03*
Y882329D03*
X446928Y879124D03*
X448779Y875920D03*
Y882329D03*
X450629Y879124D03*
X452479Y875920D03*
Y882329D03*
X437679Y888737D03*
Y895146D03*
Y901555D03*
X439528Y885533D03*
Y891942D03*
Y898350D03*
X441379Y888737D03*
Y895146D03*
Y901555D03*
X443228Y885533D03*
Y891942D03*
Y898350D03*
X445079Y888737D03*
Y895146D03*
Y901555D03*
X446928Y885533D03*
Y891942D03*
Y898350D03*
X448779Y888737D03*
Y895146D03*
Y901555D03*
X450629Y885533D03*
Y891942D03*
Y898350D03*
X452479Y888737D03*
Y895146D03*
Y901555D03*
X437679Y907963D03*
Y914372D03*
X439528Y904759D03*
Y911167D03*
Y917576D03*
X441379Y907963D03*
Y914372D03*
X443228Y904759D03*
Y911167D03*
Y917576D03*
X445079Y907963D03*
Y914372D03*
X446928Y904759D03*
Y911167D03*
Y917576D03*
X448779Y907963D03*
Y914372D03*
X450629Y904759D03*
Y911167D03*
Y917576D03*
X452479Y907963D03*
Y914372D03*
X437679Y920780D03*
Y927189D03*
X439528Y923985D03*
Y930393D03*
X441379Y920780D03*
Y927189D03*
X443228Y923985D03*
Y930393D03*
X445079Y920780D03*
Y927189D03*
X446928Y923985D03*
Y930393D03*
X448779Y920780D03*
Y927189D03*
X450629Y923985D03*
Y930393D03*
X452479Y920780D03*
X437679Y933598D03*
X441379D03*
X445079D03*
X448779D03*
X437679Y940006D03*
Y946414D03*
X439528Y936801D03*
Y943210D03*
Y949619D03*
X441379Y940006D03*
Y946414D03*
X443228Y936801D03*
Y943210D03*
Y949619D03*
X445079Y940006D03*
Y946414D03*
X446928Y936801D03*
Y943210D03*
Y949619D03*
X448779Y940006D03*
Y946414D03*
X450629Y936801D03*
Y943210D03*
Y949619D03*
X437679Y952823D03*
Y959232D03*
X439528Y956027D03*
Y962436D03*
X441379Y952823D03*
Y959232D03*
X443228Y956027D03*
Y962436D03*
X445079Y952823D03*
Y959232D03*
X446928Y956027D03*
Y962436D03*
X448779Y952823D03*
Y959232D03*
X450629Y956027D03*
Y962436D03*
X437679Y965640D03*
X441379D03*
X445079D03*
X448779D03*
X437679Y972049D03*
Y978457D03*
X439528Y968845D03*
Y975253D03*
Y981662D03*
X441379Y972049D03*
Y978457D03*
X443228Y968845D03*
Y975253D03*
Y981662D03*
X445079Y972049D03*
Y978457D03*
X446928Y968845D03*
Y975253D03*
Y981662D03*
X448779Y972049D03*
Y978457D03*
X450629Y968845D03*
Y975253D03*
Y981662D03*
X437679Y984866D03*
X441379D03*
X445079D03*
X448779D03*
X439961Y997574D03*
X443661D03*
X447361D03*
X451061D03*
X438112Y1000778D03*
Y1007187D03*
Y1013595D03*
X439961Y1003983D03*
Y1010391D03*
X441812Y1000778D03*
Y1007187D03*
Y1013595D03*
X443661Y1003983D03*
Y1010391D03*
X445511Y1000778D03*
Y1007187D03*
Y1013595D03*
X447361Y1003983D03*
Y1010391D03*
X449212Y1000778D03*
Y1007187D03*
Y1013595D03*
X451061Y1003983D03*
Y1010391D03*
X438112Y1020004D03*
X439961Y1016800D03*
X441812Y1020004D03*
X443661Y1016800D03*
X445511Y1020004D03*
X447361Y1016800D03*
X449212Y1020004D03*
X451061Y1016800D03*
X438112Y1026413D03*
X439961Y1023208D03*
Y1029617D03*
X441812Y1026413D03*
X443661Y1023208D03*
Y1029617D03*
X445511Y1026413D03*
X447361Y1023208D03*
Y1029617D03*
X449212Y1026413D03*
X451061Y1023208D03*
Y1029617D03*
X438112Y1032821D03*
Y1039230D03*
Y1045639D03*
X439961Y1036026D03*
Y1042434D03*
X441812Y1032821D03*
Y1039230D03*
Y1045639D03*
X443661Y1036026D03*
Y1042434D03*
X445511Y1032821D03*
Y1039230D03*
Y1045639D03*
X447361Y1036026D03*
Y1042434D03*
X449212Y1032821D03*
Y1039230D03*
Y1045639D03*
X451061Y1036026D03*
Y1042434D03*
X438112Y1052047D03*
X439961Y1048842D03*
X441812Y1052047D03*
X443661Y1048842D03*
X445511Y1052047D03*
X447361Y1048842D03*
X449212Y1052047D03*
X451061Y1048842D03*
X438112Y1058455D03*
X439961Y1055251D03*
Y1061660D03*
X441812Y1058455D03*
X443661Y1055251D03*
Y1061660D03*
X445511Y1058455D03*
X447361Y1055251D03*
Y1061660D03*
X449212Y1058455D03*
X451061Y1055251D03*
Y1061660D03*
X438112Y1064864D03*
Y1071273D03*
Y1077681D03*
X439961Y1068068D03*
Y1074477D03*
X441812Y1064864D03*
Y1071273D03*
Y1077681D03*
X443661Y1068068D03*
Y1074477D03*
X445511Y1064864D03*
Y1071273D03*
Y1077681D03*
X447361Y1068068D03*
Y1074477D03*
X449212Y1064864D03*
Y1071273D03*
Y1077681D03*
X451061Y1068068D03*
Y1074477D03*
X439961Y1080885D03*
X443661D03*
X447361D03*
X451061D03*
X438112Y1084090D03*
Y1090498D03*
X439961Y1087294D03*
Y1093703D03*
X441812Y1084090D03*
Y1090498D03*
X443661Y1087294D03*
Y1093703D03*
X445511Y1084090D03*
Y1090498D03*
X447361Y1087294D03*
Y1093703D03*
X449212Y1084090D03*
Y1090498D03*
X451061Y1087294D03*
Y1093703D03*
X438112Y1096907D03*
Y1103316D03*
Y1109724D03*
X439961Y1100111D03*
Y1106520D03*
X441812Y1096907D03*
Y1103316D03*
Y1109724D03*
X443661Y1100111D03*
Y1106520D03*
X445511Y1096907D03*
Y1103316D03*
Y1109724D03*
X447361Y1100111D03*
Y1106520D03*
X449212Y1096907D03*
Y1103316D03*
Y1109724D03*
X451061Y1100111D03*
Y1106520D03*
X439961Y1112929D03*
X443661D03*
X447361D03*
X451061D03*
X438112Y1116133D03*
Y1122541D03*
Y1128950D03*
X439961Y1119337D03*
Y1125746D03*
X441812Y1116133D03*
Y1122541D03*
Y1128950D03*
X443661Y1119337D03*
Y1125746D03*
X445511Y1116133D03*
Y1122541D03*
Y1128950D03*
X447361Y1119337D03*
Y1125746D03*
X449212Y1116133D03*
Y1122541D03*
Y1128950D03*
X451061Y1119337D03*
Y1125746D03*
X438112Y1135359D03*
X439961Y1132154D03*
X441812Y1135359D03*
X443661Y1132154D03*
X445511Y1135359D03*
X447361Y1132154D03*
X449212Y1135359D03*
X451061Y1132154D03*
X467279Y843877D03*
X456179D03*
X459879D03*
X463579D03*
X467279Y850286D03*
X454328Y847081D03*
X456179Y850286D03*
X458028Y847081D03*
X459879Y850286D03*
X461728Y847081D03*
X463579Y850286D03*
X465428Y847081D03*
X467279Y856694D03*
Y863103D03*
X454328Y853490D03*
Y859899D03*
Y866307D03*
X456179Y856694D03*
Y863103D03*
X458028Y853490D03*
Y859899D03*
Y866307D03*
X459879Y856694D03*
Y863103D03*
X461728Y853490D03*
Y859899D03*
Y866307D03*
X463579Y856694D03*
Y863103D03*
X465428Y853490D03*
Y859899D03*
Y866307D03*
X467279Y869511D03*
X454328Y872716D03*
X456179Y869511D03*
X458028Y872716D03*
X459879Y869511D03*
X461728Y872716D03*
X463579Y869511D03*
X465428Y872716D03*
X467279Y875920D03*
Y882329D03*
X454328Y879124D03*
X456179Y875920D03*
Y882329D03*
X458028Y879124D03*
X459879Y875920D03*
Y882329D03*
X461728Y879124D03*
X463579Y875920D03*
Y882329D03*
X465428Y879124D03*
X467279Y888737D03*
Y895146D03*
Y901555D03*
X454328Y885533D03*
Y891942D03*
Y898350D03*
X456179Y888737D03*
Y895146D03*
Y901555D03*
X458028Y885533D03*
Y891942D03*
Y898350D03*
X459879Y888737D03*
Y895146D03*
Y901555D03*
X461728Y885533D03*
Y891942D03*
Y898350D03*
X463579Y888737D03*
Y895146D03*
Y901555D03*
X465428Y885533D03*
Y891942D03*
Y898350D03*
X467279Y907963D03*
Y914372D03*
X454328Y904759D03*
Y911167D03*
Y917576D03*
X456179Y907963D03*
Y914372D03*
X458028Y904759D03*
Y911167D03*
Y917576D03*
X459879Y907963D03*
Y914372D03*
X461728Y904759D03*
Y911167D03*
Y917576D03*
X463579Y907963D03*
Y914372D03*
X465428Y904759D03*
Y911167D03*
Y917576D03*
X467279Y920780D03*
X454328Y923985D03*
X456179Y920780D03*
X458028Y923985D03*
X459879Y920780D03*
X461728Y923985D03*
X463579Y920780D03*
X465428Y923985D03*
X467712Y1039230D03*
Y1045639D03*
X452912Y1039230D03*
Y1045639D03*
X454761Y1042434D03*
X456612Y1039230D03*
Y1045639D03*
X458461Y1042434D03*
X460312Y1039230D03*
Y1045639D03*
X462161Y1042434D03*
X464012Y1039230D03*
Y1045639D03*
X465861Y1042434D03*
X467712Y1052047D03*
X452912D03*
X454761Y1048842D03*
X456612Y1052047D03*
X458461Y1048842D03*
X460312Y1052047D03*
X462161Y1048842D03*
X464012Y1052047D03*
X465861Y1048842D03*
Y1055251D03*
X467712Y1058455D03*
X452912D03*
X454761Y1055251D03*
Y1061660D03*
X456612Y1058455D03*
X458461Y1055251D03*
Y1061660D03*
X460312Y1058455D03*
X462161Y1055251D03*
Y1061660D03*
X464012Y1058455D03*
X465861Y1061660D03*
X467712Y1064864D03*
Y1071273D03*
Y1077681D03*
X452912Y1064864D03*
Y1071273D03*
Y1077681D03*
X454761Y1068068D03*
Y1074477D03*
X456612Y1064864D03*
Y1071273D03*
Y1077681D03*
X458461Y1068068D03*
Y1074477D03*
X460312Y1064864D03*
Y1071273D03*
Y1077681D03*
X462161Y1068068D03*
Y1074477D03*
X464012Y1064864D03*
Y1071273D03*
Y1077681D03*
X465861Y1068068D03*
Y1074477D03*
X454761Y1080885D03*
X458461D03*
X462161D03*
X465861D03*
X467712Y1084090D03*
Y1090498D03*
X452912Y1084090D03*
Y1090498D03*
X454761Y1087294D03*
Y1093703D03*
X456612Y1084090D03*
Y1090498D03*
X458461Y1087294D03*
Y1093703D03*
X460312Y1084090D03*
Y1090498D03*
X462161Y1087294D03*
Y1093703D03*
X464012Y1084090D03*
Y1090498D03*
X465861Y1087294D03*
Y1093703D03*
X467712Y1096907D03*
Y1103316D03*
Y1109724D03*
X452912Y1096907D03*
Y1103316D03*
Y1109724D03*
X454761Y1100111D03*
Y1106520D03*
X456612Y1096907D03*
Y1103316D03*
Y1109724D03*
X458461Y1100111D03*
Y1106520D03*
X460312Y1096907D03*
Y1103316D03*
Y1109724D03*
X462161Y1100111D03*
Y1106520D03*
X464012Y1096907D03*
Y1103316D03*
Y1109724D03*
X465861Y1100111D03*
Y1106520D03*
Y1112929D03*
X454761D03*
X458461D03*
X462161D03*
X467712Y1116133D03*
Y1122541D03*
Y1128950D03*
X452912Y1116133D03*
Y1122541D03*
Y1128950D03*
X454761Y1119337D03*
Y1125746D03*
X456612Y1116133D03*
Y1122541D03*
Y1128950D03*
X458461Y1119337D03*
Y1125746D03*
X460312Y1116133D03*
Y1122541D03*
Y1128950D03*
X462161Y1119337D03*
Y1125746D03*
X464012Y1116133D03*
Y1122541D03*
Y1128950D03*
X465861Y1119337D03*
Y1125746D03*
X467712Y1135359D03*
X452912D03*
X454761Y1132154D03*
Y1138563D03*
X456612Y1135359D03*
X458461Y1132154D03*
Y1138563D03*
X460312Y1135359D03*
X462161Y1132154D03*
Y1138563D03*
X464012Y1135359D03*
X465861Y1132154D03*
Y1138563D03*
X470979Y843877D03*
X474679D03*
X478379D03*
X482079D03*
X469128Y847081D03*
X470979Y850286D03*
X472828Y847081D03*
X474679Y850286D03*
X476528Y847081D03*
X478379Y850286D03*
X480228Y847081D03*
X482079Y850286D03*
X483928Y847081D03*
X469128Y853490D03*
Y859899D03*
Y866307D03*
X470979Y856694D03*
Y863103D03*
X472828Y853490D03*
Y859899D03*
Y866307D03*
X474679Y856694D03*
Y863103D03*
X476528Y853490D03*
Y859899D03*
Y866307D03*
X478379Y856694D03*
Y863103D03*
X480228Y853490D03*
Y859899D03*
Y866307D03*
X482079Y856694D03*
Y863103D03*
X483928Y853490D03*
Y859899D03*
Y866307D03*
X469128Y872716D03*
X470979Y869511D03*
X472828Y872716D03*
X474679Y869511D03*
X476528Y872716D03*
X478379Y869511D03*
X480228Y872716D03*
X482079Y869511D03*
X483928Y872716D03*
X469128Y879124D03*
X470979Y875920D03*
Y882329D03*
X472828Y879124D03*
X474679Y875920D03*
Y882329D03*
X476528Y879124D03*
X478379Y875920D03*
Y882329D03*
X480228Y879124D03*
X482079Y875920D03*
Y882329D03*
X483928Y879124D03*
X469128Y885533D03*
Y891942D03*
Y898350D03*
X470979Y888737D03*
Y895146D03*
Y901555D03*
X472828Y885533D03*
Y891942D03*
Y898350D03*
X474679Y888737D03*
Y895146D03*
Y901555D03*
X476528Y885533D03*
Y891942D03*
Y898350D03*
X478379Y888737D03*
Y895146D03*
Y901555D03*
X480228Y885533D03*
Y891942D03*
Y898350D03*
X482079Y888737D03*
Y895146D03*
Y901555D03*
X483928Y885533D03*
Y891942D03*
Y898350D03*
X469128Y904759D03*
Y911167D03*
Y917576D03*
X470979Y907963D03*
Y914372D03*
X472828Y904759D03*
Y911167D03*
Y917576D03*
X474679Y907963D03*
Y914372D03*
X476528Y904759D03*
Y911167D03*
Y917576D03*
X478379Y907963D03*
Y914372D03*
X480228Y904759D03*
Y911167D03*
Y917576D03*
X482079Y907963D03*
Y914372D03*
X483928Y904759D03*
Y911167D03*
Y917576D03*
X469128Y923985D03*
X470979Y920780D03*
X472828Y923985D03*
X474679Y920780D03*
X476528Y923985D03*
X478379Y920780D03*
Y927189D03*
X480228Y923985D03*
Y930393D03*
X482079Y920780D03*
Y927189D03*
X483928Y923985D03*
Y930393D03*
X478379Y933598D03*
X482079D03*
X478379Y940006D03*
Y946414D03*
X480228Y936801D03*
Y943210D03*
Y949619D03*
X482079Y940006D03*
Y946414D03*
X483928Y936801D03*
Y943210D03*
Y949619D03*
X478379Y952823D03*
Y959232D03*
X480228Y956027D03*
Y962436D03*
X482079Y952823D03*
Y959232D03*
X483928Y956027D03*
Y962436D03*
X478379Y965640D03*
X482079D03*
X478379Y972049D03*
Y978457D03*
X480228Y968845D03*
Y975253D03*
Y981662D03*
X482079Y972049D03*
Y978457D03*
X483928Y968845D03*
Y975253D03*
Y981662D03*
X478379Y984866D03*
X482079D03*
X480661Y997574D03*
X484361D03*
X478812Y1000778D03*
Y1007187D03*
Y1013595D03*
X480661Y1003983D03*
Y1010391D03*
X482512Y1000778D03*
Y1007187D03*
Y1013595D03*
X484361Y1003983D03*
Y1010391D03*
X478812Y1020004D03*
X480661Y1016800D03*
X482512Y1020004D03*
X484361Y1016800D03*
X478812Y1026413D03*
X480661Y1023208D03*
Y1029617D03*
X482512Y1026413D03*
X484361Y1023208D03*
Y1029617D03*
X469561Y1042434D03*
X471412Y1039230D03*
Y1045639D03*
X473261Y1042434D03*
X475112Y1039230D03*
Y1045639D03*
X476961Y1042434D03*
X478812Y1032821D03*
Y1039230D03*
Y1045639D03*
X480661Y1036026D03*
Y1042434D03*
X482512Y1032821D03*
Y1039230D03*
Y1045639D03*
X484361Y1036026D03*
Y1042434D03*
X469561Y1048842D03*
X471412Y1052047D03*
X473261Y1048842D03*
X475112Y1052047D03*
X476961Y1048842D03*
X478812Y1052047D03*
X480661Y1048842D03*
X482512Y1052047D03*
X484361Y1048842D03*
X469561Y1055251D03*
Y1061660D03*
X471412Y1058455D03*
X473261Y1055251D03*
Y1061660D03*
X475112Y1058455D03*
X476961Y1055251D03*
Y1061660D03*
X478812Y1058455D03*
X480661Y1055251D03*
Y1061660D03*
X482512Y1058455D03*
X484361Y1055251D03*
Y1061660D03*
X469561Y1068068D03*
Y1074477D03*
X471412Y1064864D03*
Y1071273D03*
Y1077681D03*
X473261Y1068068D03*
Y1074477D03*
X475112Y1064864D03*
Y1071273D03*
Y1077681D03*
X476961Y1068068D03*
Y1074477D03*
X478812Y1064864D03*
Y1071273D03*
Y1077681D03*
X480661Y1068068D03*
Y1074477D03*
X482512Y1064864D03*
Y1071273D03*
Y1077681D03*
X484361Y1068068D03*
Y1074477D03*
X469561Y1080885D03*
X473261D03*
X476961D03*
X480661D03*
X484361D03*
X469561Y1087294D03*
Y1093703D03*
X471412Y1084090D03*
Y1090498D03*
X473261Y1087294D03*
Y1093703D03*
X475112Y1084090D03*
Y1090498D03*
X476961Y1087294D03*
Y1093703D03*
X478812Y1084090D03*
Y1090498D03*
X480661Y1087294D03*
Y1093703D03*
X482512Y1084090D03*
Y1090498D03*
X484361Y1087294D03*
Y1093703D03*
X469561Y1100111D03*
Y1106520D03*
X471412Y1096907D03*
Y1103316D03*
Y1109724D03*
X473261Y1100111D03*
Y1106520D03*
X475112Y1096907D03*
Y1103316D03*
Y1109724D03*
X476961Y1100111D03*
Y1106520D03*
X478812Y1096907D03*
Y1103316D03*
Y1109724D03*
X480661Y1100111D03*
Y1106520D03*
X482512Y1096907D03*
Y1103316D03*
Y1109724D03*
X484361Y1100111D03*
Y1106520D03*
X469561Y1112929D03*
X473261D03*
X476961D03*
X480661D03*
X484361D03*
X469561Y1119337D03*
Y1125746D03*
X471412Y1116133D03*
Y1122541D03*
Y1128950D03*
X473261Y1119337D03*
Y1125746D03*
X475112Y1116133D03*
Y1122541D03*
Y1128950D03*
X476961Y1119337D03*
Y1125746D03*
X478812Y1116133D03*
Y1122541D03*
Y1128950D03*
X480661Y1119337D03*
Y1125746D03*
X482512Y1116133D03*
Y1122541D03*
Y1128950D03*
X484361Y1119337D03*
Y1125746D03*
X469561Y1132154D03*
Y1138563D03*
X471412Y1135359D03*
X473261Y1132154D03*
Y1138563D03*
X475112Y1135359D03*
X476961Y1132154D03*
Y1138563D03*
X478812Y1135359D03*
X480661Y1132154D03*
Y1138563D03*
X482512Y1135359D03*
X484361Y1132154D03*
Y1138563D03*
X496879Y843877D03*
X500579D03*
X485779D03*
X489479D03*
X493179D03*
X496879Y850286D03*
X498728Y847081D03*
X500579Y850286D03*
X485779D03*
X487628Y847081D03*
X489479Y850286D03*
X491328Y847081D03*
X493179Y850286D03*
X495028Y847081D03*
X496879Y856694D03*
Y863103D03*
X498728Y853490D03*
Y859899D03*
Y866307D03*
X500579Y856694D03*
Y863103D03*
X485779Y856694D03*
Y863103D03*
X487628Y853490D03*
Y859899D03*
Y866307D03*
X489479Y856694D03*
Y863103D03*
X491328Y853490D03*
Y859899D03*
Y866307D03*
X493179Y856694D03*
Y863103D03*
X495028Y853490D03*
Y859899D03*
Y866307D03*
X496879Y869511D03*
X498728Y872716D03*
X500579Y869511D03*
X485779D03*
X487628Y872716D03*
X489479Y869511D03*
X491328Y872716D03*
X493179Y869511D03*
X495028Y872716D03*
X496879Y875920D03*
Y882329D03*
X498728Y879124D03*
X500579Y875920D03*
Y882329D03*
X485779Y875920D03*
Y882329D03*
X487628Y879124D03*
X489479Y875920D03*
Y882329D03*
X491328Y879124D03*
X493179Y875920D03*
Y882329D03*
X495028Y879124D03*
X496879Y888737D03*
Y895146D03*
Y901555D03*
X498728Y885533D03*
Y891942D03*
Y898350D03*
X500579Y888737D03*
Y895146D03*
Y901555D03*
X485779Y888737D03*
Y895146D03*
Y901555D03*
X487628Y885533D03*
Y891942D03*
Y898350D03*
X489479Y888737D03*
Y895146D03*
Y901555D03*
X491328Y885533D03*
Y891942D03*
Y898350D03*
X493179Y888737D03*
Y895146D03*
Y901555D03*
X495028Y885533D03*
Y891942D03*
Y898350D03*
X496879Y907963D03*
Y914372D03*
X498728Y904759D03*
Y911167D03*
Y917576D03*
X500579Y907963D03*
Y914372D03*
X485779Y907963D03*
Y914372D03*
X487628Y904759D03*
Y911167D03*
Y917576D03*
X489479Y907963D03*
Y914372D03*
X491328Y904759D03*
Y911167D03*
Y917576D03*
X493179Y907963D03*
Y914372D03*
X495028Y904759D03*
Y911167D03*
Y917576D03*
X496879Y920780D03*
Y927189D03*
X498728Y923985D03*
Y930393D03*
X500579Y920780D03*
Y927189D03*
X485779Y920780D03*
Y927189D03*
X487628Y923985D03*
Y930393D03*
X489479Y920780D03*
Y927189D03*
X491328Y923985D03*
Y930393D03*
X493179Y920780D03*
Y927189D03*
X495028Y923985D03*
Y930393D03*
X496879Y933598D03*
X500579D03*
X485779D03*
X489479D03*
X493179D03*
X496879Y940006D03*
Y946414D03*
X498728Y936801D03*
Y943210D03*
Y949619D03*
X500579Y940006D03*
Y946414D03*
X485779Y940006D03*
Y946414D03*
X487628Y936801D03*
Y943210D03*
Y949619D03*
X489479Y940006D03*
Y946414D03*
X491328Y936801D03*
Y943210D03*
Y949619D03*
X493179Y940006D03*
Y946414D03*
X495028Y936801D03*
Y943210D03*
Y949619D03*
X496879Y952823D03*
Y959232D03*
X498728Y956027D03*
Y962436D03*
X500579Y952823D03*
Y959232D03*
X485779Y952823D03*
Y959232D03*
X487628Y956027D03*
Y962436D03*
X489479Y952823D03*
Y959232D03*
X491328Y956027D03*
Y962436D03*
X493179Y952823D03*
Y959232D03*
X495028Y956027D03*
Y962436D03*
X496879Y965640D03*
X500579D03*
X485779D03*
X489479D03*
X493179D03*
X496879Y972049D03*
Y978457D03*
X498728Y968845D03*
Y975253D03*
Y981662D03*
X500579Y972049D03*
Y978457D03*
X485779Y972049D03*
Y978457D03*
X487628Y968845D03*
Y975253D03*
Y981662D03*
X489479Y972049D03*
Y978457D03*
X491328Y968845D03*
Y975253D03*
Y981662D03*
X493179Y972049D03*
Y978457D03*
X495028Y968845D03*
Y975253D03*
Y981662D03*
X496879Y984866D03*
X500579D03*
X485779D03*
X489479D03*
X493179D03*
X499161Y997574D03*
X488061D03*
X491761D03*
X495461D03*
X497312Y1000778D03*
Y1007187D03*
Y1013595D03*
X499161Y1003983D03*
Y1010391D03*
X501012Y1000778D03*
Y1007187D03*
Y1013595D03*
X486212Y1000778D03*
Y1007187D03*
Y1013595D03*
X488061Y1003983D03*
Y1010391D03*
X489912Y1000778D03*
Y1007187D03*
Y1013595D03*
X491761Y1003983D03*
Y1010391D03*
X493612Y1000778D03*
Y1007187D03*
Y1013595D03*
X495461Y1003983D03*
Y1010391D03*
X497312Y1020004D03*
X499161Y1016800D03*
X501012Y1020004D03*
X486212D03*
X488061Y1016800D03*
X489912Y1020004D03*
X491761Y1016800D03*
X493612Y1020004D03*
X495461Y1016800D03*
X497312Y1026413D03*
X499161Y1023208D03*
Y1029617D03*
X501012Y1026413D03*
X486212D03*
X488061Y1023208D03*
Y1029617D03*
X489912Y1026413D03*
X491761Y1023208D03*
Y1029617D03*
X493612Y1026413D03*
X495461Y1023208D03*
Y1029617D03*
X497312Y1032821D03*
Y1039230D03*
Y1045639D03*
X499161Y1036026D03*
Y1042434D03*
X501012Y1032821D03*
Y1039230D03*
Y1045639D03*
X486212Y1032821D03*
Y1039230D03*
Y1045639D03*
X488061Y1036026D03*
Y1042434D03*
X489912Y1032821D03*
Y1039230D03*
Y1045639D03*
X491761Y1036026D03*
Y1042434D03*
X493612Y1032821D03*
Y1039230D03*
Y1045639D03*
X495461Y1036026D03*
Y1042434D03*
X497312Y1052047D03*
X499161Y1048842D03*
X501012Y1052047D03*
X486212D03*
X488061Y1048842D03*
X489912Y1052047D03*
X491761Y1048842D03*
X493612Y1052047D03*
X495461Y1048842D03*
X497312Y1058455D03*
X499161Y1055251D03*
Y1061660D03*
X501012Y1058455D03*
X486212D03*
X488061Y1055251D03*
Y1061660D03*
X489912Y1058455D03*
X491761Y1055251D03*
Y1061660D03*
X493612Y1058455D03*
X495461Y1055251D03*
Y1061660D03*
X497312Y1064864D03*
Y1071273D03*
Y1077681D03*
X499161Y1068068D03*
Y1074477D03*
X501012Y1064864D03*
Y1071273D03*
Y1077681D03*
X486212Y1064864D03*
Y1071273D03*
Y1077681D03*
X488061Y1068068D03*
Y1074477D03*
X489912Y1064864D03*
Y1071273D03*
Y1077681D03*
X491761Y1068068D03*
Y1074477D03*
X493612Y1064864D03*
Y1071273D03*
Y1077681D03*
X495461Y1068068D03*
Y1074477D03*
X499161Y1080885D03*
X488061D03*
X491761D03*
X495461D03*
X497312Y1084090D03*
Y1090498D03*
X499161Y1087294D03*
Y1093703D03*
X501012Y1084090D03*
Y1090498D03*
X486212Y1084090D03*
Y1090498D03*
X488061Y1087294D03*
Y1093703D03*
X489912Y1084090D03*
Y1090498D03*
X491761Y1087294D03*
Y1093703D03*
X493612Y1084090D03*
Y1090498D03*
X495461Y1087294D03*
Y1093703D03*
X497312Y1096907D03*
Y1103316D03*
Y1109724D03*
X499161Y1100111D03*
Y1106520D03*
X501012Y1096907D03*
Y1103316D03*
Y1109724D03*
X486212Y1096907D03*
Y1103316D03*
Y1109724D03*
X488061Y1100111D03*
Y1106520D03*
X489912Y1096907D03*
Y1103316D03*
Y1109724D03*
X491761Y1100111D03*
Y1106520D03*
X493612Y1096907D03*
Y1103316D03*
Y1109724D03*
X495461Y1100111D03*
Y1106520D03*
X499161Y1112929D03*
X488061D03*
X491761D03*
X495461D03*
X497312Y1116133D03*
Y1122541D03*
Y1128950D03*
X499161Y1119337D03*
Y1125746D03*
X501012Y1116133D03*
Y1122541D03*
Y1128950D03*
X486212Y1116133D03*
Y1122541D03*
Y1128950D03*
X488061Y1119337D03*
Y1125746D03*
X489912Y1116133D03*
Y1122541D03*
Y1128950D03*
X491761Y1119337D03*
Y1125746D03*
X493612Y1116133D03*
Y1122541D03*
Y1128950D03*
X495461Y1119337D03*
Y1125746D03*
X497312Y1135359D03*
X499161Y1132154D03*
Y1138563D03*
X501012Y1135359D03*
X486212D03*
X488061Y1132154D03*
Y1138563D03*
X489912Y1135359D03*
X491761Y1132154D03*
Y1138563D03*
X493612Y1135359D03*
X495461Y1132154D03*
Y1138563D03*
X504279Y843877D03*
X507979D03*
X511679D03*
X515379D03*
X502428Y847081D03*
X504279Y850286D03*
X506128Y847081D03*
X507979Y850286D03*
X509828Y847081D03*
X511679Y850286D03*
X513528Y847081D03*
X515379Y850286D03*
X517228Y847081D03*
X502428Y853490D03*
Y859899D03*
Y866307D03*
X504279Y856694D03*
Y863103D03*
X506128Y853490D03*
Y859899D03*
Y866307D03*
X507979Y856694D03*
Y863103D03*
X509828Y853490D03*
Y859899D03*
Y866307D03*
X511679Y856694D03*
Y863103D03*
X513528Y853490D03*
Y859899D03*
Y866307D03*
X515379Y856694D03*
Y863103D03*
X517228Y853490D03*
Y859899D03*
Y866307D03*
X502428Y872716D03*
X504279Y869511D03*
X506128Y872716D03*
X507979Y869511D03*
X509828Y872716D03*
X511679Y869511D03*
X513528Y872716D03*
X515379Y869511D03*
X517228Y872716D03*
X502428Y879124D03*
X504279Y875920D03*
Y882329D03*
X506128Y879124D03*
X507979Y875920D03*
Y882329D03*
X509828Y879124D03*
X511679Y875920D03*
Y882329D03*
X513528Y879124D03*
X515379Y875920D03*
Y882329D03*
X517228Y879124D03*
X502428Y885533D03*
Y891942D03*
Y898350D03*
X504279Y888737D03*
Y895146D03*
Y901555D03*
X506128Y885533D03*
Y891942D03*
Y898350D03*
X507979Y888737D03*
Y895146D03*
Y901555D03*
X509828Y885533D03*
Y891942D03*
Y898350D03*
X511679Y888737D03*
Y895146D03*
Y901555D03*
X513528Y885533D03*
Y891942D03*
Y898350D03*
X515379Y888737D03*
Y895146D03*
Y901555D03*
X517228Y885533D03*
Y891942D03*
Y898350D03*
X502428Y904759D03*
Y911167D03*
Y917576D03*
X504279Y907963D03*
Y914372D03*
X506128Y904759D03*
Y911167D03*
Y917576D03*
X507979Y907963D03*
Y914372D03*
X509828Y904759D03*
Y911167D03*
Y917576D03*
X511679Y907963D03*
Y914372D03*
X513528Y904759D03*
Y911167D03*
Y917576D03*
X515379Y907963D03*
Y914372D03*
X517228Y904759D03*
Y911167D03*
Y917576D03*
X502428Y923985D03*
Y930393D03*
X504279Y920780D03*
Y927189D03*
X506128Y923985D03*
Y930393D03*
X507979Y920780D03*
Y927189D03*
X509828Y923985D03*
Y930393D03*
X511679Y920780D03*
Y927189D03*
X513528Y923985D03*
Y930393D03*
X515379Y920780D03*
Y927189D03*
X517228Y923985D03*
Y930393D03*
X504279Y933598D03*
X507979D03*
X511679D03*
X515379D03*
X502428Y936801D03*
Y943210D03*
Y949619D03*
X504279Y940006D03*
Y946414D03*
X506128Y936801D03*
Y943210D03*
Y949619D03*
X507979Y940006D03*
Y946414D03*
X509828Y936801D03*
Y943210D03*
Y949619D03*
X511679Y940006D03*
Y946414D03*
X513528Y936801D03*
Y943210D03*
Y949619D03*
X515379Y940006D03*
Y946414D03*
X517228Y936801D03*
Y943210D03*
Y949619D03*
X502428Y956027D03*
Y962436D03*
X504279Y952823D03*
Y959232D03*
X506128Y956027D03*
Y962436D03*
X507979Y952823D03*
Y959232D03*
X509828Y956027D03*
Y962436D03*
X511679Y952823D03*
Y959232D03*
X513528Y956027D03*
Y962436D03*
X515379Y952823D03*
Y959232D03*
X517228Y956027D03*
Y962436D03*
X504279Y965640D03*
X507979D03*
X511679D03*
X515379D03*
X502428Y968845D03*
Y975253D03*
Y981662D03*
X504279Y972049D03*
Y978457D03*
X506128Y968845D03*
Y975253D03*
Y981662D03*
X507979Y972049D03*
Y978457D03*
X509828Y968845D03*
Y975253D03*
Y981662D03*
X511679Y972049D03*
Y978457D03*
X513528Y968845D03*
Y975253D03*
Y981662D03*
X515379Y972049D03*
Y978457D03*
X517228Y968845D03*
Y975253D03*
Y981662D03*
X504279Y984866D03*
X507979D03*
X511679D03*
X515379D03*
X502861Y997574D03*
X506561D03*
X510261D03*
X513961D03*
X517661D03*
X502861Y1003983D03*
Y1010391D03*
X504712Y1000778D03*
Y1007187D03*
Y1013595D03*
X506561Y1003983D03*
Y1010391D03*
X508412Y1000778D03*
Y1007187D03*
Y1013595D03*
X510261Y1003983D03*
Y1010391D03*
X512112Y1000778D03*
Y1007187D03*
Y1013595D03*
X513961Y1003983D03*
Y1010391D03*
X515812Y1000778D03*
Y1007187D03*
Y1013595D03*
X517661Y1003983D03*
Y1010391D03*
X502861Y1016800D03*
X504712Y1020004D03*
X506561Y1016800D03*
X508412Y1020004D03*
X510261Y1016800D03*
X512112Y1020004D03*
X513961Y1016800D03*
X515812Y1020004D03*
X517661Y1016800D03*
X502861Y1023208D03*
Y1029617D03*
X504712Y1026413D03*
X506561Y1023208D03*
Y1029617D03*
X508412Y1026413D03*
X510261Y1023208D03*
Y1029617D03*
X512112Y1026413D03*
X513961Y1023208D03*
Y1029617D03*
X515812Y1026413D03*
X517661Y1023208D03*
Y1029617D03*
X502861Y1036026D03*
Y1042434D03*
X504712Y1032821D03*
Y1039230D03*
Y1045639D03*
X506561Y1036026D03*
Y1042434D03*
X508412Y1032821D03*
Y1039230D03*
Y1045639D03*
X510261Y1036026D03*
Y1042434D03*
X512112Y1032821D03*
Y1039230D03*
Y1045639D03*
X513961Y1036026D03*
Y1042434D03*
X515812Y1032821D03*
Y1039230D03*
Y1045639D03*
X517661Y1036026D03*
Y1042434D03*
X502861Y1048842D03*
X504712Y1052047D03*
X506561Y1048842D03*
X508412Y1052047D03*
X510261Y1048842D03*
X512112Y1052047D03*
X513961Y1048842D03*
X515812Y1052047D03*
X517661Y1048842D03*
X502861Y1055251D03*
Y1061660D03*
X504712Y1058455D03*
X506561Y1055251D03*
Y1061660D03*
X508412Y1058455D03*
X510261Y1055251D03*
Y1061660D03*
X512112Y1058455D03*
X513961Y1055251D03*
Y1061660D03*
X515812Y1058455D03*
X517661Y1055251D03*
Y1061660D03*
X502861Y1068068D03*
Y1074477D03*
X504712Y1064864D03*
Y1071273D03*
Y1077681D03*
X506561Y1068068D03*
Y1074477D03*
X508412Y1064864D03*
Y1071273D03*
Y1077681D03*
X510261Y1068068D03*
Y1074477D03*
X512112Y1064864D03*
Y1071273D03*
Y1077681D03*
X513961Y1068068D03*
Y1074477D03*
X515812Y1064864D03*
Y1071273D03*
Y1077681D03*
X517661Y1068068D03*
Y1074477D03*
X502861Y1080885D03*
X506561D03*
X510261D03*
X513961D03*
X517661D03*
X502861Y1087294D03*
Y1093703D03*
X504712Y1084090D03*
Y1090498D03*
X506561Y1087294D03*
Y1093703D03*
X508412Y1084090D03*
Y1090498D03*
X510261Y1087294D03*
Y1093703D03*
X512112Y1084090D03*
Y1090498D03*
X513961Y1087294D03*
Y1093703D03*
X515812Y1084090D03*
Y1090498D03*
X517661Y1087294D03*
Y1093703D03*
X502861Y1100111D03*
Y1106520D03*
X504712Y1096907D03*
Y1103316D03*
Y1109724D03*
X506561Y1100111D03*
Y1106520D03*
X508412Y1096907D03*
Y1103316D03*
Y1109724D03*
X510261Y1100111D03*
Y1106520D03*
X512112Y1096907D03*
Y1103316D03*
Y1109724D03*
X513961Y1100111D03*
Y1106520D03*
X515812Y1096907D03*
Y1103316D03*
Y1109724D03*
X517661Y1100111D03*
Y1106520D03*
X502861Y1112929D03*
X506561D03*
X510261D03*
X513961D03*
X517661D03*
X502861Y1119337D03*
Y1125746D03*
X504712Y1116133D03*
Y1122541D03*
Y1128950D03*
X506561Y1119337D03*
Y1125746D03*
X508412Y1116133D03*
Y1122541D03*
Y1128950D03*
X510261Y1119337D03*
Y1125746D03*
X512112Y1116133D03*
Y1122541D03*
Y1128950D03*
X513961Y1119337D03*
Y1125746D03*
X515812Y1116133D03*
Y1122541D03*
Y1128950D03*
X517661Y1119337D03*
Y1125746D03*
X502861Y1132154D03*
Y1138563D03*
X504712Y1135359D03*
X506561Y1132154D03*
Y1138563D03*
X508412Y1135359D03*
X510261Y1132154D03*
Y1138563D03*
X512112Y1135359D03*
X513961Y1132154D03*
Y1138563D03*
X515812Y1135359D03*
X517661Y1132154D03*
Y1138563D03*
X519079Y843877D03*
X522779D03*
X526479Y850286D03*
X528329Y847081D03*
X530179Y850286D03*
X532028Y847081D03*
X533879Y850286D03*
X519079D03*
X520928Y847081D03*
X522779Y850286D03*
X524628Y847081D03*
X526479Y856694D03*
Y863103D03*
X528329Y853490D03*
Y859899D03*
Y866307D03*
X530179Y856694D03*
Y863103D03*
X532028Y853490D03*
Y859899D03*
Y866307D03*
X533879Y856694D03*
Y863103D03*
X519079Y856694D03*
Y863103D03*
X520928Y853490D03*
Y859899D03*
Y866307D03*
X522779Y856694D03*
Y863103D03*
X524628Y853490D03*
Y859899D03*
Y866307D03*
X526479Y869511D03*
X528329Y872716D03*
X530179Y869511D03*
X532028Y872716D03*
X533879Y869511D03*
X519079D03*
X520928Y872716D03*
X522779Y869511D03*
X524628Y872716D03*
X526479Y875920D03*
Y882329D03*
X528329Y879124D03*
X530179Y875920D03*
Y882329D03*
X532028Y879124D03*
X533879Y875920D03*
Y882329D03*
X519079Y875920D03*
Y882329D03*
X520928Y879124D03*
X522779Y875920D03*
Y882329D03*
X524628Y879124D03*
X526479Y888737D03*
Y895146D03*
Y901555D03*
X528329Y885533D03*
Y891942D03*
Y898350D03*
X530179Y888737D03*
Y895146D03*
Y901555D03*
X532028Y885533D03*
Y891942D03*
Y898350D03*
X533879Y888737D03*
Y895146D03*
Y901555D03*
X519079Y888737D03*
Y895146D03*
Y901555D03*
X520928Y885533D03*
Y891942D03*
Y898350D03*
X522779Y888737D03*
Y895146D03*
Y901555D03*
X524628Y885533D03*
Y891942D03*
Y898350D03*
X526479Y907963D03*
Y914372D03*
X528329Y904759D03*
Y911167D03*
Y917576D03*
X530179Y907963D03*
Y914372D03*
X532028Y904759D03*
Y911167D03*
Y917576D03*
X533879Y907963D03*
Y914372D03*
X519079Y907963D03*
Y914372D03*
X520928Y904759D03*
Y911167D03*
Y917576D03*
X522779Y907963D03*
Y914372D03*
X524628Y904759D03*
Y911167D03*
Y917576D03*
X526479Y920780D03*
Y927189D03*
X528329Y923985D03*
Y930393D03*
X530179Y920780D03*
Y927189D03*
X532028Y923985D03*
Y930393D03*
X533879Y920780D03*
Y927189D03*
X519079Y920780D03*
Y927189D03*
X520928Y923985D03*
Y930393D03*
X522779Y920780D03*
Y927189D03*
X524628Y923985D03*
Y930393D03*
X526479Y933598D03*
X530179D03*
X533879D03*
X519079D03*
X522779D03*
X526479Y940006D03*
Y946414D03*
X528329Y936801D03*
Y943210D03*
Y949619D03*
X530179Y940006D03*
Y946414D03*
X532028Y936801D03*
Y943210D03*
Y949619D03*
X533879Y940006D03*
Y946414D03*
X519079Y940006D03*
Y946414D03*
X520928Y936801D03*
Y943210D03*
Y949619D03*
X522779Y940006D03*
Y946414D03*
X524628Y936801D03*
Y943210D03*
Y949619D03*
X526479Y952823D03*
Y959232D03*
X528329Y956027D03*
Y962436D03*
X530179Y952823D03*
Y959232D03*
X532028Y956027D03*
Y962436D03*
X533879Y952823D03*
Y959232D03*
X519079Y952823D03*
Y959232D03*
X520928Y956027D03*
Y962436D03*
X522779Y952823D03*
Y959232D03*
X524628Y956027D03*
Y962436D03*
X526479Y965640D03*
X530179D03*
X533879D03*
X519079D03*
X522779D03*
X526479Y972049D03*
Y978457D03*
X528329Y968845D03*
Y975253D03*
Y981662D03*
X530179Y972049D03*
Y978457D03*
X532028Y968845D03*
Y975253D03*
Y981662D03*
X533879Y972049D03*
Y978457D03*
X519079Y972049D03*
Y978457D03*
X520928Y968845D03*
Y975253D03*
Y981662D03*
X522779Y972049D03*
Y978457D03*
X524628Y968845D03*
Y975253D03*
Y981662D03*
X526479Y984866D03*
X530179D03*
X533879D03*
X519079D03*
X522779D03*
X528761Y997574D03*
X532461D03*
X521361D03*
X525061D03*
X526912Y1000778D03*
Y1007187D03*
Y1013595D03*
X528761Y1003983D03*
Y1010391D03*
X530612Y1000778D03*
Y1007187D03*
Y1013595D03*
X532461Y1003983D03*
Y1010391D03*
X519512Y1000778D03*
Y1007187D03*
Y1013595D03*
X521361Y1003983D03*
Y1010391D03*
X523212Y1000778D03*
Y1007187D03*
Y1013595D03*
X525061Y1003983D03*
Y1010391D03*
X526912Y1020004D03*
X528761Y1016800D03*
X530612Y1020004D03*
X532461Y1016800D03*
X519512Y1020004D03*
X521361Y1016800D03*
X523212Y1020004D03*
X525061Y1016800D03*
X526912Y1026413D03*
X528761Y1023208D03*
Y1029617D03*
X530612Y1026413D03*
X532461Y1023208D03*
Y1029617D03*
X519512Y1026413D03*
X521361Y1023208D03*
Y1029617D03*
X523212Y1026413D03*
X525061Y1023208D03*
Y1029617D03*
X526912Y1032821D03*
Y1039230D03*
Y1045639D03*
X528761Y1036026D03*
Y1042434D03*
X530612Y1032821D03*
Y1039230D03*
Y1045639D03*
X532461Y1036026D03*
Y1042434D03*
X519512Y1032821D03*
Y1039230D03*
Y1045639D03*
X521361Y1036026D03*
Y1042434D03*
X523212Y1032821D03*
Y1039230D03*
Y1045639D03*
X525061Y1036026D03*
Y1042434D03*
X526912Y1052047D03*
X528761Y1048842D03*
X530612Y1052047D03*
X532461Y1048842D03*
X519512Y1052047D03*
X521361Y1048842D03*
X523212Y1052047D03*
X525061Y1048842D03*
X526912Y1058455D03*
X528761Y1055251D03*
Y1061660D03*
X530612Y1058455D03*
X532461Y1055251D03*
Y1061660D03*
X519512Y1058455D03*
X521361Y1055251D03*
Y1061660D03*
X523212Y1058455D03*
X525061Y1055251D03*
Y1061660D03*
X526912Y1064864D03*
Y1071273D03*
Y1077681D03*
X528761Y1068068D03*
Y1074477D03*
X530612Y1064864D03*
Y1071273D03*
Y1077681D03*
X532461Y1068068D03*
Y1074477D03*
X519512Y1064864D03*
Y1071273D03*
Y1077681D03*
X521361Y1068068D03*
Y1074477D03*
X523212Y1064864D03*
Y1071273D03*
Y1077681D03*
X525061Y1068068D03*
Y1074477D03*
X528761Y1080885D03*
X532461D03*
X521361D03*
X525061D03*
X526912Y1084090D03*
Y1090498D03*
X528761Y1087294D03*
Y1093703D03*
X530612Y1084090D03*
Y1090498D03*
X532461Y1087294D03*
Y1093703D03*
X519512Y1084090D03*
Y1090498D03*
X521361Y1087294D03*
Y1093703D03*
X523212Y1084090D03*
Y1090498D03*
X525061Y1087294D03*
Y1093703D03*
X526912Y1096907D03*
Y1103316D03*
Y1109724D03*
X528761Y1100111D03*
Y1106520D03*
X530612Y1096907D03*
Y1103316D03*
Y1109724D03*
X532461Y1100111D03*
Y1106520D03*
X519512Y1096907D03*
Y1103316D03*
Y1109724D03*
X521361Y1100111D03*
Y1106520D03*
X523212Y1096907D03*
Y1103316D03*
Y1109724D03*
X525061Y1100111D03*
Y1106520D03*
X528761Y1112929D03*
X532461D03*
X521361D03*
X525061D03*
X526912Y1116133D03*
Y1122541D03*
Y1128950D03*
X528761Y1119337D03*
Y1125746D03*
X530612Y1116133D03*
Y1122541D03*
Y1128950D03*
X532461Y1119337D03*
Y1125746D03*
X534311Y1128950D03*
X519512Y1116133D03*
Y1122541D03*
Y1128950D03*
X521361Y1119337D03*
Y1125746D03*
X523212Y1116133D03*
Y1122541D03*
Y1128950D03*
X525061Y1119337D03*
Y1125746D03*
X526912Y1135359D03*
X528761Y1132154D03*
X530612Y1135359D03*
X532461Y1132154D03*
X534311Y1135359D03*
X519512D03*
X521361Y1132154D03*
Y1138563D03*
X523212Y1135359D03*
X525061Y1132154D03*
Y1138563D03*
X535729Y847081D03*
X537579Y850286D03*
X535729Y853490D03*
Y859899D03*
Y866307D03*
X537579Y856694D03*
Y863103D03*
X539428Y853490D03*
Y859899D03*
Y866307D03*
X541279Y856694D03*
Y863103D03*
X543129Y853490D03*
Y859899D03*
Y866307D03*
X544979Y856694D03*
Y863103D03*
X546828Y866307D03*
X535729Y872716D03*
X537579Y869511D03*
X539428Y872716D03*
X541279Y869511D03*
X543129Y872716D03*
X544979Y869511D03*
X546828Y872716D03*
X535729Y879124D03*
X537579Y875920D03*
Y882329D03*
X539428Y879124D03*
X541279Y875920D03*
Y882329D03*
X543129Y879124D03*
X544979Y875920D03*
Y882329D03*
X546828Y879124D03*
X535729Y885533D03*
Y891942D03*
Y898350D03*
X537579Y888737D03*
Y895146D03*
Y901555D03*
X539428Y885533D03*
Y891942D03*
Y898350D03*
X541279Y888737D03*
Y895146D03*
Y901555D03*
X543129Y885533D03*
Y891942D03*
Y898350D03*
X544979Y888737D03*
Y895146D03*
Y901555D03*
X546828Y885533D03*
Y891942D03*
Y898350D03*
X535729Y904759D03*
Y911167D03*
Y917576D03*
X537579Y907963D03*
Y914372D03*
X539428Y904759D03*
Y911167D03*
Y917576D03*
X541279Y907963D03*
Y914372D03*
X543129Y904759D03*
Y911167D03*
Y917576D03*
X544979Y907963D03*
Y914372D03*
X546828Y904759D03*
Y911167D03*
Y917576D03*
X535729Y923985D03*
Y930393D03*
X537579Y920780D03*
Y927189D03*
X539428Y923985D03*
Y930393D03*
X541279Y920780D03*
Y927189D03*
X543129Y923985D03*
Y930393D03*
X544979Y920780D03*
Y927189D03*
X546828Y923985D03*
Y930393D03*
X537579Y933598D03*
X541279D03*
X544979D03*
X535729Y936801D03*
Y943210D03*
Y949619D03*
X537579Y940006D03*
Y946414D03*
X539428Y936801D03*
Y943210D03*
Y949619D03*
X541279Y940006D03*
Y946414D03*
X543129Y936801D03*
Y943210D03*
Y949619D03*
X544979Y940006D03*
Y946414D03*
X546828Y936801D03*
Y943210D03*
Y949619D03*
X535729Y956027D03*
Y962436D03*
X537579Y952823D03*
Y959232D03*
X539428Y956027D03*
Y962436D03*
X541279Y952823D03*
Y959232D03*
X543129Y956027D03*
Y962436D03*
X544979Y952823D03*
Y959232D03*
X546828Y956027D03*
Y962436D03*
X537579Y965640D03*
X541279D03*
X544979D03*
X535729Y968845D03*
Y975253D03*
Y981662D03*
X537579Y972049D03*
Y978457D03*
X539428Y968845D03*
Y975253D03*
Y981662D03*
X541279Y972049D03*
Y978457D03*
X543129Y968845D03*
Y975253D03*
Y981662D03*
X544979Y972049D03*
Y978457D03*
X546828Y968845D03*
Y975253D03*
X537579Y984866D03*
X541279D03*
X536161Y997574D03*
X539861D03*
X543561D03*
X534311Y1000778D03*
Y1007187D03*
Y1013595D03*
X536161Y1003983D03*
Y1010391D03*
X538012Y1000778D03*
Y1007187D03*
Y1013595D03*
X539861Y1003983D03*
Y1010391D03*
X541711Y1000778D03*
Y1007187D03*
Y1013595D03*
X543561Y1003983D03*
Y1010391D03*
X545412Y1000778D03*
Y1007187D03*
Y1013595D03*
X547261Y1003983D03*
Y1010391D03*
X534311Y1020004D03*
X536161Y1016800D03*
X538012Y1020004D03*
X539861Y1016800D03*
X541711Y1020004D03*
X543561Y1016800D03*
X545412Y1020004D03*
X547261Y1016800D03*
X534311Y1026413D03*
X536161Y1023208D03*
Y1029617D03*
X538012Y1026413D03*
X539861Y1023208D03*
Y1029617D03*
X541711Y1026413D03*
X543561Y1023208D03*
Y1029617D03*
X545412Y1026413D03*
X547261Y1023208D03*
Y1029617D03*
X534311Y1032821D03*
Y1039230D03*
Y1045639D03*
X536161Y1036026D03*
Y1042434D03*
X538012Y1032821D03*
Y1039230D03*
Y1045639D03*
X539861Y1036026D03*
Y1042434D03*
X541711Y1032821D03*
Y1039230D03*
Y1045639D03*
X543561Y1036026D03*
Y1042434D03*
X545412Y1032821D03*
Y1039230D03*
Y1045639D03*
X547261Y1036026D03*
Y1042434D03*
X534311Y1052047D03*
X536161Y1048842D03*
X538012Y1052047D03*
X539861Y1048842D03*
X541711Y1052047D03*
X543561Y1048842D03*
X545412Y1052047D03*
X534311Y1058455D03*
X536161Y1055251D03*
Y1061660D03*
X538012Y1058455D03*
X539861Y1055251D03*
Y1061660D03*
X541711Y1058455D03*
X543561Y1055251D03*
Y1061660D03*
X545412Y1058455D03*
X534311Y1064864D03*
Y1071273D03*
Y1077681D03*
X536161Y1068068D03*
Y1074477D03*
X538012Y1064864D03*
Y1071273D03*
Y1077681D03*
X539861Y1068068D03*
Y1074477D03*
X541711Y1064864D03*
Y1071273D03*
Y1077681D03*
X543561Y1068068D03*
Y1074477D03*
X545412Y1064864D03*
Y1071273D03*
Y1077681D03*
X536161Y1080885D03*
X539861D03*
X543561D03*
X534311Y1084090D03*
Y1090498D03*
X536161Y1087294D03*
Y1093703D03*
X538012Y1084090D03*
Y1090498D03*
X539861Y1087294D03*
Y1093703D03*
X541711Y1084090D03*
Y1090498D03*
X543561Y1087294D03*
Y1093703D03*
X545412Y1084090D03*
Y1090498D03*
X534311Y1096907D03*
Y1103316D03*
Y1109724D03*
X536161Y1100111D03*
Y1106520D03*
X538012Y1096907D03*
Y1103316D03*
Y1109724D03*
X539861Y1100111D03*
Y1106520D03*
X541711Y1096907D03*
Y1103316D03*
Y1109724D03*
X543561Y1100111D03*
Y1106520D03*
X545412Y1096907D03*
Y1103316D03*
Y1109724D03*
X536161Y1112929D03*
X539861D03*
X543561D03*
X534311Y1116133D03*
Y1122541D03*
X536161Y1119337D03*
Y1125746D03*
X538012Y1116133D03*
Y1122541D03*
Y1128950D03*
X539861Y1119337D03*
Y1125746D03*
X541711Y1116133D03*
Y1122541D03*
Y1128950D03*
X543561Y1119337D03*
Y1125746D03*
X545412Y1116133D03*
Y1122541D03*
X536161Y1132154D03*
X1312070Y859899D03*
Y866307D03*
X1313921Y856694D03*
Y863103D03*
X1310221Y869511D03*
X1312070Y872716D03*
X1313921Y869511D03*
X1310221Y875920D03*
Y882329D03*
X1312070Y879124D03*
X1313921Y875920D03*
Y882329D03*
X1310221Y888737D03*
Y895146D03*
X1312070Y885533D03*
Y891942D03*
Y898350D03*
X1313921Y888737D03*
Y895146D03*
Y901555D03*
X1310221D03*
Y907963D03*
Y914372D03*
X1312070Y904759D03*
Y911167D03*
Y917576D03*
X1313921Y907963D03*
Y914372D03*
X1310221Y920780D03*
Y927189D03*
Y933598D03*
X1312070Y923985D03*
Y930393D03*
X1313921Y920780D03*
Y927189D03*
Y933598D03*
X1310221Y940006D03*
Y946414D03*
X1312070Y936801D03*
Y943210D03*
Y949619D03*
X1313921Y940006D03*
Y946414D03*
X1310221Y952823D03*
Y959232D03*
X1312070Y956027D03*
Y962436D03*
X1313921Y952823D03*
Y959232D03*
X1310221Y965640D03*
X1313921D03*
X1310221Y972049D03*
Y978457D03*
X1312070Y968845D03*
Y975253D03*
Y981662D03*
X1313921Y972049D03*
Y978457D03*
Y984866D03*
X1310654Y1007187D03*
Y1013595D03*
X1312503Y1003983D03*
Y1010391D03*
X1314353Y1000778D03*
Y1007187D03*
Y1013595D03*
X1310654Y1020004D03*
X1312503Y1016800D03*
Y1023208D03*
X1314353Y1020004D03*
X1310654Y1026413D03*
X1312503Y1029617D03*
X1314353Y1026413D03*
X1310654Y1032821D03*
Y1039230D03*
Y1045639D03*
X1312503Y1036026D03*
Y1042434D03*
X1314353Y1032821D03*
Y1039230D03*
Y1045639D03*
X1310654Y1052047D03*
X1312503Y1048842D03*
X1314353Y1052047D03*
X1312503Y1055251D03*
Y1061660D03*
X1314353Y1058455D03*
X1312503Y1068068D03*
Y1074477D03*
X1314353Y1064864D03*
Y1071273D03*
Y1077681D03*
X1312503Y1080885D03*
Y1087294D03*
Y1093703D03*
X1314353Y1084090D03*
Y1090498D03*
X1312503Y1100111D03*
Y1106520D03*
Y1112929D03*
X1314353Y1096907D03*
Y1103316D03*
Y1109724D03*
X1312503Y1119337D03*
Y1125746D03*
X1314353Y1116133D03*
Y1122541D03*
Y1128950D03*
X1323171Y847081D03*
X1325021Y850286D03*
X1326870Y847081D03*
X1328721Y850286D03*
X1330570Y847081D03*
X1321321Y850286D03*
X1323171Y853490D03*
Y859899D03*
Y866307D03*
X1325021Y856694D03*
Y863103D03*
X1326870Y853490D03*
Y859899D03*
Y866307D03*
X1328721Y856694D03*
Y863103D03*
X1330570Y853490D03*
Y859899D03*
Y866307D03*
X1315771Y853490D03*
Y859899D03*
Y866307D03*
X1317621Y856694D03*
Y863103D03*
X1319470Y853490D03*
Y859899D03*
Y866307D03*
X1321321Y856694D03*
Y863103D03*
X1323171Y872716D03*
X1325021Y869511D03*
X1326870Y872716D03*
X1328721Y869511D03*
X1330570Y872716D03*
X1315771D03*
X1317621Y869511D03*
X1319470Y872716D03*
X1321321Y869511D03*
X1323171Y879124D03*
X1325021Y875920D03*
Y882329D03*
X1326870Y879124D03*
X1328721Y875920D03*
Y882329D03*
X1330570Y879124D03*
X1315771D03*
X1317621Y875920D03*
Y882329D03*
X1319470Y879124D03*
X1321321Y875920D03*
Y882329D03*
X1323171Y885533D03*
Y891942D03*
Y898350D03*
X1325021Y888737D03*
Y895146D03*
Y901555D03*
X1326870Y885533D03*
Y891942D03*
Y898350D03*
X1328721Y888737D03*
Y895146D03*
Y901555D03*
X1330570Y885533D03*
Y891942D03*
Y898350D03*
X1315771Y885533D03*
Y891942D03*
Y898350D03*
X1317621Y888737D03*
Y895146D03*
Y901555D03*
X1319470Y885533D03*
Y891942D03*
Y898350D03*
X1321321Y888737D03*
Y895146D03*
Y901555D03*
X1323171Y904759D03*
Y911167D03*
Y917576D03*
X1325021Y907963D03*
Y914372D03*
X1326870Y904759D03*
Y911167D03*
Y917576D03*
X1328721Y907963D03*
Y914372D03*
X1330570Y904759D03*
Y911167D03*
Y917576D03*
X1315771Y904759D03*
Y911167D03*
Y917576D03*
X1317621Y907963D03*
Y914372D03*
X1319470Y904759D03*
Y911167D03*
Y917576D03*
X1321321Y907963D03*
Y914372D03*
X1323171Y923985D03*
Y930393D03*
X1325021Y920780D03*
Y927189D03*
Y933598D03*
X1326870Y923985D03*
Y930393D03*
X1328721Y920780D03*
Y927189D03*
Y933598D03*
X1330570Y923985D03*
Y930393D03*
X1315771Y923985D03*
Y930393D03*
X1317621Y920780D03*
Y927189D03*
Y933598D03*
X1319470Y923985D03*
Y930393D03*
X1321321Y920780D03*
Y927189D03*
Y933598D03*
X1323171Y936801D03*
Y943210D03*
Y949619D03*
X1325021Y940006D03*
Y946414D03*
X1326870Y936801D03*
Y943210D03*
Y949619D03*
X1328721Y940006D03*
Y946414D03*
X1330570Y936801D03*
Y943210D03*
Y949619D03*
X1315771Y936801D03*
Y943210D03*
Y949619D03*
X1317621Y940006D03*
Y946414D03*
X1319470Y936801D03*
Y943210D03*
Y949619D03*
X1321321Y940006D03*
Y946414D03*
X1323171Y956027D03*
Y962436D03*
X1325021Y952823D03*
Y959232D03*
X1326870Y956027D03*
Y962436D03*
X1328721Y952823D03*
Y959232D03*
X1330570Y956027D03*
Y962436D03*
X1315771Y956027D03*
Y962436D03*
X1317621Y952823D03*
Y959232D03*
X1319470Y956027D03*
Y962436D03*
X1321321Y952823D03*
Y959232D03*
X1325021Y965640D03*
X1328721D03*
X1317621D03*
X1321321D03*
X1323171Y968845D03*
Y975253D03*
Y981662D03*
X1325021Y972049D03*
Y978457D03*
X1326870Y968845D03*
Y975253D03*
Y981662D03*
X1328721Y972049D03*
Y978457D03*
X1330570Y968845D03*
Y975253D03*
Y981662D03*
X1315771Y968845D03*
Y975253D03*
Y981662D03*
X1317621Y972049D03*
Y978457D03*
X1319470Y968845D03*
Y975253D03*
Y981662D03*
X1321321Y972049D03*
Y978457D03*
X1325021Y984866D03*
X1328721D03*
X1317621D03*
X1321321D03*
X1323603Y997574D03*
X1327303D03*
X1331003D03*
X1316203D03*
X1319903D03*
X1323603Y1003983D03*
Y1010391D03*
X1325454Y1000778D03*
Y1007187D03*
Y1013595D03*
X1327303Y1003983D03*
Y1010391D03*
X1329153Y1000778D03*
Y1007187D03*
Y1013595D03*
X1331003Y1003983D03*
Y1010391D03*
X1316203Y1003983D03*
Y1010391D03*
X1318054Y1000778D03*
Y1007187D03*
Y1013595D03*
X1319903Y1003983D03*
Y1010391D03*
X1321753Y1000778D03*
Y1007187D03*
Y1013595D03*
X1323603Y1016800D03*
Y1023208D03*
X1325454Y1020004D03*
X1327303Y1016800D03*
Y1023208D03*
X1329153Y1020004D03*
X1331003Y1016800D03*
Y1023208D03*
X1316203Y1016800D03*
Y1023208D03*
X1318054Y1020004D03*
X1319903Y1016800D03*
Y1023208D03*
X1321753Y1020004D03*
X1323603Y1029617D03*
X1325454Y1026413D03*
X1327303Y1029617D03*
X1329153Y1026413D03*
X1331003Y1029617D03*
X1316203D03*
X1318054Y1026413D03*
X1319903Y1029617D03*
X1321753Y1026413D03*
X1323603Y1036026D03*
Y1042434D03*
X1325454Y1032821D03*
Y1039230D03*
Y1045639D03*
X1327303Y1036026D03*
Y1042434D03*
X1329153Y1032821D03*
Y1039230D03*
Y1045639D03*
X1331003Y1036026D03*
Y1042434D03*
X1316203Y1036026D03*
Y1042434D03*
X1318054Y1032821D03*
Y1039230D03*
Y1045639D03*
X1319903Y1036026D03*
Y1042434D03*
X1321753Y1032821D03*
Y1039230D03*
Y1045639D03*
X1323603Y1048842D03*
X1325454Y1052047D03*
X1327303Y1048842D03*
X1329153Y1052047D03*
X1331003Y1048842D03*
X1316203D03*
X1318054Y1052047D03*
X1319903Y1048842D03*
X1321753Y1052047D03*
X1323603Y1055251D03*
Y1061660D03*
X1325454Y1058455D03*
X1327303Y1055251D03*
Y1061660D03*
X1329153Y1058455D03*
X1331003Y1055251D03*
Y1061660D03*
X1316203Y1055251D03*
Y1061660D03*
X1318054Y1058455D03*
X1319903Y1055251D03*
Y1061660D03*
X1321753Y1058455D03*
X1323603Y1068068D03*
Y1074477D03*
X1325454Y1064864D03*
Y1071273D03*
Y1077681D03*
X1327303Y1068068D03*
Y1074477D03*
X1329153Y1064864D03*
Y1071273D03*
Y1077681D03*
X1331003Y1068068D03*
Y1074477D03*
X1316203Y1068068D03*
Y1074477D03*
X1318054Y1064864D03*
Y1071273D03*
Y1077681D03*
X1319903Y1068068D03*
Y1074477D03*
X1321753Y1064864D03*
Y1071273D03*
Y1077681D03*
X1323603Y1080885D03*
X1327303D03*
X1331003D03*
X1316203D03*
X1319903D03*
X1323603Y1087294D03*
Y1093703D03*
X1325454Y1084090D03*
Y1090498D03*
X1327303Y1087294D03*
Y1093703D03*
X1329153Y1084090D03*
Y1090498D03*
X1331003Y1087294D03*
Y1093703D03*
X1316203Y1087294D03*
Y1093703D03*
X1318054Y1084090D03*
Y1090498D03*
X1319903Y1087294D03*
Y1093703D03*
X1321753Y1084090D03*
Y1090498D03*
X1323603Y1100111D03*
Y1106520D03*
Y1112929D03*
X1325454Y1096907D03*
Y1103316D03*
Y1109724D03*
X1327303Y1100111D03*
Y1106520D03*
Y1112929D03*
X1329153Y1096907D03*
Y1103316D03*
Y1109724D03*
X1331003Y1100111D03*
Y1106520D03*
Y1112929D03*
X1316203Y1100111D03*
Y1106520D03*
Y1112929D03*
X1318054Y1096907D03*
Y1103316D03*
Y1109724D03*
X1319903Y1100111D03*
Y1106520D03*
Y1112929D03*
X1321753Y1096907D03*
Y1103316D03*
Y1109724D03*
X1323603Y1119337D03*
Y1125746D03*
X1325454Y1116133D03*
Y1122541D03*
Y1128950D03*
X1327303Y1119337D03*
Y1125746D03*
X1329153Y1116133D03*
Y1122541D03*
Y1128950D03*
X1331003Y1119337D03*
Y1125746D03*
X1316203Y1119337D03*
Y1125746D03*
X1318054Y1116133D03*
Y1122541D03*
Y1128950D03*
X1319903Y1119337D03*
Y1125746D03*
X1321753Y1116133D03*
Y1122541D03*
Y1128950D03*
X1323603Y1132154D03*
X1325454Y1135359D03*
X1327303Y1132154D03*
X1329153Y1135359D03*
X1331003Y1132154D03*
X1319903D03*
X1321753Y1135359D03*
X1347221Y843877D03*
X1332421D03*
X1336121D03*
X1339821D03*
X1343521D03*
X1347221Y850286D03*
X1332421D03*
X1334270Y847081D03*
X1336121Y850286D03*
X1337970Y847081D03*
X1339821Y850286D03*
X1341670Y847081D03*
X1343521Y850286D03*
X1345370Y847081D03*
X1347221Y856694D03*
Y863103D03*
X1332421Y856694D03*
Y863103D03*
X1334270Y853490D03*
Y859899D03*
Y866307D03*
X1336121Y856694D03*
Y863103D03*
X1337970Y853490D03*
Y859899D03*
Y866307D03*
X1339821Y856694D03*
Y863103D03*
X1341670Y853490D03*
Y859899D03*
Y866307D03*
X1343521Y856694D03*
Y863103D03*
X1345370Y853490D03*
Y859899D03*
Y866307D03*
X1347221Y869511D03*
X1332421D03*
X1334270Y872716D03*
X1336121Y869511D03*
X1337970Y872716D03*
X1339821Y869511D03*
X1341670Y872716D03*
X1343521Y869511D03*
X1345370Y872716D03*
X1347221Y875920D03*
Y882329D03*
X1332421Y875920D03*
Y882329D03*
X1334270Y879124D03*
X1336121Y875920D03*
Y882329D03*
X1337970Y879124D03*
X1339821Y875920D03*
Y882329D03*
X1341670Y879124D03*
X1343521Y875920D03*
Y882329D03*
X1345370Y879124D03*
X1347221Y888737D03*
Y895146D03*
Y901555D03*
X1332421Y888737D03*
Y895146D03*
Y901555D03*
X1334270Y885533D03*
Y891942D03*
Y898350D03*
X1336121Y888737D03*
Y895146D03*
Y901555D03*
X1337970Y885533D03*
Y891942D03*
Y898350D03*
X1339821Y888737D03*
Y895146D03*
Y901555D03*
X1341670Y885533D03*
Y891942D03*
Y898350D03*
X1343521Y888737D03*
Y895146D03*
Y901555D03*
X1345370Y885533D03*
Y891942D03*
Y898350D03*
X1347221Y907963D03*
Y914372D03*
X1332421Y907963D03*
Y914372D03*
X1334270Y904759D03*
Y911167D03*
Y917576D03*
X1336121Y907963D03*
Y914372D03*
X1337970Y904759D03*
Y911167D03*
Y917576D03*
X1339821Y907963D03*
Y914372D03*
X1341670Y904759D03*
Y911167D03*
Y917576D03*
X1343521Y907963D03*
Y914372D03*
X1345370Y904759D03*
Y911167D03*
Y917576D03*
X1347221Y920780D03*
Y927189D03*
X1332421Y920780D03*
Y927189D03*
Y933598D03*
X1334270Y923985D03*
Y930393D03*
X1336121Y920780D03*
Y927189D03*
Y933598D03*
X1337970Y923985D03*
Y930393D03*
X1339821Y920780D03*
Y927189D03*
Y933598D03*
X1341670Y923985D03*
Y930393D03*
X1343521Y920780D03*
Y927189D03*
Y933598D03*
X1345370Y923985D03*
Y930393D03*
X1347221Y933598D03*
Y940006D03*
Y946414D03*
X1332421Y940006D03*
Y946414D03*
X1334270Y936801D03*
Y943210D03*
Y949619D03*
X1336121Y940006D03*
Y946414D03*
X1337970Y936801D03*
Y943210D03*
Y949619D03*
X1339821Y940006D03*
Y946414D03*
X1341670Y936801D03*
Y943210D03*
Y949619D03*
X1343521Y940006D03*
Y946414D03*
X1345370Y936801D03*
Y943210D03*
Y949619D03*
X1347221Y952823D03*
Y959232D03*
X1332421Y952823D03*
Y959232D03*
X1334270Y956027D03*
Y962436D03*
X1336121Y952823D03*
Y959232D03*
X1337970Y956027D03*
Y962436D03*
X1339821Y952823D03*
Y959232D03*
X1341670Y956027D03*
Y962436D03*
X1343521Y952823D03*
Y959232D03*
X1345370Y956027D03*
Y962436D03*
X1347221Y965640D03*
X1332421D03*
X1336121D03*
X1339821D03*
X1343521D03*
X1347221Y972049D03*
Y978457D03*
X1332421Y972049D03*
Y978457D03*
X1334270Y968845D03*
Y975253D03*
Y981662D03*
X1336121Y972049D03*
Y978457D03*
X1337970Y968845D03*
Y975253D03*
Y981662D03*
X1339821Y972049D03*
Y978457D03*
X1341670Y968845D03*
Y975253D03*
Y981662D03*
X1343521Y972049D03*
Y978457D03*
X1345370Y968845D03*
Y975253D03*
Y981662D03*
X1347221Y984866D03*
X1332421D03*
X1336121D03*
X1339821D03*
X1343521D03*
X1334703Y997574D03*
X1338403D03*
X1342103D03*
X1345803D03*
X1332854Y1000778D03*
Y1007187D03*
Y1013595D03*
X1334703Y1003983D03*
Y1010391D03*
X1336554Y1000778D03*
Y1007187D03*
Y1013595D03*
X1338403Y1003983D03*
Y1010391D03*
X1340254Y1000778D03*
Y1007187D03*
Y1013595D03*
X1342103Y1003983D03*
Y1010391D03*
X1343954Y1000778D03*
Y1007187D03*
Y1013595D03*
X1345803Y1003983D03*
Y1010391D03*
X1332854Y1020004D03*
X1334703Y1016800D03*
Y1023208D03*
X1336554Y1020004D03*
X1338403Y1016800D03*
Y1023208D03*
X1340254Y1020004D03*
X1342103Y1016800D03*
Y1023208D03*
X1343954Y1020004D03*
X1345803Y1016800D03*
Y1023208D03*
X1332854Y1026413D03*
X1334703Y1029617D03*
X1336554Y1026413D03*
X1338403Y1029617D03*
X1340254Y1026413D03*
X1342103Y1029617D03*
X1343954Y1026413D03*
X1345803Y1029617D03*
X1332854Y1032821D03*
Y1039230D03*
Y1045639D03*
X1334703Y1036026D03*
Y1042434D03*
X1336554Y1032821D03*
Y1039230D03*
Y1045639D03*
X1338403Y1036026D03*
Y1042434D03*
X1340254Y1032821D03*
Y1039230D03*
Y1045639D03*
X1342103Y1036026D03*
Y1042434D03*
X1343954Y1032821D03*
Y1039230D03*
Y1045639D03*
X1345803Y1036026D03*
Y1042434D03*
X1332854Y1052047D03*
X1334703Y1048842D03*
X1336554Y1052047D03*
X1338403Y1048842D03*
X1340254Y1052047D03*
X1342103Y1048842D03*
X1343954Y1052047D03*
X1345803Y1048842D03*
X1332854Y1058455D03*
X1334703Y1055251D03*
Y1061660D03*
X1336554Y1058455D03*
X1338403Y1055251D03*
Y1061660D03*
X1340254Y1058455D03*
X1342103Y1055251D03*
Y1061660D03*
X1343954Y1058455D03*
X1345803Y1055251D03*
Y1061660D03*
X1332854Y1064864D03*
Y1071273D03*
Y1077681D03*
X1334703Y1068068D03*
Y1074477D03*
X1336554Y1064864D03*
Y1071273D03*
Y1077681D03*
X1338403Y1068068D03*
Y1074477D03*
X1340254Y1064864D03*
Y1071273D03*
Y1077681D03*
X1342103Y1068068D03*
Y1074477D03*
X1343954Y1064864D03*
Y1071273D03*
Y1077681D03*
X1345803Y1068068D03*
Y1074477D03*
X1334703Y1080885D03*
X1338403D03*
X1342103D03*
X1345803D03*
X1332854Y1084090D03*
Y1090498D03*
X1334703Y1087294D03*
Y1093703D03*
X1336554Y1084090D03*
Y1090498D03*
X1338403Y1087294D03*
Y1093703D03*
X1340254Y1084090D03*
Y1090498D03*
X1342103Y1087294D03*
Y1093703D03*
X1343954Y1084090D03*
Y1090498D03*
X1345803Y1087294D03*
Y1093703D03*
X1332854Y1096907D03*
Y1103316D03*
Y1109724D03*
X1334703Y1100111D03*
Y1106520D03*
Y1112929D03*
X1336554Y1096907D03*
Y1103316D03*
Y1109724D03*
X1338403Y1100111D03*
Y1106520D03*
Y1112929D03*
X1340254Y1096907D03*
Y1103316D03*
Y1109724D03*
X1342103Y1100111D03*
Y1106520D03*
Y1112929D03*
X1343954Y1096907D03*
Y1103316D03*
Y1109724D03*
X1345803Y1100111D03*
Y1106520D03*
Y1112929D03*
X1332854Y1116133D03*
Y1122541D03*
Y1128950D03*
X1334703Y1119337D03*
Y1125746D03*
X1336554Y1116133D03*
Y1122541D03*
Y1128950D03*
X1338403Y1119337D03*
Y1125746D03*
X1340254Y1116133D03*
Y1122541D03*
Y1128950D03*
X1342103Y1119337D03*
Y1125746D03*
X1343954Y1116133D03*
Y1122541D03*
Y1128950D03*
X1345803Y1119337D03*
Y1125746D03*
X1332854Y1135359D03*
X1334703Y1132154D03*
Y1138563D03*
X1336554Y1135359D03*
X1338403Y1132154D03*
Y1138563D03*
X1340254Y1135359D03*
X1342103Y1132154D03*
Y1138563D03*
X1343954Y1135359D03*
X1345803Y1132154D03*
Y1138563D03*
X1354621Y843877D03*
X1358321D03*
X1362021D03*
X1350921D03*
X1352770Y847081D03*
X1354621Y850286D03*
X1356470Y847081D03*
X1358321Y850286D03*
X1360170Y847081D03*
X1362021Y850286D03*
X1349070Y847081D03*
X1350921Y850286D03*
X1352770Y853490D03*
Y859899D03*
Y866307D03*
X1354621Y856694D03*
Y863103D03*
X1356470Y853490D03*
Y859899D03*
Y866307D03*
X1358321Y856694D03*
Y863103D03*
X1360170Y853490D03*
Y859899D03*
Y866307D03*
X1362021Y856694D03*
Y863103D03*
X1349070Y853490D03*
Y859899D03*
Y866307D03*
X1350921Y856694D03*
Y863103D03*
X1352770Y872716D03*
X1354621Y869511D03*
X1356470Y872716D03*
X1358321Y869511D03*
X1360170Y872716D03*
X1362021Y869511D03*
X1349070Y872716D03*
X1350921Y869511D03*
X1352770Y879124D03*
X1354621Y875920D03*
Y882329D03*
X1356470Y879124D03*
X1358321Y875920D03*
Y882329D03*
X1360170Y879124D03*
X1362021Y875920D03*
Y882329D03*
X1349070Y879124D03*
X1350921Y875920D03*
Y882329D03*
X1352770Y885533D03*
Y891942D03*
Y898350D03*
X1354621Y888737D03*
Y895146D03*
Y901555D03*
X1356470Y885533D03*
Y891942D03*
Y898350D03*
X1358321Y888737D03*
Y895146D03*
Y901555D03*
X1360170Y885533D03*
Y891942D03*
Y898350D03*
X1362021Y888737D03*
Y895146D03*
Y901555D03*
X1349070Y885533D03*
Y891942D03*
Y898350D03*
X1350921Y888737D03*
Y895146D03*
Y901555D03*
X1352770Y904759D03*
Y911167D03*
Y917576D03*
X1354621Y907963D03*
Y914372D03*
X1356470Y904759D03*
Y911167D03*
Y917576D03*
X1358321Y907963D03*
Y914372D03*
X1360170Y904759D03*
Y911167D03*
Y917576D03*
X1362021Y907963D03*
Y914372D03*
X1349070Y904759D03*
Y911167D03*
Y917576D03*
X1350921Y907963D03*
Y914372D03*
X1352770Y923985D03*
Y930393D03*
X1354621Y920780D03*
Y927189D03*
X1356470Y923985D03*
Y930393D03*
X1358321Y920780D03*
Y927189D03*
X1360170Y923985D03*
Y930393D03*
X1362021Y920780D03*
Y927189D03*
X1349070Y923985D03*
Y930393D03*
X1350921Y920780D03*
Y927189D03*
X1354621Y933598D03*
X1358321D03*
X1362021D03*
X1350921D03*
X1352770Y936801D03*
Y943210D03*
Y949619D03*
X1354621Y940006D03*
Y946414D03*
X1356470Y936801D03*
Y943210D03*
Y949619D03*
X1358321Y940006D03*
Y946414D03*
X1360170Y936801D03*
Y943210D03*
Y949619D03*
X1362021Y940006D03*
Y946414D03*
X1349070Y936801D03*
Y943210D03*
Y949619D03*
X1350921Y940006D03*
Y946414D03*
X1352770Y956027D03*
Y962436D03*
X1354621Y952823D03*
Y959232D03*
X1356470Y956027D03*
Y962436D03*
X1358321Y952823D03*
Y959232D03*
X1360170Y956027D03*
Y962436D03*
X1362021Y952823D03*
Y959232D03*
X1349070Y956027D03*
Y962436D03*
X1350921Y952823D03*
Y959232D03*
X1354621Y965640D03*
X1358321D03*
X1362021D03*
X1350921D03*
X1352770Y968845D03*
Y975253D03*
Y981662D03*
X1354621Y972049D03*
Y978457D03*
X1356470Y968845D03*
Y975253D03*
Y981662D03*
X1358321Y972049D03*
Y978457D03*
X1360170Y968845D03*
Y975253D03*
Y981662D03*
X1362021Y972049D03*
Y978457D03*
X1349070Y968845D03*
Y975253D03*
Y981662D03*
X1350921Y972049D03*
Y978457D03*
X1354621Y984866D03*
X1358321D03*
X1362021D03*
X1350921D03*
X1353203Y997574D03*
X1356903D03*
X1360603D03*
X1349503D03*
X1353203Y1003983D03*
Y1010391D03*
X1355054Y1000778D03*
Y1007187D03*
Y1013595D03*
X1356903Y1003983D03*
Y1010391D03*
X1358754Y1000778D03*
Y1007187D03*
Y1013595D03*
X1360603Y1003983D03*
Y1010391D03*
X1362454Y1000778D03*
Y1007187D03*
Y1013595D03*
X1347654Y1000778D03*
Y1007187D03*
Y1013595D03*
X1349503Y1003983D03*
Y1010391D03*
X1351354Y1000778D03*
Y1007187D03*
Y1013595D03*
X1353203Y1016800D03*
X1355054Y1020004D03*
X1356903Y1016800D03*
X1358754Y1020004D03*
X1360603Y1016800D03*
X1362454Y1020004D03*
X1347654D03*
X1349503Y1016800D03*
X1351354Y1020004D03*
X1353203Y1023208D03*
Y1029617D03*
X1355054Y1026413D03*
X1356903Y1023208D03*
Y1029617D03*
X1358754Y1026413D03*
X1360603Y1023208D03*
Y1029617D03*
X1362454Y1026413D03*
X1347654D03*
X1349503Y1023208D03*
Y1029617D03*
X1351354Y1026413D03*
X1353203Y1036026D03*
Y1042434D03*
X1355054Y1032821D03*
Y1039230D03*
Y1045639D03*
X1356903Y1036026D03*
Y1042434D03*
X1358754Y1032821D03*
Y1039230D03*
Y1045639D03*
X1360603Y1036026D03*
Y1042434D03*
X1362454Y1032821D03*
Y1039230D03*
Y1045639D03*
X1347654Y1032821D03*
Y1039230D03*
Y1045639D03*
X1349503Y1036026D03*
Y1042434D03*
X1351354Y1032821D03*
Y1039230D03*
Y1045639D03*
X1353203Y1048842D03*
X1355054Y1052047D03*
X1356903Y1048842D03*
X1358754Y1052047D03*
X1360603Y1048842D03*
X1362454Y1052047D03*
X1347654D03*
X1349503Y1048842D03*
X1351354Y1052047D03*
X1353203Y1055251D03*
Y1061660D03*
X1355054Y1058455D03*
X1356903Y1055251D03*
Y1061660D03*
X1358754Y1058455D03*
X1360603Y1055251D03*
Y1061660D03*
X1362454Y1058455D03*
X1347654D03*
X1349503Y1055251D03*
Y1061660D03*
X1351354Y1058455D03*
X1353203Y1068068D03*
Y1074477D03*
X1355054Y1064864D03*
Y1071273D03*
Y1077681D03*
X1356903Y1068068D03*
Y1074477D03*
X1358754Y1064864D03*
Y1071273D03*
Y1077681D03*
X1360603Y1068068D03*
Y1074477D03*
X1362454Y1064864D03*
Y1071273D03*
Y1077681D03*
X1347654Y1064864D03*
Y1071273D03*
Y1077681D03*
X1349503Y1068068D03*
Y1074477D03*
X1351354Y1064864D03*
Y1071273D03*
Y1077681D03*
X1353203Y1080885D03*
X1356903D03*
X1360603D03*
X1349503D03*
X1353203Y1087294D03*
Y1093703D03*
X1355054Y1084090D03*
Y1090498D03*
X1356903Y1087294D03*
Y1093703D03*
X1358754Y1084090D03*
Y1090498D03*
X1360603Y1087294D03*
Y1093703D03*
X1362454Y1084090D03*
Y1090498D03*
X1347654Y1084090D03*
Y1090498D03*
X1349503Y1087294D03*
Y1093703D03*
X1351354Y1084090D03*
Y1090498D03*
X1353203Y1100111D03*
Y1106520D03*
X1355054Y1096907D03*
Y1103316D03*
Y1109724D03*
X1356903Y1100111D03*
Y1106520D03*
X1358754Y1096907D03*
Y1103316D03*
Y1109724D03*
X1360603Y1100111D03*
Y1106520D03*
X1362454Y1096907D03*
Y1103316D03*
Y1109724D03*
X1347654Y1096907D03*
Y1103316D03*
Y1109724D03*
X1349503Y1100111D03*
Y1106520D03*
X1351354Y1096907D03*
Y1103316D03*
Y1109724D03*
X1353203Y1112929D03*
X1356903D03*
X1360603D03*
X1349503D03*
X1353203Y1119337D03*
Y1125746D03*
X1355054Y1116133D03*
Y1122541D03*
Y1128950D03*
X1356903Y1119337D03*
Y1125746D03*
X1358754Y1116133D03*
Y1122541D03*
Y1128950D03*
X1360603Y1119337D03*
Y1125746D03*
X1362454Y1116133D03*
Y1122541D03*
Y1128950D03*
X1347654Y1116133D03*
Y1122541D03*
Y1128950D03*
X1349503Y1119337D03*
Y1125746D03*
X1351354Y1116133D03*
Y1122541D03*
Y1128950D03*
X1353203Y1132154D03*
Y1138563D03*
X1355054Y1135359D03*
X1356903Y1132154D03*
Y1138563D03*
X1358754Y1135359D03*
X1360603Y1132154D03*
Y1138563D03*
X1362454Y1135359D03*
X1347654D03*
X1349503Y1132154D03*
Y1138563D03*
X1351354Y1135359D03*
X1365721Y843877D03*
X1369421D03*
X1373121D03*
X1376821D03*
X1363870Y847081D03*
X1365721Y850286D03*
X1367570Y847081D03*
X1369421Y850286D03*
X1371270Y847081D03*
X1373121Y850286D03*
X1374970Y847081D03*
X1376821Y850286D03*
X1378670Y847081D03*
X1363870Y853490D03*
Y859899D03*
Y866307D03*
X1365721Y856694D03*
Y863103D03*
X1367570Y853490D03*
Y859899D03*
Y866307D03*
X1369421Y856694D03*
Y863103D03*
X1371270Y853490D03*
Y859899D03*
Y866307D03*
X1373121Y856694D03*
Y863103D03*
X1374970Y853490D03*
Y859899D03*
Y866307D03*
X1376821Y856694D03*
Y863103D03*
X1378670Y853490D03*
Y859899D03*
Y866307D03*
X1363870Y872716D03*
X1365721Y869511D03*
X1367570Y872716D03*
X1369421Y869511D03*
X1371270Y872716D03*
X1373121Y869511D03*
X1374970Y872716D03*
X1376821Y869511D03*
X1378670Y872716D03*
X1363870Y879124D03*
X1365721Y875920D03*
Y882329D03*
X1367570Y879124D03*
X1369421Y875920D03*
Y882329D03*
X1371270Y879124D03*
X1373121Y875920D03*
Y882329D03*
X1374970Y879124D03*
X1376821Y875920D03*
Y882329D03*
X1378670Y879124D03*
X1363870Y885533D03*
Y891942D03*
Y898350D03*
X1365721Y888737D03*
Y895146D03*
Y901555D03*
X1367570Y885533D03*
Y891942D03*
Y898350D03*
X1369421Y888737D03*
Y895146D03*
Y901555D03*
X1371270Y885533D03*
Y891942D03*
Y898350D03*
X1373121Y888737D03*
Y895146D03*
Y901555D03*
X1374970Y885533D03*
Y891942D03*
Y898350D03*
X1376821Y888737D03*
Y895146D03*
Y901555D03*
X1378670Y885533D03*
Y891942D03*
Y898350D03*
X1363870Y904759D03*
Y911167D03*
Y917576D03*
X1365721Y907963D03*
Y914372D03*
X1367570Y904759D03*
Y911167D03*
Y917576D03*
X1369421Y907963D03*
Y914372D03*
X1371270Y904759D03*
Y911167D03*
Y917576D03*
X1373121Y907963D03*
Y914372D03*
X1374970Y904759D03*
Y911167D03*
Y917576D03*
X1376821Y907963D03*
Y914372D03*
X1378670Y904759D03*
Y911167D03*
Y917576D03*
X1363870Y923985D03*
Y930393D03*
X1365721Y920780D03*
Y927189D03*
X1367570Y923985D03*
Y930393D03*
X1369421Y920780D03*
Y927189D03*
X1371270Y923985D03*
Y930393D03*
X1373121Y920780D03*
Y927189D03*
X1374970Y923985D03*
Y930393D03*
X1376821Y920780D03*
Y927189D03*
X1378670Y923985D03*
Y930393D03*
X1365721Y933598D03*
X1369421D03*
X1373121D03*
X1376821D03*
X1363870Y936801D03*
Y943210D03*
Y949619D03*
X1365721Y940006D03*
Y946414D03*
X1367570Y936801D03*
Y943210D03*
Y949619D03*
X1369421Y940006D03*
Y946414D03*
X1371270Y936801D03*
Y943210D03*
Y949619D03*
X1373121Y940006D03*
Y946414D03*
X1374970Y936801D03*
Y943210D03*
Y949619D03*
X1376821Y940006D03*
Y946414D03*
X1378670Y936801D03*
Y943210D03*
Y949619D03*
X1363870Y956027D03*
Y962436D03*
X1365721Y952823D03*
Y959232D03*
X1367570Y956027D03*
Y962436D03*
X1369421Y952823D03*
Y959232D03*
X1371270Y956027D03*
Y962436D03*
X1373121Y952823D03*
Y959232D03*
X1374970Y956027D03*
Y962436D03*
X1376821Y952823D03*
Y959232D03*
X1378670Y956027D03*
Y962436D03*
X1365721Y965640D03*
X1369421D03*
X1373121D03*
X1376821D03*
X1363870Y968845D03*
Y975253D03*
Y981662D03*
X1365721Y972049D03*
Y978457D03*
X1367570Y968845D03*
Y975253D03*
Y981662D03*
X1369421Y972049D03*
Y978457D03*
X1371270Y968845D03*
Y975253D03*
Y981662D03*
X1373121Y972049D03*
Y978457D03*
X1374970Y968845D03*
Y975253D03*
Y981662D03*
X1376821Y972049D03*
Y978457D03*
X1378670Y968845D03*
Y975253D03*
Y981662D03*
X1365721Y984866D03*
X1369421D03*
X1373121D03*
X1376821D03*
X1364303Y997574D03*
X1368003D03*
X1371703D03*
X1375403D03*
X1379103D03*
X1364303Y1003983D03*
Y1010391D03*
X1366154Y1000778D03*
Y1007187D03*
Y1013595D03*
X1368003Y1003983D03*
Y1010391D03*
X1369854Y1000778D03*
Y1007187D03*
Y1013595D03*
X1371703Y1003983D03*
Y1010391D03*
X1373554Y1000778D03*
Y1007187D03*
Y1013595D03*
X1375403Y1003983D03*
Y1010391D03*
X1377254Y1000778D03*
Y1007187D03*
Y1013595D03*
X1379103Y1003983D03*
Y1010391D03*
X1364303Y1016800D03*
X1366154Y1020004D03*
X1368003Y1016800D03*
X1369854Y1020004D03*
X1371703Y1016800D03*
X1373554Y1020004D03*
X1375403Y1016800D03*
X1377254Y1020004D03*
X1379103Y1016800D03*
X1364303Y1023208D03*
Y1029617D03*
X1366154Y1026413D03*
X1368003Y1023208D03*
Y1029617D03*
X1369854Y1026413D03*
X1371703Y1023208D03*
Y1029617D03*
X1373554Y1026413D03*
X1375403Y1023208D03*
Y1029617D03*
X1377254Y1026413D03*
X1379103Y1023208D03*
Y1029617D03*
X1364303Y1036026D03*
Y1042434D03*
X1366154Y1032821D03*
Y1039230D03*
Y1045639D03*
X1368003Y1036026D03*
Y1042434D03*
X1369854Y1032821D03*
Y1039230D03*
Y1045639D03*
X1371703Y1036026D03*
Y1042434D03*
X1373554Y1032821D03*
Y1039230D03*
Y1045639D03*
X1375403Y1036026D03*
Y1042434D03*
X1377254Y1032821D03*
Y1039230D03*
Y1045639D03*
X1379103Y1036026D03*
Y1042434D03*
X1364303Y1048842D03*
X1366154Y1052047D03*
X1368003Y1048842D03*
X1369854Y1052047D03*
X1371703Y1048842D03*
X1373554Y1052047D03*
X1375403Y1048842D03*
X1377254Y1052047D03*
X1379103Y1048842D03*
X1364303Y1055251D03*
Y1061660D03*
X1366154Y1058455D03*
X1368003Y1055251D03*
Y1061660D03*
X1369854Y1058455D03*
X1371703Y1055251D03*
Y1061660D03*
X1373554Y1058455D03*
X1375403Y1055251D03*
Y1061660D03*
X1377254Y1058455D03*
X1379103Y1055251D03*
Y1061660D03*
X1364303Y1068068D03*
Y1074477D03*
X1366154Y1064864D03*
Y1071273D03*
Y1077681D03*
X1368003Y1068068D03*
Y1074477D03*
X1369854Y1064864D03*
Y1071273D03*
Y1077681D03*
X1371703Y1068068D03*
Y1074477D03*
X1373554Y1064864D03*
Y1071273D03*
Y1077681D03*
X1375403Y1068068D03*
Y1074477D03*
X1377254Y1064864D03*
Y1071273D03*
Y1077681D03*
X1379103Y1068068D03*
Y1074477D03*
X1364303Y1080885D03*
X1368003D03*
X1371703D03*
X1375403D03*
X1379103D03*
X1364303Y1087294D03*
Y1093703D03*
X1366154Y1084090D03*
Y1090498D03*
X1368003Y1087294D03*
Y1093703D03*
X1369854Y1084090D03*
Y1090498D03*
X1371703Y1087294D03*
Y1093703D03*
X1373554Y1084090D03*
Y1090498D03*
X1375403Y1087294D03*
Y1093703D03*
X1377254Y1084090D03*
Y1090498D03*
X1379103Y1087294D03*
Y1093703D03*
X1364303Y1100111D03*
Y1106520D03*
X1366154Y1096907D03*
Y1103316D03*
Y1109724D03*
X1368003Y1100111D03*
Y1106520D03*
X1369854Y1096907D03*
Y1103316D03*
Y1109724D03*
X1371703Y1100111D03*
Y1106520D03*
X1373554Y1096907D03*
Y1103316D03*
Y1109724D03*
X1375403Y1100111D03*
Y1106520D03*
X1377254Y1096907D03*
Y1103316D03*
Y1109724D03*
X1379103Y1100111D03*
Y1106520D03*
X1364303Y1112929D03*
X1368003D03*
X1371703D03*
X1375403D03*
X1379103D03*
X1364303Y1119337D03*
Y1125746D03*
X1366154Y1116133D03*
Y1122541D03*
Y1128950D03*
X1368003Y1119337D03*
Y1125746D03*
X1369854Y1116133D03*
Y1122541D03*
Y1128950D03*
X1371703Y1119337D03*
Y1125746D03*
X1373554Y1116133D03*
Y1122541D03*
Y1128950D03*
X1375403Y1119337D03*
Y1125746D03*
X1377254Y1116133D03*
Y1122541D03*
Y1128950D03*
X1379103Y1119337D03*
Y1125746D03*
X1364303Y1132154D03*
Y1138563D03*
X1366154Y1135359D03*
X1368003Y1132154D03*
Y1138563D03*
X1369854Y1135359D03*
X1371703Y1132154D03*
Y1138563D03*
X1373554Y1135359D03*
X1375403Y1132154D03*
Y1138563D03*
X1377254Y1135359D03*
X1379103Y1132154D03*
Y1138563D03*
X1384221Y843877D03*
X1387921D03*
X1391621D03*
X1395321D03*
X1380521D03*
X1382370Y847081D03*
X1384221Y850286D03*
X1386070Y847081D03*
X1387921Y850286D03*
X1389770Y847081D03*
X1391621Y850286D03*
X1393470Y847081D03*
X1395321Y850286D03*
X1380521D03*
X1382370Y853490D03*
Y859899D03*
Y866307D03*
X1384221Y856694D03*
Y863103D03*
X1386070Y853490D03*
Y859899D03*
Y866307D03*
X1387921Y856694D03*
Y863103D03*
X1389770Y853490D03*
Y859899D03*
Y866307D03*
X1391621Y856694D03*
Y863103D03*
X1393470Y853490D03*
Y859899D03*
Y866307D03*
X1395321Y856694D03*
Y863103D03*
X1380521Y856694D03*
Y863103D03*
X1382370Y872716D03*
X1384221Y869511D03*
X1386070Y872716D03*
X1387921Y869511D03*
X1389770Y872716D03*
X1391621Y869511D03*
X1393470Y872716D03*
X1395321Y869511D03*
X1380521D03*
X1382370Y879124D03*
X1384221Y875920D03*
Y882329D03*
X1386070Y879124D03*
X1387921Y875920D03*
Y882329D03*
X1389770Y879124D03*
X1391621Y875920D03*
Y882329D03*
X1393470Y879124D03*
X1395321Y875920D03*
Y882329D03*
X1380521Y875920D03*
Y882329D03*
X1382370Y885533D03*
Y891942D03*
Y898350D03*
X1384221Y888737D03*
Y895146D03*
Y901555D03*
X1386070Y885533D03*
Y891942D03*
Y898350D03*
X1387921Y888737D03*
Y895146D03*
Y901555D03*
X1389770Y885533D03*
Y891942D03*
Y898350D03*
X1391621Y888737D03*
Y895146D03*
Y901555D03*
X1393470Y885533D03*
Y891942D03*
Y898350D03*
X1395321Y888737D03*
Y895146D03*
Y901555D03*
X1380521Y888737D03*
Y895146D03*
Y901555D03*
X1382370Y904759D03*
Y911167D03*
Y917576D03*
X1384221Y907963D03*
Y914372D03*
X1386070Y904759D03*
Y911167D03*
Y917576D03*
X1387921Y907963D03*
Y914372D03*
X1389770Y904759D03*
Y911167D03*
Y917576D03*
X1391621Y907963D03*
Y914372D03*
X1393470Y904759D03*
Y911167D03*
Y917576D03*
X1395321Y907963D03*
Y914372D03*
X1380521Y907963D03*
Y914372D03*
X1382370Y923985D03*
X1384221Y920780D03*
X1386070Y923985D03*
X1387921Y920780D03*
X1389770Y923985D03*
X1391621Y920780D03*
X1393470Y923985D03*
X1395321Y920780D03*
X1380521D03*
X1382803Y1042434D03*
X1384654Y1039230D03*
Y1045639D03*
X1386503Y1042434D03*
X1388354Y1039230D03*
Y1045639D03*
X1390203Y1042434D03*
X1392054Y1039230D03*
Y1045639D03*
X1393903Y1042434D03*
X1395754Y1039230D03*
Y1045639D03*
X1380954Y1039230D03*
Y1045639D03*
X1382803Y1048842D03*
X1384654Y1052047D03*
X1386503Y1048842D03*
X1388354Y1052047D03*
X1390203Y1048842D03*
X1392054Y1052047D03*
X1393903Y1048842D03*
X1395754Y1052047D03*
X1380954D03*
X1382803Y1055251D03*
Y1061660D03*
X1384654Y1058455D03*
X1386503Y1055251D03*
Y1061660D03*
X1388354Y1058455D03*
X1390203Y1055251D03*
Y1061660D03*
X1392054Y1058455D03*
X1393903Y1055251D03*
Y1061660D03*
X1395754Y1058455D03*
X1380954D03*
X1382803Y1068068D03*
Y1074477D03*
X1384654Y1064864D03*
Y1071273D03*
Y1077681D03*
X1386503Y1068068D03*
Y1074477D03*
X1388354Y1064864D03*
Y1071273D03*
Y1077681D03*
X1390203Y1068068D03*
Y1074477D03*
X1392054Y1064864D03*
Y1071273D03*
Y1077681D03*
X1393903Y1068068D03*
Y1074477D03*
X1395754Y1064864D03*
Y1071273D03*
Y1077681D03*
X1380954Y1064864D03*
Y1071273D03*
Y1077681D03*
X1382803Y1080885D03*
X1386503D03*
X1390203D03*
X1393903D03*
X1382803Y1087294D03*
Y1093703D03*
X1384654Y1084090D03*
Y1090498D03*
X1386503Y1087294D03*
Y1093703D03*
X1388354Y1084090D03*
Y1090498D03*
X1390203Y1087294D03*
Y1093703D03*
X1392054Y1084090D03*
Y1090498D03*
X1393903Y1087294D03*
Y1093703D03*
X1395754Y1084090D03*
Y1090498D03*
X1380954Y1084090D03*
Y1090498D03*
X1382803Y1100111D03*
Y1106520D03*
X1384654Y1096907D03*
Y1103316D03*
Y1109724D03*
X1386503Y1100111D03*
Y1106520D03*
X1388354Y1096907D03*
Y1103316D03*
Y1109724D03*
X1390203Y1100111D03*
Y1106520D03*
X1392054Y1096907D03*
Y1103316D03*
Y1109724D03*
X1393903Y1100111D03*
Y1106520D03*
X1395754Y1096907D03*
Y1103316D03*
Y1109724D03*
X1380954Y1096907D03*
Y1103316D03*
Y1109724D03*
X1382803Y1112929D03*
X1386503D03*
X1390203D03*
X1393903D03*
X1382803Y1119337D03*
Y1125746D03*
X1384654Y1116133D03*
Y1122541D03*
Y1128950D03*
X1386503Y1119337D03*
Y1125746D03*
X1388354Y1116133D03*
Y1122541D03*
Y1128950D03*
X1390203Y1119337D03*
Y1125746D03*
X1392054Y1116133D03*
Y1122541D03*
Y1128950D03*
X1393903Y1119337D03*
Y1125746D03*
X1395754Y1116133D03*
Y1122541D03*
Y1128950D03*
X1380954Y1116133D03*
Y1122541D03*
Y1128950D03*
X1382803Y1132154D03*
Y1138563D03*
X1384654Y1135359D03*
X1386503Y1132154D03*
Y1138563D03*
X1388354Y1135359D03*
X1390203Y1132154D03*
Y1138563D03*
X1392054Y1135359D03*
X1393903Y1132154D03*
Y1138563D03*
X1395754Y1135359D03*
X1380954D03*
X1399021Y843877D03*
X1402721D03*
X1397170Y847081D03*
X1399021Y850286D03*
X1400870Y847081D03*
X1402721Y850286D03*
X1404570Y847081D03*
X1406421Y850286D03*
X1408270Y847081D03*
X1410121Y850286D03*
X1411971Y847081D03*
X1397170Y853490D03*
Y859899D03*
Y866307D03*
X1399021Y856694D03*
Y863103D03*
X1400870Y853490D03*
Y859899D03*
Y866307D03*
X1402721Y856694D03*
Y863103D03*
X1404570Y853490D03*
Y859899D03*
Y866307D03*
X1406421Y856694D03*
Y863103D03*
X1408270Y853490D03*
Y859899D03*
Y866307D03*
X1410121Y856694D03*
Y863103D03*
X1411971Y853490D03*
Y859899D03*
Y866307D03*
X1397170Y872716D03*
X1399021Y869511D03*
X1400870Y872716D03*
X1402721Y869511D03*
X1404570Y872716D03*
X1406421Y869511D03*
X1408270Y872716D03*
X1410121Y869511D03*
X1411971Y872716D03*
X1397170Y879124D03*
X1399021Y875920D03*
Y882329D03*
X1400870Y879124D03*
X1402721Y875920D03*
Y882329D03*
X1404570Y879124D03*
X1406421Y875920D03*
Y882329D03*
X1408270Y879124D03*
X1410121Y875920D03*
Y882329D03*
X1411971Y879124D03*
X1397170Y885533D03*
Y891942D03*
Y898350D03*
X1399021Y888737D03*
Y895146D03*
Y901555D03*
X1400870Y885533D03*
Y891942D03*
Y898350D03*
X1402721Y888737D03*
Y895146D03*
Y901555D03*
X1404570Y885533D03*
Y891942D03*
Y898350D03*
X1406421Y888737D03*
Y895146D03*
Y901555D03*
X1408270Y885533D03*
Y891942D03*
Y898350D03*
X1410121Y888737D03*
Y895146D03*
Y901555D03*
X1411971Y885533D03*
Y891942D03*
Y898350D03*
Y904759D03*
X1397170D03*
Y911167D03*
Y917576D03*
X1399021Y907963D03*
Y914372D03*
X1400870Y904759D03*
Y911167D03*
Y917576D03*
X1402721Y907963D03*
Y914372D03*
X1404570Y904759D03*
Y911167D03*
Y917576D03*
X1406421Y907963D03*
Y914372D03*
X1408270Y904759D03*
Y911167D03*
Y917576D03*
X1410121Y907963D03*
Y914372D03*
X1411971Y911167D03*
Y917576D03*
X1397170Y923985D03*
X1399021Y920780D03*
X1400870Y923985D03*
X1402721Y920780D03*
X1404570Y923985D03*
X1406421Y920780D03*
Y927189D03*
X1408270Y923985D03*
Y930393D03*
X1410121Y920780D03*
Y927189D03*
X1411971Y923985D03*
Y930393D03*
X1406421Y933598D03*
X1410121D03*
X1406421Y940006D03*
Y946414D03*
X1408270Y936801D03*
Y943210D03*
Y949619D03*
X1410121Y940006D03*
Y946414D03*
X1411971Y936801D03*
Y943210D03*
Y949619D03*
X1406421Y952823D03*
Y959232D03*
X1408270Y956027D03*
Y962436D03*
X1410121Y952823D03*
Y959232D03*
X1411971Y956027D03*
Y962436D03*
X1406421Y965640D03*
X1410121D03*
X1406421Y972049D03*
Y978457D03*
X1408270Y968845D03*
Y975253D03*
Y981662D03*
X1410121Y972049D03*
Y978457D03*
X1411971Y968845D03*
Y975253D03*
Y981662D03*
X1406421Y984866D03*
X1410121D03*
X1412403Y997574D03*
X1408703D03*
X1412403Y1003983D03*
Y1010391D03*
X1406853Y1000778D03*
Y1007187D03*
Y1013595D03*
X1408703Y1003983D03*
Y1010391D03*
X1410554Y1000778D03*
Y1007187D03*
Y1013595D03*
X1412403Y1016800D03*
X1406853Y1020004D03*
X1408703Y1016800D03*
X1410554Y1020004D03*
X1412403Y1023208D03*
Y1029617D03*
X1406853Y1026413D03*
X1408703Y1023208D03*
Y1029617D03*
X1410554Y1026413D03*
X1412403Y1036026D03*
Y1042434D03*
X1397603D03*
X1399454Y1039230D03*
Y1045639D03*
X1401303Y1042434D03*
X1403154Y1039230D03*
Y1045639D03*
X1405003Y1042434D03*
X1406853Y1032821D03*
Y1039230D03*
Y1045639D03*
X1408703Y1036026D03*
Y1042434D03*
X1410554Y1032821D03*
Y1039230D03*
Y1045639D03*
X1412403Y1048842D03*
X1397603D03*
X1399454Y1052047D03*
X1401303Y1048842D03*
X1403154Y1052047D03*
X1405003Y1048842D03*
X1406853Y1052047D03*
X1408703Y1048842D03*
X1410554Y1052047D03*
X1412403Y1055251D03*
Y1061660D03*
X1397603Y1055251D03*
Y1061660D03*
X1399454Y1058455D03*
X1401303Y1055251D03*
Y1061660D03*
X1403154Y1058455D03*
X1405003Y1055251D03*
Y1061660D03*
X1406853Y1058455D03*
X1408703Y1055251D03*
Y1061660D03*
X1410554Y1058455D03*
X1412403Y1068068D03*
Y1074477D03*
X1397603Y1068068D03*
Y1074477D03*
X1399454Y1064864D03*
Y1071273D03*
Y1077681D03*
X1401303Y1068068D03*
Y1074477D03*
X1403154Y1064864D03*
Y1071273D03*
Y1077681D03*
X1405003Y1068068D03*
Y1074477D03*
X1406853Y1064864D03*
Y1071273D03*
Y1077681D03*
X1408703Y1068068D03*
Y1074477D03*
X1410554Y1064864D03*
Y1071273D03*
Y1077681D03*
X1412403Y1080885D03*
X1397603D03*
X1401303D03*
X1405003D03*
X1408703D03*
X1412403Y1087294D03*
Y1093703D03*
X1397603Y1087294D03*
Y1093703D03*
X1399454Y1084090D03*
Y1090498D03*
X1401303Y1087294D03*
Y1093703D03*
X1403154Y1084090D03*
Y1090498D03*
X1405003Y1087294D03*
Y1093703D03*
X1406853Y1084090D03*
Y1090498D03*
X1408703Y1087294D03*
Y1093703D03*
X1410554Y1084090D03*
Y1090498D03*
X1412403Y1100111D03*
Y1106520D03*
X1397603Y1100111D03*
Y1106520D03*
X1399454Y1096907D03*
Y1103316D03*
Y1109724D03*
X1401303Y1100111D03*
Y1106520D03*
X1403154Y1096907D03*
Y1103316D03*
Y1109724D03*
X1405003Y1100111D03*
Y1106520D03*
X1406853Y1096907D03*
Y1103316D03*
Y1109724D03*
X1408703Y1100111D03*
Y1106520D03*
X1410554Y1096907D03*
Y1103316D03*
Y1109724D03*
X1412403Y1112929D03*
X1397603D03*
X1401303D03*
X1405003D03*
X1408703D03*
X1412403Y1119337D03*
Y1125746D03*
X1397603Y1119337D03*
Y1125746D03*
X1399454Y1116133D03*
Y1122541D03*
Y1128950D03*
X1401303Y1119337D03*
Y1125746D03*
X1403154Y1116133D03*
Y1122541D03*
Y1128950D03*
X1405003Y1119337D03*
Y1125746D03*
X1406853Y1116133D03*
Y1122541D03*
Y1128950D03*
X1408703Y1119337D03*
Y1125746D03*
X1410554Y1116133D03*
Y1122541D03*
Y1128950D03*
X1412403Y1132154D03*
X1397603D03*
Y1138563D03*
X1399454Y1135359D03*
X1401303Y1132154D03*
Y1138563D03*
X1403154Y1135359D03*
X1405003Y1132154D03*
Y1138563D03*
X1406853Y1135359D03*
X1408703Y1132154D03*
X1410554Y1135359D03*
X1428621Y843877D03*
X1413821Y850286D03*
X1415670Y847081D03*
X1417521Y850286D03*
X1419370Y847081D03*
X1421221Y850286D03*
X1423070Y847081D03*
X1424921Y850286D03*
X1426771Y847081D03*
X1428621Y850286D03*
X1413821Y856694D03*
Y863103D03*
X1415670Y853490D03*
Y859899D03*
Y866307D03*
X1417521Y856694D03*
Y863103D03*
X1419370Y853490D03*
Y859899D03*
Y866307D03*
X1421221Y856694D03*
Y863103D03*
X1423070Y853490D03*
Y859899D03*
Y866307D03*
X1424921Y856694D03*
Y863103D03*
X1426771Y853490D03*
Y859899D03*
Y866307D03*
X1428621Y856694D03*
Y863103D03*
X1413821Y869511D03*
X1415670Y872716D03*
X1417521Y869511D03*
X1419370Y872716D03*
X1421221Y869511D03*
X1423070Y872716D03*
X1424921Y869511D03*
X1426771Y872716D03*
X1428621Y869511D03*
X1413821Y875920D03*
Y882329D03*
X1415670Y879124D03*
X1417521Y875920D03*
Y882329D03*
X1419370Y879124D03*
X1421221Y875920D03*
Y882329D03*
X1423070Y879124D03*
X1424921Y875920D03*
Y882329D03*
X1426771Y879124D03*
X1428621Y875920D03*
Y882329D03*
X1413821Y888737D03*
Y895146D03*
Y901555D03*
X1415670Y885533D03*
Y891942D03*
Y898350D03*
X1417521Y888737D03*
Y895146D03*
Y901555D03*
X1419370Y885533D03*
Y891942D03*
Y898350D03*
X1421221Y888737D03*
Y895146D03*
Y901555D03*
X1423070Y885533D03*
Y891942D03*
Y898350D03*
X1424921Y888737D03*
Y895146D03*
Y901555D03*
X1426771Y885533D03*
Y891942D03*
Y898350D03*
X1428621Y888737D03*
Y895146D03*
Y901555D03*
X1413821Y907963D03*
Y914372D03*
X1415670Y904759D03*
Y911167D03*
Y917576D03*
X1417521Y907963D03*
Y914372D03*
X1419370Y904759D03*
Y911167D03*
Y917576D03*
X1421221Y907963D03*
Y914372D03*
X1423070Y904759D03*
Y911167D03*
Y917576D03*
X1424921Y907963D03*
Y914372D03*
X1426771Y904759D03*
Y911167D03*
Y917576D03*
X1428621Y907963D03*
Y914372D03*
X1413821Y920780D03*
Y927189D03*
X1415670Y923985D03*
Y930393D03*
X1417521Y920780D03*
Y927189D03*
X1419370Y923985D03*
Y930393D03*
X1421221Y920780D03*
Y927189D03*
X1423070Y923985D03*
Y930393D03*
X1424921Y920780D03*
Y927189D03*
X1426771Y923985D03*
Y930393D03*
X1428621Y920780D03*
X1413821Y933598D03*
X1417521D03*
X1421221D03*
X1424921D03*
X1413821Y940006D03*
Y946414D03*
X1415670Y936801D03*
Y943210D03*
Y949619D03*
X1417521Y940006D03*
Y946414D03*
X1419370Y936801D03*
Y943210D03*
Y949619D03*
X1421221Y940006D03*
Y946414D03*
X1423070Y936801D03*
Y943210D03*
Y949619D03*
X1424921Y940006D03*
Y946414D03*
X1426771Y936801D03*
Y943210D03*
Y949619D03*
X1413821Y952823D03*
Y959232D03*
X1415670Y956027D03*
Y962436D03*
X1417521Y952823D03*
Y959232D03*
X1419370Y956027D03*
Y962436D03*
X1421221Y952823D03*
Y959232D03*
X1423070Y956027D03*
Y962436D03*
X1424921Y952823D03*
Y959232D03*
X1426771Y956027D03*
Y962436D03*
X1413821Y965640D03*
X1417521D03*
X1421221D03*
X1424921D03*
X1413821Y972049D03*
Y978457D03*
X1415670Y968845D03*
Y975253D03*
Y981662D03*
X1417521Y972049D03*
Y978457D03*
X1419370Y968845D03*
Y975253D03*
Y981662D03*
X1421221Y972049D03*
Y978457D03*
X1423070Y968845D03*
Y975253D03*
Y981662D03*
X1424921Y972049D03*
Y978457D03*
X1426771Y968845D03*
Y975253D03*
Y981662D03*
X1413821Y984866D03*
X1417521D03*
X1421221D03*
X1424921D03*
X1416103Y997574D03*
X1419803D03*
X1423503D03*
X1427203D03*
X1414254Y1000778D03*
Y1007187D03*
Y1013595D03*
X1416103Y1003983D03*
Y1010391D03*
X1417954Y1000778D03*
Y1007187D03*
Y1013595D03*
X1419803Y1003983D03*
Y1010391D03*
X1421653Y1000778D03*
Y1007187D03*
Y1013595D03*
X1423503Y1003983D03*
Y1010391D03*
X1425354Y1000778D03*
Y1007187D03*
Y1013595D03*
X1427203Y1003983D03*
Y1010391D03*
X1414254Y1020004D03*
X1416103Y1016800D03*
X1417954Y1020004D03*
X1419803Y1016800D03*
X1421653Y1020004D03*
X1423503Y1016800D03*
X1425354Y1020004D03*
X1427203Y1016800D03*
X1414254Y1026413D03*
X1416103Y1023208D03*
Y1029617D03*
X1417954Y1026413D03*
X1419803Y1023208D03*
Y1029617D03*
X1421653Y1026413D03*
X1423503Y1023208D03*
Y1029617D03*
X1425354Y1026413D03*
X1427203Y1023208D03*
Y1029617D03*
X1414254Y1032821D03*
Y1039230D03*
Y1045639D03*
X1416103Y1036026D03*
Y1042434D03*
X1417954Y1032821D03*
Y1039230D03*
Y1045639D03*
X1419803Y1036026D03*
Y1042434D03*
X1421653Y1032821D03*
Y1039230D03*
Y1045639D03*
X1423503Y1036026D03*
Y1042434D03*
X1425354Y1032821D03*
Y1039230D03*
Y1045639D03*
X1427203Y1036026D03*
Y1042434D03*
X1414254Y1052047D03*
X1416103Y1048842D03*
X1417954Y1052047D03*
X1419803Y1048842D03*
X1421653Y1052047D03*
X1423503Y1048842D03*
X1425354Y1052047D03*
X1427203Y1048842D03*
X1414254Y1058455D03*
X1416103Y1055251D03*
Y1061660D03*
X1417954Y1058455D03*
X1419803Y1055251D03*
Y1061660D03*
X1421653Y1058455D03*
X1423503Y1055251D03*
Y1061660D03*
X1425354Y1058455D03*
X1427203Y1055251D03*
Y1061660D03*
X1414254Y1064864D03*
Y1071273D03*
Y1077681D03*
X1416103Y1068068D03*
Y1074477D03*
X1417954Y1064864D03*
Y1071273D03*
Y1077681D03*
X1419803Y1068068D03*
Y1074477D03*
X1421653Y1064864D03*
Y1071273D03*
Y1077681D03*
X1423503Y1068068D03*
Y1074477D03*
X1425354Y1064864D03*
Y1071273D03*
Y1077681D03*
X1427203Y1068068D03*
Y1074477D03*
X1416103Y1080885D03*
X1419803D03*
X1423503D03*
X1427203D03*
X1414254Y1084090D03*
Y1090498D03*
X1416103Y1087294D03*
Y1093703D03*
X1417954Y1084090D03*
Y1090498D03*
X1419803Y1087294D03*
Y1093703D03*
X1421653Y1084090D03*
Y1090498D03*
X1423503Y1087294D03*
Y1093703D03*
X1425354Y1084090D03*
Y1090498D03*
X1427203Y1087294D03*
Y1093703D03*
X1414254Y1096907D03*
Y1103316D03*
Y1109724D03*
X1416103Y1100111D03*
Y1106520D03*
X1417954Y1096907D03*
Y1103316D03*
Y1109724D03*
X1419803Y1100111D03*
Y1106520D03*
X1421653Y1096907D03*
Y1103316D03*
Y1109724D03*
X1423503Y1100111D03*
Y1106520D03*
X1425354Y1096907D03*
Y1103316D03*
Y1109724D03*
X1427203Y1100111D03*
Y1106520D03*
X1416103Y1112929D03*
X1419803D03*
X1423503D03*
X1427203D03*
X1414254Y1116133D03*
Y1122541D03*
Y1128950D03*
X1416103Y1119337D03*
Y1125746D03*
X1417954Y1116133D03*
Y1122541D03*
Y1128950D03*
X1419803Y1119337D03*
Y1125746D03*
X1421653Y1116133D03*
Y1122541D03*
Y1128950D03*
X1423503Y1119337D03*
Y1125746D03*
X1425354Y1116133D03*
Y1122541D03*
Y1128950D03*
X1427203Y1119337D03*
Y1125746D03*
X1414254Y1135359D03*
X1416103Y1132154D03*
X1417954Y1135359D03*
X1419803Y1132154D03*
X1421653Y1135359D03*
X1423503Y1132154D03*
X1425354Y1135359D03*
X1427203Y1132154D03*
X1443421Y843877D03*
X1432321D03*
X1436021D03*
X1439721D03*
X1443421Y850286D03*
X1430470Y847081D03*
X1432321Y850286D03*
X1434170Y847081D03*
X1436021Y850286D03*
X1437870Y847081D03*
X1439721Y850286D03*
X1441570Y847081D03*
X1443421Y856694D03*
Y863103D03*
X1430470Y853490D03*
Y859899D03*
Y866307D03*
X1432321Y856694D03*
Y863103D03*
X1434170Y853490D03*
Y859899D03*
Y866307D03*
X1436021Y856694D03*
Y863103D03*
X1437870Y853490D03*
Y859899D03*
Y866307D03*
X1439721Y856694D03*
Y863103D03*
X1441570Y853490D03*
Y859899D03*
Y866307D03*
X1443421Y869511D03*
X1430470Y872716D03*
X1432321Y869511D03*
X1434170Y872716D03*
X1436021Y869511D03*
X1437870Y872716D03*
X1439721Y869511D03*
X1441570Y872716D03*
X1443421Y875920D03*
Y882329D03*
X1430470Y879124D03*
X1432321Y875920D03*
Y882329D03*
X1434170Y879124D03*
X1436021Y875920D03*
Y882329D03*
X1437870Y879124D03*
X1439721Y875920D03*
Y882329D03*
X1441570Y879124D03*
X1443421Y888737D03*
Y895146D03*
Y901555D03*
X1430470Y885533D03*
Y891942D03*
Y898350D03*
X1432321Y888737D03*
Y895146D03*
Y901555D03*
X1434170Y885533D03*
Y891942D03*
Y898350D03*
X1436021Y888737D03*
Y895146D03*
Y901555D03*
X1437870Y885533D03*
Y891942D03*
Y898350D03*
X1439721Y888737D03*
Y895146D03*
Y901555D03*
X1441570Y885533D03*
Y891942D03*
Y898350D03*
X1443421Y907963D03*
Y914372D03*
X1430470Y904759D03*
Y911167D03*
Y917576D03*
X1432321Y907963D03*
Y914372D03*
X1434170Y904759D03*
Y911167D03*
Y917576D03*
X1436021Y907963D03*
Y914372D03*
X1437870Y904759D03*
Y911167D03*
Y917576D03*
X1439721Y907963D03*
Y914372D03*
X1441570Y904759D03*
Y911167D03*
Y917576D03*
X1443421Y920780D03*
X1430470Y923985D03*
X1432321Y920780D03*
X1434170Y923985D03*
X1436021Y920780D03*
X1437870Y923985D03*
X1439721Y920780D03*
X1441570Y923985D03*
X1443854Y1039230D03*
Y1045639D03*
X1429054Y1039230D03*
Y1045639D03*
X1430903Y1042434D03*
X1432754Y1039230D03*
Y1045639D03*
X1434603Y1042434D03*
X1436454Y1039230D03*
Y1045639D03*
X1438303Y1042434D03*
X1440154Y1039230D03*
Y1045639D03*
X1442003Y1042434D03*
X1443854Y1052047D03*
X1429054D03*
X1430903Y1048842D03*
X1432754Y1052047D03*
X1434603Y1048842D03*
X1436454Y1052047D03*
X1438303Y1048842D03*
X1440154Y1052047D03*
X1442003Y1048842D03*
Y1055251D03*
X1443854Y1058455D03*
X1429054D03*
X1430903Y1055251D03*
Y1061660D03*
X1432754Y1058455D03*
X1434603Y1055251D03*
Y1061660D03*
X1436454Y1058455D03*
X1438303Y1055251D03*
Y1061660D03*
X1440154Y1058455D03*
X1442003Y1061660D03*
X1443854Y1064864D03*
Y1071273D03*
Y1077681D03*
X1429054Y1064864D03*
Y1071273D03*
Y1077681D03*
X1430903Y1068068D03*
Y1074477D03*
X1432754Y1064864D03*
Y1071273D03*
Y1077681D03*
X1434603Y1068068D03*
Y1074477D03*
X1436454Y1064864D03*
Y1071273D03*
Y1077681D03*
X1438303Y1068068D03*
Y1074477D03*
X1440154Y1064864D03*
Y1071273D03*
Y1077681D03*
X1442003Y1068068D03*
Y1074477D03*
X1430903Y1080885D03*
X1434603D03*
X1438303D03*
X1442003D03*
X1443854Y1084090D03*
Y1090498D03*
X1429054Y1084090D03*
Y1090498D03*
X1430903Y1087294D03*
Y1093703D03*
X1432754Y1084090D03*
Y1090498D03*
X1434603Y1087294D03*
Y1093703D03*
X1436454Y1084090D03*
Y1090498D03*
X1438303Y1087294D03*
Y1093703D03*
X1440154Y1084090D03*
Y1090498D03*
X1442003Y1087294D03*
Y1093703D03*
X1443854Y1096907D03*
Y1103316D03*
Y1109724D03*
X1429054Y1096907D03*
Y1103316D03*
Y1109724D03*
X1430903Y1100111D03*
Y1106520D03*
X1432754Y1096907D03*
Y1103316D03*
Y1109724D03*
X1434603Y1100111D03*
Y1106520D03*
X1436454Y1096907D03*
Y1103316D03*
Y1109724D03*
X1438303Y1100111D03*
Y1106520D03*
X1440154Y1096907D03*
Y1103316D03*
Y1109724D03*
X1442003Y1100111D03*
Y1106520D03*
Y1112929D03*
X1430903D03*
X1434603D03*
X1438303D03*
X1443854Y1116133D03*
Y1122541D03*
Y1128950D03*
X1429054Y1116133D03*
Y1122541D03*
Y1128950D03*
X1430903Y1119337D03*
Y1125746D03*
X1432754Y1116133D03*
Y1122541D03*
Y1128950D03*
X1434603Y1119337D03*
Y1125746D03*
X1436454Y1116133D03*
Y1122541D03*
Y1128950D03*
X1438303Y1119337D03*
Y1125746D03*
X1440154Y1116133D03*
Y1122541D03*
Y1128950D03*
X1442003Y1119337D03*
Y1125746D03*
X1443854Y1135359D03*
X1429054D03*
X1430903Y1132154D03*
Y1138563D03*
X1432754Y1135359D03*
X1434603Y1132154D03*
Y1138563D03*
X1436454Y1135359D03*
X1438303Y1132154D03*
Y1138563D03*
X1440154Y1135359D03*
X1442003Y1132154D03*
Y1138563D03*
X1447121Y843877D03*
X1450821D03*
X1454521D03*
X1458221D03*
X1445270Y847081D03*
X1447121Y850286D03*
X1448970Y847081D03*
X1450821Y850286D03*
X1452670Y847081D03*
X1454521Y850286D03*
X1456370Y847081D03*
X1458221Y850286D03*
X1460070Y847081D03*
X1445270Y853490D03*
Y859899D03*
Y866307D03*
X1447121Y856694D03*
Y863103D03*
X1448970Y853490D03*
Y859899D03*
Y866307D03*
X1450821Y856694D03*
Y863103D03*
X1452670Y853490D03*
Y859899D03*
Y866307D03*
X1454521Y856694D03*
Y863103D03*
X1456370Y853490D03*
Y859899D03*
Y866307D03*
X1458221Y856694D03*
Y863103D03*
X1460070Y853490D03*
Y859899D03*
Y866307D03*
X1445270Y872716D03*
X1447121Y869511D03*
X1448970Y872716D03*
X1450821Y869511D03*
X1452670Y872716D03*
X1454521Y869511D03*
X1456370Y872716D03*
X1458221Y869511D03*
X1460070Y872716D03*
X1445270Y879124D03*
X1447121Y875920D03*
Y882329D03*
X1448970Y879124D03*
X1450821Y875920D03*
Y882329D03*
X1452670Y879124D03*
X1454521Y875920D03*
Y882329D03*
X1456370Y879124D03*
X1458221Y875920D03*
Y882329D03*
X1460070Y879124D03*
X1445270Y885533D03*
Y891942D03*
Y898350D03*
X1447121Y888737D03*
Y895146D03*
Y901555D03*
X1448970Y885533D03*
Y891942D03*
Y898350D03*
X1450821Y888737D03*
Y895146D03*
Y901555D03*
X1452670Y885533D03*
Y891942D03*
Y898350D03*
X1454521Y888737D03*
Y895146D03*
Y901555D03*
X1456370Y885533D03*
Y891942D03*
Y898350D03*
X1458221Y888737D03*
Y895146D03*
Y901555D03*
X1460070Y885533D03*
Y891942D03*
Y898350D03*
X1445270Y904759D03*
Y911167D03*
Y917576D03*
X1447121Y907963D03*
Y914372D03*
X1448970Y904759D03*
Y911167D03*
Y917576D03*
X1450821Y907963D03*
Y914372D03*
X1452670Y904759D03*
Y911167D03*
Y917576D03*
X1454521Y907963D03*
Y914372D03*
X1456370Y904759D03*
Y911167D03*
Y917576D03*
X1458221Y907963D03*
Y914372D03*
X1460070Y904759D03*
Y911167D03*
Y917576D03*
X1445270Y923985D03*
X1447121Y920780D03*
X1448970Y923985D03*
X1450821Y920780D03*
X1452670Y923985D03*
X1454521Y920780D03*
Y927189D03*
X1456370Y923985D03*
Y930393D03*
X1458221Y920780D03*
Y927189D03*
X1460070Y923985D03*
Y930393D03*
X1454521Y933598D03*
X1458221D03*
X1454521Y940006D03*
Y946414D03*
X1456370Y936801D03*
Y943210D03*
Y949619D03*
X1458221Y940006D03*
Y946414D03*
X1460070Y936801D03*
Y943210D03*
Y949619D03*
X1454521Y952823D03*
Y959232D03*
X1456370Y956027D03*
Y962436D03*
X1458221Y952823D03*
Y959232D03*
X1460070Y956027D03*
Y962436D03*
X1454521Y965640D03*
X1458221D03*
X1454521Y972049D03*
Y978457D03*
X1456370Y968845D03*
Y975253D03*
Y981662D03*
X1458221Y972049D03*
Y978457D03*
X1460070Y968845D03*
Y975253D03*
Y981662D03*
X1454521Y984866D03*
X1458221D03*
X1456803Y997574D03*
X1460503D03*
X1454954Y1000778D03*
Y1007187D03*
Y1013595D03*
X1456803Y1003983D03*
Y1010391D03*
X1458654Y1000778D03*
Y1007187D03*
Y1013595D03*
X1460503Y1003983D03*
Y1010391D03*
X1454954Y1020004D03*
X1456803Y1016800D03*
X1458654Y1020004D03*
X1460503Y1016800D03*
X1454954Y1026413D03*
X1456803Y1023208D03*
Y1029617D03*
X1458654Y1026413D03*
X1460503Y1023208D03*
Y1029617D03*
X1445703Y1042434D03*
X1447554Y1039230D03*
Y1045639D03*
X1449403Y1042434D03*
X1451254Y1039230D03*
Y1045639D03*
X1453103Y1042434D03*
X1454954Y1032821D03*
Y1039230D03*
Y1045639D03*
X1456803Y1036026D03*
Y1042434D03*
X1458654Y1032821D03*
Y1039230D03*
Y1045639D03*
X1460503Y1036026D03*
Y1042434D03*
X1445703Y1048842D03*
X1447554Y1052047D03*
X1449403Y1048842D03*
X1451254Y1052047D03*
X1453103Y1048842D03*
X1454954Y1052047D03*
X1456803Y1048842D03*
X1458654Y1052047D03*
X1460503Y1048842D03*
X1445703Y1055251D03*
Y1061660D03*
X1447554Y1058455D03*
X1449403Y1055251D03*
Y1061660D03*
X1451254Y1058455D03*
X1453103Y1055251D03*
Y1061660D03*
X1454954Y1058455D03*
X1456803Y1055251D03*
Y1061660D03*
X1458654Y1058455D03*
X1460503Y1055251D03*
Y1061660D03*
X1445703Y1068068D03*
Y1074477D03*
X1447554Y1064864D03*
Y1071273D03*
Y1077681D03*
X1449403Y1068068D03*
Y1074477D03*
X1451254Y1064864D03*
Y1071273D03*
Y1077681D03*
X1453103Y1068068D03*
Y1074477D03*
X1454954Y1064864D03*
Y1071273D03*
Y1077681D03*
X1456803Y1068068D03*
Y1074477D03*
X1458654Y1064864D03*
Y1071273D03*
Y1077681D03*
X1460503Y1068068D03*
Y1074477D03*
X1445703Y1080885D03*
X1449403D03*
X1453103D03*
X1456803D03*
X1460503D03*
X1445703Y1087294D03*
Y1093703D03*
X1447554Y1084090D03*
Y1090498D03*
X1449403Y1087294D03*
Y1093703D03*
X1451254Y1084090D03*
Y1090498D03*
X1453103Y1087294D03*
Y1093703D03*
X1454954Y1084090D03*
Y1090498D03*
X1456803Y1087294D03*
Y1093703D03*
X1458654Y1084090D03*
Y1090498D03*
X1460503Y1087294D03*
Y1093703D03*
X1445703Y1100111D03*
Y1106520D03*
X1447554Y1096907D03*
Y1103316D03*
Y1109724D03*
X1449403Y1100111D03*
Y1106520D03*
X1451254Y1096907D03*
Y1103316D03*
Y1109724D03*
X1453103Y1100111D03*
Y1106520D03*
X1454954Y1096907D03*
Y1103316D03*
Y1109724D03*
X1456803Y1100111D03*
Y1106520D03*
X1458654Y1096907D03*
Y1103316D03*
Y1109724D03*
X1460503Y1100111D03*
Y1106520D03*
X1445703Y1112929D03*
X1449403D03*
X1453103D03*
X1456803D03*
X1460503D03*
X1445703Y1119337D03*
Y1125746D03*
X1447554Y1116133D03*
Y1122541D03*
Y1128950D03*
X1449403Y1119337D03*
Y1125746D03*
X1451254Y1116133D03*
Y1122541D03*
Y1128950D03*
X1453103Y1119337D03*
Y1125746D03*
X1454954Y1116133D03*
Y1122541D03*
Y1128950D03*
X1456803Y1119337D03*
Y1125746D03*
X1458654Y1116133D03*
Y1122541D03*
Y1128950D03*
X1460503Y1119337D03*
Y1125746D03*
X1445703Y1132154D03*
Y1138563D03*
X1447554Y1135359D03*
X1449403Y1132154D03*
Y1138563D03*
X1451254Y1135359D03*
X1453103Y1132154D03*
Y1138563D03*
X1454954Y1135359D03*
X1456803Y1132154D03*
Y1138563D03*
X1458654Y1135359D03*
X1460503Y1132154D03*
Y1138563D03*
X1473021Y843877D03*
X1476721D03*
X1461921D03*
X1465621D03*
X1469321D03*
X1473021Y850286D03*
X1474870Y847081D03*
X1476721Y850286D03*
X1461921D03*
X1463770Y847081D03*
X1465621Y850286D03*
X1467470Y847081D03*
X1469321Y850286D03*
X1471170Y847081D03*
X1473021Y856694D03*
Y863103D03*
X1474870Y853490D03*
Y859899D03*
Y866307D03*
X1476721Y856694D03*
Y863103D03*
X1461921Y856694D03*
Y863103D03*
X1463770Y853490D03*
Y859899D03*
Y866307D03*
X1465621Y856694D03*
Y863103D03*
X1467470Y853490D03*
Y859899D03*
Y866307D03*
X1469321Y856694D03*
Y863103D03*
X1471170Y853490D03*
Y859899D03*
Y866307D03*
X1473021Y869511D03*
X1474870Y872716D03*
X1476721Y869511D03*
X1461921D03*
X1463770Y872716D03*
X1465621Y869511D03*
X1467470Y872716D03*
X1469321Y869511D03*
X1471170Y872716D03*
X1473021Y875920D03*
Y882329D03*
X1474870Y879124D03*
X1476721Y875920D03*
Y882329D03*
X1461921Y875920D03*
Y882329D03*
X1463770Y879124D03*
X1465621Y875920D03*
Y882329D03*
X1467470Y879124D03*
X1469321Y875920D03*
Y882329D03*
X1471170Y879124D03*
X1473021Y888737D03*
Y895146D03*
Y901555D03*
X1474870Y885533D03*
Y891942D03*
Y898350D03*
X1476721Y888737D03*
Y895146D03*
Y901555D03*
X1461921Y888737D03*
Y895146D03*
Y901555D03*
X1463770Y885533D03*
Y891942D03*
Y898350D03*
X1465621Y888737D03*
Y895146D03*
Y901555D03*
X1467470Y885533D03*
Y891942D03*
Y898350D03*
X1469321Y888737D03*
Y895146D03*
Y901555D03*
X1471170Y885533D03*
Y891942D03*
Y898350D03*
X1473021Y907963D03*
Y914372D03*
X1474870Y904759D03*
Y911167D03*
Y917576D03*
X1476721Y907963D03*
Y914372D03*
X1461921Y907963D03*
Y914372D03*
X1463770Y904759D03*
Y911167D03*
Y917576D03*
X1465621Y907963D03*
Y914372D03*
X1467470Y904759D03*
Y911167D03*
Y917576D03*
X1469321Y907963D03*
Y914372D03*
X1471170Y904759D03*
Y911167D03*
Y917576D03*
X1473021Y920780D03*
Y927189D03*
X1474870Y923985D03*
Y930393D03*
X1476721Y920780D03*
Y927189D03*
X1461921Y920780D03*
Y927189D03*
X1463770Y923985D03*
Y930393D03*
X1465621Y920780D03*
Y927189D03*
X1467470Y923985D03*
Y930393D03*
X1469321Y920780D03*
Y927189D03*
X1471170Y923985D03*
Y930393D03*
X1473021Y933598D03*
X1476721D03*
X1461921D03*
X1465621D03*
X1469321D03*
X1473021Y940006D03*
Y946414D03*
X1474870Y936801D03*
Y943210D03*
Y949619D03*
X1476721Y940006D03*
Y946414D03*
X1461921Y940006D03*
Y946414D03*
X1463770Y936801D03*
Y943210D03*
Y949619D03*
X1465621Y940006D03*
Y946414D03*
X1467470Y936801D03*
Y943210D03*
Y949619D03*
X1469321Y940006D03*
Y946414D03*
X1471170Y936801D03*
Y943210D03*
Y949619D03*
X1473021Y952823D03*
Y959232D03*
X1474870Y956027D03*
Y962436D03*
X1476721Y952823D03*
Y959232D03*
X1461921Y952823D03*
Y959232D03*
X1463770Y956027D03*
Y962436D03*
X1465621Y952823D03*
Y959232D03*
X1467470Y956027D03*
Y962436D03*
X1469321Y952823D03*
Y959232D03*
X1471170Y956027D03*
Y962436D03*
X1473021Y965640D03*
X1476721D03*
X1461921D03*
X1465621D03*
X1469321D03*
X1473021Y972049D03*
Y978457D03*
X1474870Y968845D03*
Y975253D03*
Y981662D03*
X1476721Y972049D03*
Y978457D03*
X1461921Y972049D03*
Y978457D03*
X1463770Y968845D03*
Y975253D03*
Y981662D03*
X1465621Y972049D03*
Y978457D03*
X1467470Y968845D03*
Y975253D03*
Y981662D03*
X1469321Y972049D03*
Y978457D03*
X1471170Y968845D03*
Y975253D03*
Y981662D03*
X1473021Y984866D03*
X1476721D03*
X1461921D03*
X1465621D03*
X1469321D03*
X1475303Y997574D03*
X1464203D03*
X1467903D03*
X1471603D03*
X1473454Y1000778D03*
Y1007187D03*
Y1013595D03*
X1475303Y1003983D03*
Y1010391D03*
X1477154Y1000778D03*
Y1007187D03*
Y1013595D03*
X1462354Y1000778D03*
Y1007187D03*
Y1013595D03*
X1464203Y1003983D03*
Y1010391D03*
X1466054Y1000778D03*
Y1007187D03*
Y1013595D03*
X1467903Y1003983D03*
Y1010391D03*
X1469754Y1000778D03*
Y1007187D03*
Y1013595D03*
X1471603Y1003983D03*
Y1010391D03*
X1473454Y1020004D03*
X1475303Y1016800D03*
X1477154Y1020004D03*
X1462354D03*
X1464203Y1016800D03*
X1466054Y1020004D03*
X1467903Y1016800D03*
X1469754Y1020004D03*
X1471603Y1016800D03*
X1473454Y1026413D03*
X1475303Y1023208D03*
Y1029617D03*
X1477154Y1026413D03*
X1462354D03*
X1464203Y1023208D03*
Y1029617D03*
X1466054Y1026413D03*
X1467903Y1023208D03*
Y1029617D03*
X1469754Y1026413D03*
X1471603Y1023208D03*
Y1029617D03*
X1473454Y1032821D03*
Y1039230D03*
Y1045639D03*
X1475303Y1036026D03*
Y1042434D03*
X1477154Y1032821D03*
Y1039230D03*
Y1045639D03*
X1462354Y1032821D03*
Y1039230D03*
Y1045639D03*
X1464203Y1036026D03*
Y1042434D03*
X1466054Y1032821D03*
Y1039230D03*
Y1045639D03*
X1467903Y1036026D03*
Y1042434D03*
X1469754Y1032821D03*
Y1039230D03*
Y1045639D03*
X1471603Y1036026D03*
Y1042434D03*
X1473454Y1052047D03*
X1475303Y1048842D03*
X1477154Y1052047D03*
X1462354D03*
X1464203Y1048842D03*
X1466054Y1052047D03*
X1467903Y1048842D03*
X1469754Y1052047D03*
X1471603Y1048842D03*
X1473454Y1058455D03*
X1475303Y1055251D03*
Y1061660D03*
X1477154Y1058455D03*
X1462354D03*
X1464203Y1055251D03*
Y1061660D03*
X1466054Y1058455D03*
X1467903Y1055251D03*
Y1061660D03*
X1469754Y1058455D03*
X1471603Y1055251D03*
Y1061660D03*
X1473454Y1064864D03*
Y1071273D03*
Y1077681D03*
X1475303Y1068068D03*
Y1074477D03*
X1477154Y1064864D03*
Y1071273D03*
Y1077681D03*
X1462354Y1064864D03*
Y1071273D03*
Y1077681D03*
X1464203Y1068068D03*
Y1074477D03*
X1466054Y1064864D03*
Y1071273D03*
Y1077681D03*
X1467903Y1068068D03*
Y1074477D03*
X1469754Y1064864D03*
Y1071273D03*
Y1077681D03*
X1471603Y1068068D03*
Y1074477D03*
X1475303Y1080885D03*
X1464203D03*
X1467903D03*
X1471603D03*
X1473454Y1084090D03*
Y1090498D03*
X1475303Y1087294D03*
Y1093703D03*
X1477154Y1084090D03*
Y1090498D03*
X1462354Y1084090D03*
Y1090498D03*
X1464203Y1087294D03*
Y1093703D03*
X1466054Y1084090D03*
Y1090498D03*
X1467903Y1087294D03*
Y1093703D03*
X1469754Y1084090D03*
Y1090498D03*
X1471603Y1087294D03*
Y1093703D03*
X1473454Y1096907D03*
Y1103316D03*
Y1109724D03*
X1475303Y1100111D03*
Y1106520D03*
X1477154Y1096907D03*
Y1103316D03*
Y1109724D03*
X1462354Y1096907D03*
Y1103316D03*
Y1109724D03*
X1464203Y1100111D03*
Y1106520D03*
X1466054Y1096907D03*
Y1103316D03*
Y1109724D03*
X1467903Y1100111D03*
Y1106520D03*
X1469754Y1096907D03*
Y1103316D03*
Y1109724D03*
X1471603Y1100111D03*
Y1106520D03*
X1475303Y1112929D03*
X1464203D03*
X1467903D03*
X1471603D03*
X1473454Y1116133D03*
Y1122541D03*
Y1128950D03*
X1475303Y1119337D03*
Y1125746D03*
X1477154Y1116133D03*
Y1122541D03*
Y1128950D03*
X1462354Y1116133D03*
Y1122541D03*
Y1128950D03*
X1464203Y1119337D03*
Y1125746D03*
X1466054Y1116133D03*
Y1122541D03*
Y1128950D03*
X1467903Y1119337D03*
Y1125746D03*
X1469754Y1116133D03*
Y1122541D03*
Y1128950D03*
X1471603Y1119337D03*
Y1125746D03*
X1473454Y1135359D03*
X1475303Y1132154D03*
Y1138563D03*
X1477154Y1135359D03*
X1462354D03*
X1464203Y1132154D03*
Y1138563D03*
X1466054Y1135359D03*
X1467903Y1132154D03*
Y1138563D03*
X1469754Y1135359D03*
X1471603Y1132154D03*
Y1138563D03*
X1480421Y843877D03*
X1484121D03*
X1487821D03*
X1491521D03*
X1478570Y847081D03*
X1480421Y850286D03*
X1482270Y847081D03*
X1484121Y850286D03*
X1485970Y847081D03*
X1487821Y850286D03*
X1489670Y847081D03*
X1491521Y850286D03*
X1493370Y847081D03*
X1478570Y853490D03*
Y859899D03*
Y866307D03*
X1480421Y856694D03*
Y863103D03*
X1482270Y853490D03*
Y859899D03*
Y866307D03*
X1484121Y856694D03*
Y863103D03*
X1485970Y853490D03*
Y859899D03*
Y866307D03*
X1487821Y856694D03*
Y863103D03*
X1489670Y853490D03*
Y859899D03*
Y866307D03*
X1491521Y856694D03*
Y863103D03*
X1493370Y853490D03*
Y859899D03*
Y866307D03*
X1478570Y872716D03*
X1480421Y869511D03*
X1482270Y872716D03*
X1484121Y869511D03*
X1485970Y872716D03*
X1487821Y869511D03*
X1489670Y872716D03*
X1491521Y869511D03*
X1493370Y872716D03*
X1478570Y879124D03*
X1480421Y875920D03*
Y882329D03*
X1482270Y879124D03*
X1484121Y875920D03*
Y882329D03*
X1485970Y879124D03*
X1487821Y875920D03*
Y882329D03*
X1489670Y879124D03*
X1491521Y875920D03*
Y882329D03*
X1493370Y879124D03*
X1478570Y885533D03*
Y891942D03*
Y898350D03*
X1480421Y888737D03*
Y895146D03*
Y901555D03*
X1482270Y885533D03*
Y891942D03*
Y898350D03*
X1484121Y888737D03*
Y895146D03*
Y901555D03*
X1485970Y885533D03*
Y891942D03*
Y898350D03*
X1487821Y888737D03*
Y895146D03*
Y901555D03*
X1489670Y885533D03*
Y891942D03*
Y898350D03*
X1491521Y888737D03*
Y895146D03*
Y901555D03*
X1493370Y885533D03*
Y891942D03*
Y898350D03*
X1478570Y904759D03*
Y911167D03*
Y917576D03*
X1480421Y907963D03*
Y914372D03*
X1482270Y904759D03*
Y911167D03*
Y917576D03*
X1484121Y907963D03*
Y914372D03*
X1485970Y904759D03*
Y911167D03*
Y917576D03*
X1487821Y907963D03*
Y914372D03*
X1489670Y904759D03*
Y911167D03*
Y917576D03*
X1491521Y907963D03*
Y914372D03*
X1493370Y904759D03*
Y911167D03*
Y917576D03*
X1478570Y923985D03*
Y930393D03*
X1480421Y920780D03*
Y927189D03*
X1482270Y923985D03*
Y930393D03*
X1484121Y920780D03*
Y927189D03*
X1485970Y923985D03*
Y930393D03*
X1487821Y920780D03*
Y927189D03*
X1489670Y923985D03*
Y930393D03*
X1491521Y920780D03*
Y927189D03*
X1493370Y923985D03*
Y930393D03*
X1480421Y933598D03*
X1484121D03*
X1487821D03*
X1491521D03*
X1478570Y936801D03*
Y943210D03*
Y949619D03*
X1480421Y940006D03*
Y946414D03*
X1482270Y936801D03*
Y943210D03*
Y949619D03*
X1484121Y940006D03*
Y946414D03*
X1485970Y936801D03*
Y943210D03*
Y949619D03*
X1487821Y940006D03*
Y946414D03*
X1489670Y936801D03*
Y943210D03*
Y949619D03*
X1491521Y940006D03*
Y946414D03*
X1493370Y936801D03*
Y943210D03*
Y949619D03*
X1478570Y956027D03*
Y962436D03*
X1480421Y952823D03*
Y959232D03*
X1482270Y956027D03*
Y962436D03*
X1484121Y952823D03*
Y959232D03*
X1485970Y956027D03*
Y962436D03*
X1487821Y952823D03*
Y959232D03*
X1489670Y956027D03*
Y962436D03*
X1491521Y952823D03*
Y959232D03*
X1493370Y956027D03*
Y962436D03*
X1480421Y965640D03*
X1484121D03*
X1487821D03*
X1491521D03*
X1478570Y968845D03*
Y975253D03*
Y981662D03*
X1480421Y972049D03*
Y978457D03*
X1482270Y968845D03*
Y975253D03*
Y981662D03*
X1484121Y972049D03*
Y978457D03*
X1485970Y968845D03*
Y975253D03*
Y981662D03*
X1487821Y972049D03*
Y978457D03*
X1489670Y968845D03*
Y975253D03*
Y981662D03*
X1491521Y972049D03*
Y978457D03*
X1493370Y968845D03*
Y975253D03*
Y981662D03*
X1480421Y984866D03*
X1484121D03*
X1487821D03*
X1491521D03*
X1479003Y997574D03*
X1482703D03*
X1486403D03*
X1490103D03*
X1493803D03*
X1479003Y1003983D03*
Y1010391D03*
X1480854Y1000778D03*
Y1007187D03*
Y1013595D03*
X1482703Y1003983D03*
Y1010391D03*
X1484554Y1000778D03*
Y1007187D03*
Y1013595D03*
X1486403Y1003983D03*
Y1010391D03*
X1488254Y1000778D03*
Y1007187D03*
Y1013595D03*
X1490103Y1003983D03*
Y1010391D03*
X1491954Y1000778D03*
Y1007187D03*
Y1013595D03*
X1493803Y1003983D03*
Y1010391D03*
X1479003Y1016800D03*
X1480854Y1020004D03*
X1482703Y1016800D03*
X1484554Y1020004D03*
X1486403Y1016800D03*
X1488254Y1020004D03*
X1490103Y1016800D03*
X1491954Y1020004D03*
X1493803Y1016800D03*
X1479003Y1023208D03*
Y1029617D03*
X1480854Y1026413D03*
X1482703Y1023208D03*
Y1029617D03*
X1484554Y1026413D03*
X1486403Y1023208D03*
Y1029617D03*
X1488254Y1026413D03*
X1490103Y1023208D03*
Y1029617D03*
X1491954Y1026413D03*
X1493803Y1023208D03*
Y1029617D03*
X1479003Y1036026D03*
Y1042434D03*
X1480854Y1032821D03*
Y1039230D03*
Y1045639D03*
X1482703Y1036026D03*
Y1042434D03*
X1484554Y1032821D03*
Y1039230D03*
Y1045639D03*
X1486403Y1036026D03*
Y1042434D03*
X1488254Y1032821D03*
Y1039230D03*
Y1045639D03*
X1490103Y1036026D03*
Y1042434D03*
X1491954Y1032821D03*
Y1039230D03*
Y1045639D03*
X1493803Y1036026D03*
Y1042434D03*
X1479003Y1048842D03*
X1480854Y1052047D03*
X1482703Y1048842D03*
X1484554Y1052047D03*
X1486403Y1048842D03*
X1488254Y1052047D03*
X1490103Y1048842D03*
X1491954Y1052047D03*
X1493803Y1048842D03*
X1479003Y1055251D03*
Y1061660D03*
X1480854Y1058455D03*
X1482703Y1055251D03*
Y1061660D03*
X1484554Y1058455D03*
X1486403Y1055251D03*
Y1061660D03*
X1488254Y1058455D03*
X1490103Y1055251D03*
Y1061660D03*
X1491954Y1058455D03*
X1493803Y1055251D03*
Y1061660D03*
X1479003Y1068068D03*
Y1074477D03*
X1480854Y1064864D03*
Y1071273D03*
Y1077681D03*
X1482703Y1068068D03*
Y1074477D03*
X1484554Y1064864D03*
Y1071273D03*
Y1077681D03*
X1486403Y1068068D03*
Y1074477D03*
X1488254Y1064864D03*
Y1071273D03*
Y1077681D03*
X1490103Y1068068D03*
Y1074477D03*
X1491954Y1064864D03*
Y1071273D03*
Y1077681D03*
X1493803Y1068068D03*
Y1074477D03*
X1479003Y1080885D03*
X1482703D03*
X1486403D03*
X1490103D03*
X1493803D03*
X1479003Y1087294D03*
Y1093703D03*
X1480854Y1084090D03*
Y1090498D03*
X1482703Y1087294D03*
Y1093703D03*
X1484554Y1084090D03*
Y1090498D03*
X1486403Y1087294D03*
Y1093703D03*
X1488254Y1084090D03*
Y1090498D03*
X1490103Y1087294D03*
Y1093703D03*
X1491954Y1084090D03*
Y1090498D03*
X1493803Y1087294D03*
Y1093703D03*
X1479003Y1100111D03*
Y1106520D03*
X1480854Y1096907D03*
Y1103316D03*
Y1109724D03*
X1482703Y1100111D03*
Y1106520D03*
X1484554Y1096907D03*
Y1103316D03*
Y1109724D03*
X1486403Y1100111D03*
Y1106520D03*
X1488254Y1096907D03*
Y1103316D03*
Y1109724D03*
X1490103Y1100111D03*
Y1106520D03*
X1491954Y1096907D03*
Y1103316D03*
Y1109724D03*
X1493803Y1100111D03*
Y1106520D03*
X1479003Y1112929D03*
X1482703D03*
X1486403D03*
X1490103D03*
X1493803D03*
X1479003Y1119337D03*
Y1125746D03*
X1480854Y1116133D03*
Y1122541D03*
Y1128950D03*
X1482703Y1119337D03*
Y1125746D03*
X1484554Y1116133D03*
Y1122541D03*
Y1128950D03*
X1486403Y1119337D03*
Y1125746D03*
X1488254Y1116133D03*
Y1122541D03*
Y1128950D03*
X1490103Y1119337D03*
Y1125746D03*
X1491954Y1116133D03*
Y1122541D03*
Y1128950D03*
X1493803Y1119337D03*
Y1125746D03*
X1479003Y1132154D03*
Y1138563D03*
X1480854Y1135359D03*
X1482703Y1132154D03*
Y1138563D03*
X1484554Y1135359D03*
X1486403Y1132154D03*
Y1138563D03*
X1488254Y1135359D03*
X1490103Y1132154D03*
Y1138563D03*
X1491954Y1135359D03*
X1493803Y1132154D03*
Y1138563D03*
X1495221Y843877D03*
X1498921D03*
X1502621Y850286D03*
X1504471Y847081D03*
X1506321Y850286D03*
X1508170Y847081D03*
X1510021Y850286D03*
X1495221D03*
X1497070Y847081D03*
X1498921Y850286D03*
X1500770Y847081D03*
X1502621Y856694D03*
Y863103D03*
X1504471Y853490D03*
Y859899D03*
Y866307D03*
X1506321Y856694D03*
Y863103D03*
X1508170Y853490D03*
Y859899D03*
Y866307D03*
X1510021Y856694D03*
Y863103D03*
X1495221Y856694D03*
Y863103D03*
X1497070Y853490D03*
Y859899D03*
Y866307D03*
X1498921Y856694D03*
Y863103D03*
X1500770Y853490D03*
Y859899D03*
Y866307D03*
X1502621Y869511D03*
X1504471Y872716D03*
X1506321Y869511D03*
X1508170Y872716D03*
X1510021Y869511D03*
X1495221D03*
X1497070Y872716D03*
X1498921Y869511D03*
X1500770Y872716D03*
X1502621Y875920D03*
Y882329D03*
X1504471Y879124D03*
X1506321Y875920D03*
Y882329D03*
X1508170Y879124D03*
X1510021Y875920D03*
Y882329D03*
X1495221Y875920D03*
Y882329D03*
X1497070Y879124D03*
X1498921Y875920D03*
Y882329D03*
X1500770Y879124D03*
X1502621Y888737D03*
Y895146D03*
Y901555D03*
X1504471Y885533D03*
Y891942D03*
Y898350D03*
X1506321Y888737D03*
Y895146D03*
Y901555D03*
X1508170Y885533D03*
Y891942D03*
Y898350D03*
X1510021Y888737D03*
Y895146D03*
Y901555D03*
X1495221Y888737D03*
Y895146D03*
Y901555D03*
X1497070Y885533D03*
Y891942D03*
Y898350D03*
X1498921Y888737D03*
Y895146D03*
Y901555D03*
X1500770Y885533D03*
Y891942D03*
Y898350D03*
X1502621Y907963D03*
Y914372D03*
X1504471Y904759D03*
Y911167D03*
Y917576D03*
X1506321Y907963D03*
Y914372D03*
X1508170Y904759D03*
Y911167D03*
Y917576D03*
X1510021Y907963D03*
Y914372D03*
X1495221Y907963D03*
Y914372D03*
X1497070Y904759D03*
Y911167D03*
Y917576D03*
X1498921Y907963D03*
Y914372D03*
X1500770Y904759D03*
Y911167D03*
Y917576D03*
X1502621Y920780D03*
Y927189D03*
X1504471Y923985D03*
Y930393D03*
X1506321Y920780D03*
Y927189D03*
X1508170Y923985D03*
Y930393D03*
X1510021Y920780D03*
Y927189D03*
X1495221Y920780D03*
Y927189D03*
X1497070Y923985D03*
Y930393D03*
X1498921Y920780D03*
Y927189D03*
X1500770Y923985D03*
Y930393D03*
X1502621Y933598D03*
X1506321D03*
X1510021D03*
X1495221D03*
X1498921D03*
X1502621Y940006D03*
Y946414D03*
X1504471Y936801D03*
Y943210D03*
Y949619D03*
X1506321Y940006D03*
Y946414D03*
X1508170Y936801D03*
Y943210D03*
Y949619D03*
X1510021Y940006D03*
Y946414D03*
X1495221Y940006D03*
Y946414D03*
X1497070Y936801D03*
Y943210D03*
Y949619D03*
X1498921Y940006D03*
Y946414D03*
X1500770Y936801D03*
Y943210D03*
Y949619D03*
X1502621Y952823D03*
Y959232D03*
X1504471Y956027D03*
Y962436D03*
X1506321Y952823D03*
Y959232D03*
X1508170Y956027D03*
Y962436D03*
X1510021Y952823D03*
Y959232D03*
X1495221Y952823D03*
Y959232D03*
X1497070Y956027D03*
Y962436D03*
X1498921Y952823D03*
Y959232D03*
X1500770Y956027D03*
Y962436D03*
X1502621Y965640D03*
X1506321D03*
X1510021D03*
X1495221D03*
X1498921D03*
X1502621Y972049D03*
Y978457D03*
X1504471Y968845D03*
Y975253D03*
Y981662D03*
X1506321Y972049D03*
Y978457D03*
X1508170Y968845D03*
Y975253D03*
Y981662D03*
X1510021Y972049D03*
Y978457D03*
X1495221Y972049D03*
Y978457D03*
X1497070Y968845D03*
Y975253D03*
Y981662D03*
X1498921Y972049D03*
Y978457D03*
X1500770Y968845D03*
Y975253D03*
Y981662D03*
X1502621Y984866D03*
X1506321D03*
X1510021D03*
X1495221D03*
X1498921D03*
X1504903Y997574D03*
X1508603D03*
X1497503D03*
X1501203D03*
X1503054Y1000778D03*
Y1007187D03*
Y1013595D03*
X1504903Y1003983D03*
Y1010391D03*
X1506754Y1000778D03*
Y1007187D03*
Y1013595D03*
X1508603Y1003983D03*
Y1010391D03*
X1495654Y1000778D03*
Y1007187D03*
Y1013595D03*
X1497503Y1003983D03*
Y1010391D03*
X1499354Y1000778D03*
Y1007187D03*
Y1013595D03*
X1501203Y1003983D03*
Y1010391D03*
X1503054Y1020004D03*
X1504903Y1016800D03*
X1506754Y1020004D03*
X1508603Y1016800D03*
X1495654Y1020004D03*
X1497503Y1016800D03*
X1499354Y1020004D03*
X1501203Y1016800D03*
X1503054Y1026413D03*
X1504903Y1023208D03*
Y1029617D03*
X1506754Y1026413D03*
X1508603Y1023208D03*
Y1029617D03*
X1495654Y1026413D03*
X1497503Y1023208D03*
Y1029617D03*
X1499354Y1026413D03*
X1501203Y1023208D03*
Y1029617D03*
X1503054Y1032821D03*
Y1039230D03*
Y1045639D03*
X1504903Y1036026D03*
Y1042434D03*
X1506754Y1032821D03*
Y1039230D03*
Y1045639D03*
X1508603Y1036026D03*
Y1042434D03*
X1495654Y1032821D03*
Y1039230D03*
Y1045639D03*
X1497503Y1036026D03*
Y1042434D03*
X1499354Y1032821D03*
Y1039230D03*
Y1045639D03*
X1501203Y1036026D03*
Y1042434D03*
X1503054Y1052047D03*
X1504903Y1048842D03*
X1506754Y1052047D03*
X1508603Y1048842D03*
X1495654Y1052047D03*
X1497503Y1048842D03*
X1499354Y1052047D03*
X1501203Y1048842D03*
X1503054Y1058455D03*
X1504903Y1055251D03*
Y1061660D03*
X1506754Y1058455D03*
X1508603Y1055251D03*
Y1061660D03*
X1495654Y1058455D03*
X1497503Y1055251D03*
Y1061660D03*
X1499354Y1058455D03*
X1501203Y1055251D03*
Y1061660D03*
X1503054Y1064864D03*
Y1071273D03*
Y1077681D03*
X1504903Y1068068D03*
Y1074477D03*
X1506754Y1064864D03*
Y1071273D03*
Y1077681D03*
X1508603Y1068068D03*
Y1074477D03*
X1495654Y1064864D03*
Y1071273D03*
Y1077681D03*
X1497503Y1068068D03*
Y1074477D03*
X1499354Y1064864D03*
Y1071273D03*
Y1077681D03*
X1501203Y1068068D03*
Y1074477D03*
X1504903Y1080885D03*
X1508603D03*
X1497503D03*
X1501203D03*
X1503054Y1084090D03*
Y1090498D03*
X1504903Y1087294D03*
Y1093703D03*
X1506754Y1084090D03*
Y1090498D03*
X1508603Y1087294D03*
Y1093703D03*
X1495654Y1084090D03*
Y1090498D03*
X1497503Y1087294D03*
Y1093703D03*
X1499354Y1084090D03*
Y1090498D03*
X1501203Y1087294D03*
Y1093703D03*
X1503054Y1096907D03*
Y1103316D03*
Y1109724D03*
X1504903Y1100111D03*
Y1106520D03*
X1506754Y1096907D03*
Y1103316D03*
Y1109724D03*
X1508603Y1100111D03*
Y1106520D03*
X1495654Y1096907D03*
Y1103316D03*
Y1109724D03*
X1497503Y1100111D03*
Y1106520D03*
X1499354Y1096907D03*
Y1103316D03*
Y1109724D03*
X1501203Y1100111D03*
Y1106520D03*
X1504903Y1112929D03*
X1508603D03*
X1497503D03*
X1501203D03*
X1503054Y1116133D03*
Y1122541D03*
Y1128950D03*
X1504903Y1119337D03*
Y1125746D03*
X1506754Y1116133D03*
Y1122541D03*
Y1128950D03*
X1508603Y1119337D03*
Y1125746D03*
X1510453Y1128950D03*
X1495654Y1116133D03*
Y1122541D03*
Y1128950D03*
X1497503Y1119337D03*
Y1125746D03*
X1499354Y1116133D03*
Y1122541D03*
Y1128950D03*
X1501203Y1119337D03*
Y1125746D03*
X1503054Y1135359D03*
X1504903Y1132154D03*
X1506754Y1135359D03*
X1508603Y1132154D03*
X1510453Y1135359D03*
X1495654D03*
X1497503Y1132154D03*
Y1138563D03*
X1499354Y1135359D03*
X1501203Y1132154D03*
Y1138563D03*
X1511871Y847081D03*
X1513721Y850286D03*
X1511871Y853490D03*
Y859899D03*
Y866307D03*
X1513721Y856694D03*
Y863103D03*
X1515570Y853490D03*
Y859899D03*
Y866307D03*
X1517421Y856694D03*
Y863103D03*
X1519271Y853490D03*
Y859899D03*
Y866307D03*
X1521121Y856694D03*
Y863103D03*
X1522970Y866307D03*
X1511871Y872716D03*
X1513721Y869511D03*
X1515570Y872716D03*
X1517421Y869511D03*
X1519271Y872716D03*
X1521121Y869511D03*
X1522970Y872716D03*
X1511871Y879124D03*
X1513721Y875920D03*
Y882329D03*
X1515570Y879124D03*
X1517421Y875920D03*
Y882329D03*
X1519271Y879124D03*
X1521121Y875920D03*
Y882329D03*
X1522970Y879124D03*
X1511871Y885533D03*
Y891942D03*
Y898350D03*
X1513721Y888737D03*
Y895146D03*
Y901555D03*
X1515570Y885533D03*
Y891942D03*
Y898350D03*
X1517421Y888737D03*
Y895146D03*
Y901555D03*
X1519271Y885533D03*
Y891942D03*
Y898350D03*
X1521121Y888737D03*
Y895146D03*
Y901555D03*
X1522970Y885533D03*
Y891942D03*
Y898350D03*
X1511871Y904759D03*
Y911167D03*
Y917576D03*
X1513721Y907963D03*
Y914372D03*
X1515570Y904759D03*
Y911167D03*
Y917576D03*
X1517421Y907963D03*
Y914372D03*
X1519271Y904759D03*
Y911167D03*
Y917576D03*
X1521121Y907963D03*
Y914372D03*
X1522970Y904759D03*
Y911167D03*
Y917576D03*
X1511871Y923985D03*
Y930393D03*
X1513721Y920780D03*
Y927189D03*
X1515570Y923985D03*
Y930393D03*
X1517421Y920780D03*
Y927189D03*
X1519271Y923985D03*
Y930393D03*
X1521121Y920780D03*
Y927189D03*
X1522970Y923985D03*
Y930393D03*
X1513721Y933598D03*
X1517421D03*
X1521121D03*
X1511871Y936801D03*
Y943210D03*
Y949619D03*
X1513721Y940006D03*
Y946414D03*
X1515570Y936801D03*
Y943210D03*
Y949619D03*
X1517421Y940006D03*
Y946414D03*
X1519271Y936801D03*
Y943210D03*
Y949619D03*
X1521121Y940006D03*
Y946414D03*
X1522970Y936801D03*
Y943210D03*
Y949619D03*
X1511871Y956027D03*
Y962436D03*
X1513721Y952823D03*
Y959232D03*
X1515570Y956027D03*
Y962436D03*
X1517421Y952823D03*
Y959232D03*
X1519271Y956027D03*
Y962436D03*
X1521121Y952823D03*
Y959232D03*
X1522970Y956027D03*
Y962436D03*
X1513721Y965640D03*
X1517421D03*
X1521121D03*
X1511871Y968845D03*
Y975253D03*
Y981662D03*
X1513721Y972049D03*
Y978457D03*
X1515570Y968845D03*
Y975253D03*
Y981662D03*
X1517421Y972049D03*
Y978457D03*
X1519271Y968845D03*
Y975253D03*
Y981662D03*
X1521121Y972049D03*
Y978457D03*
X1522970Y968845D03*
Y975253D03*
X1513721Y984866D03*
X1517421D03*
X1512303Y997574D03*
X1516003D03*
X1519703D03*
X1510453Y1000778D03*
Y1007187D03*
Y1013595D03*
X1512303Y1003983D03*
Y1010391D03*
X1514154Y1000778D03*
Y1007187D03*
Y1013595D03*
X1516003Y1003983D03*
Y1010391D03*
X1517853Y1000778D03*
Y1007187D03*
Y1013595D03*
X1519703Y1003983D03*
Y1010391D03*
X1521554Y1000778D03*
Y1007187D03*
Y1013595D03*
X1523403Y1003983D03*
Y1010391D03*
X1510453Y1020004D03*
X1512303Y1016800D03*
X1514154Y1020004D03*
X1516003Y1016800D03*
X1517853Y1020004D03*
X1519703Y1016800D03*
X1521554Y1020004D03*
X1523403Y1016800D03*
X1510453Y1026413D03*
X1512303Y1023208D03*
Y1029617D03*
X1514154Y1026413D03*
X1516003Y1023208D03*
Y1029617D03*
X1517853Y1026413D03*
X1519703Y1023208D03*
Y1029617D03*
X1521554Y1026413D03*
X1523403Y1023208D03*
Y1029617D03*
X1510453Y1032821D03*
Y1039230D03*
Y1045639D03*
X1512303Y1036026D03*
Y1042434D03*
X1514154Y1032821D03*
Y1039230D03*
Y1045639D03*
X1516003Y1036026D03*
Y1042434D03*
X1517853Y1032821D03*
Y1039230D03*
Y1045639D03*
X1519703Y1036026D03*
Y1042434D03*
X1521554Y1032821D03*
Y1039230D03*
Y1045639D03*
X1523403Y1036026D03*
Y1042434D03*
X1510453Y1052047D03*
X1512303Y1048842D03*
X1514154Y1052047D03*
X1516003Y1048842D03*
X1517853Y1052047D03*
X1519703Y1048842D03*
X1521554Y1052047D03*
X1510453Y1058455D03*
X1512303Y1055251D03*
Y1061660D03*
X1514154Y1058455D03*
X1516003Y1055251D03*
Y1061660D03*
X1517853Y1058455D03*
X1519703Y1055251D03*
Y1061660D03*
X1521554Y1058455D03*
X1510453Y1064864D03*
Y1071273D03*
Y1077681D03*
X1512303Y1068068D03*
Y1074477D03*
X1514154Y1064864D03*
Y1071273D03*
Y1077681D03*
X1516003Y1068068D03*
Y1074477D03*
X1517853Y1064864D03*
Y1071273D03*
Y1077681D03*
X1519703Y1068068D03*
Y1074477D03*
X1521554Y1064864D03*
Y1071273D03*
Y1077681D03*
X1512303Y1080885D03*
X1516003D03*
X1519703D03*
X1510453Y1084090D03*
Y1090498D03*
X1512303Y1087294D03*
Y1093703D03*
X1514154Y1084090D03*
Y1090498D03*
X1516003Y1087294D03*
Y1093703D03*
X1517853Y1084090D03*
Y1090498D03*
X1519703Y1087294D03*
Y1093703D03*
X1521554Y1084090D03*
Y1090498D03*
X1510453Y1096907D03*
Y1103316D03*
Y1109724D03*
X1512303Y1100111D03*
Y1106520D03*
X1514154Y1096907D03*
Y1103316D03*
Y1109724D03*
X1516003Y1100111D03*
Y1106520D03*
X1517853Y1096907D03*
Y1103316D03*
Y1109724D03*
X1519703Y1100111D03*
Y1106520D03*
X1521554Y1096907D03*
Y1103316D03*
Y1109724D03*
X1512303Y1112929D03*
X1516003D03*
X1519703D03*
X1510453Y1116133D03*
Y1122541D03*
X1512303Y1119337D03*
Y1125746D03*
X1514154Y1116133D03*
Y1122541D03*
Y1128950D03*
X1516003Y1119337D03*
Y1125746D03*
X1517853Y1116133D03*
Y1122541D03*
Y1128950D03*
X1519703Y1119337D03*
Y1125746D03*
X1521554Y1116133D03*
Y1122541D03*
X1512303Y1132154D03*
G54D40*
X77416Y1536519D03*
Y1538094D03*
Y1539669D03*
G54D232*
X1025609Y286776D03*
X1027183D03*
X1028758D03*
X1030333D03*
X1031908D03*
X1033483D03*
X1035057D03*
X1802550Y1510568D03*
X1800975D03*
X1799400D03*
X1797826D03*
X1807274D03*
X1805700D03*
X1804125D03*
G54D223*
X1003672Y376725D03*
X1001704D03*
X999735D03*
X997767D03*
X995798D03*
X993830D03*
Y407237D03*
X995798D03*
X997767D03*
X999735D03*
X1001704D03*
X1003672D03*
X1019420Y376725D03*
X1017452D03*
X1015483D03*
X1013515D03*
X1011546D03*
X1009578D03*
X1007609D03*
X1005641D03*
Y407237D03*
X1007609D03*
X1009578D03*
X1011546D03*
X1013515D03*
X1015483D03*
X1017452D03*
X1019420D03*
G54D50*
X94705Y712316D03*
X1708137Y716442D03*
G54D41*
X77416Y1541244D03*
G54D14*
X17016Y193362D03*
Y200362D03*
X27736Y232362D03*
Y240362D03*
X33001Y401000D03*
X57123Y421746D03*
X59290Y1524094D03*
Y1532094D03*
Y1528194D03*
Y1548094D03*
Y1552094D03*
Y1544094D03*
Y1556094D03*
X78007Y436519D03*
Y432519D03*
X81890Y391391D03*
Y395865D03*
Y382219D03*
X88317Y428319D03*
Y424319D03*
Y420319D03*
Y450519D03*
Y446519D03*
X87656Y667734D03*
X88551Y718879D03*
X93204Y1593867D03*
Y1585852D03*
Y1589852D03*
X93279Y1611821D03*
Y1605867D03*
Y1623821D03*
X93189Y1634362D03*
Y1638362D03*
X88736Y1690362D03*
X96671Y169263D03*
X107941Y232128D03*
X104936Y493578D03*
X104966Y497374D03*
Y501374D03*
Y505374D03*
Y509374D03*
Y513374D03*
X96030Y512870D03*
X95836Y696262D03*
X107290Y1528594D03*
Y1532694D03*
Y1552594D03*
Y1556594D03*
X96516Y1655800D03*
Y1651800D03*
X123935Y278875D03*
X123916Y274800D03*
X123935Y306236D03*
X127498Y396071D03*
Y388071D03*
Y392071D03*
Y384071D03*
X116998Y404571D03*
X124254Y636153D03*
Y640103D03*
X119574Y1589352D03*
X124354Y1604367D03*
X125074Y1622321D03*
X124074Y1637862D03*
X121736Y1696362D03*
X127573Y1723182D03*
X131466Y525374D03*
X130053Y1535855D03*
X130205Y1541874D03*
X130297Y1547935D03*
X140836Y1708362D03*
X138583Y1720092D03*
X158416Y413362D03*
X144013Y510810D03*
Y514810D03*
Y518810D03*
Y526830D03*
X152824Y519281D03*
X148236Y1716362D03*
X175083Y1723592D03*
X181912Y421383D03*
Y425383D03*
Y443383D03*
Y430883D03*
X191158Y689683D03*
X182083Y1729092D03*
Y1733092D03*
X204907Y567981D03*
X197081Y584791D03*
X204907Y601981D03*
X197081Y618791D03*
X204907Y635981D03*
X197081Y652791D03*
X193686Y675092D03*
X192966Y1535377D03*
X192907Y1539678D03*
X192799Y1548430D03*
X192707Y1552940D03*
X205236Y1709862D03*
X205134Y1714017D03*
X212070Y420735D03*
Y424735D03*
Y428735D03*
Y436735D03*
Y432735D03*
Y440735D03*
Y444735D03*
Y448735D03*
Y457222D03*
Y462235D03*
X222729Y1322859D03*
Y1326859D03*
X234216Y142062D03*
X230536Y159071D03*
X242236Y75862D03*
X247313Y115743D03*
X246524Y565976D03*
X246981Y598632D03*
X246682Y633848D03*
X242534Y703397D03*
X258997Y64455D03*
X258949Y60345D03*
X258952Y56160D03*
X257813Y87543D03*
X267069Y151203D03*
Y147203D03*
X270836Y210822D03*
X266600Y439605D03*
X266570Y451735D03*
Y447735D03*
X283816Y136962D03*
X282549Y229606D03*
X275516Y451862D03*
Y447862D03*
X287036Y569548D03*
Y566022D03*
X289636Y634283D03*
Y630757D03*
X287910Y685071D03*
Y688597D03*
X295433Y67513D03*
X295943Y85983D03*
Y82483D03*
X302173Y91767D03*
X305116Y146702D03*
X290716Y139162D03*
X306235Y599318D03*
X317073Y95803D03*
X317119Y99837D03*
X320916Y161562D03*
X314990Y228258D03*
X320325Y559218D03*
X314741Y595998D03*
X336716Y141862D03*
X347554Y142869D03*
X353236Y225862D03*
X346713Y705779D03*
X385676Y119822D03*
Y132822D03*
X378736Y217362D03*
Y208862D03*
Y212862D03*
Y221362D03*
Y225362D03*
X384856Y1622722D03*
X395448Y1398653D03*
X403415Y1411231D03*
X399437Y1537810D03*
Y1545810D03*
Y1560810D03*
Y1564810D03*
X404566Y1549942D03*
X411216Y1603500D03*
Y1615200D03*
X418716Y1616600D03*
X418666Y1620402D03*
X418631Y1624692D03*
Y1628692D03*
Y1632842D03*
X419226Y1643159D03*
X419246Y1647216D03*
X418631Y1636842D03*
X412736Y1672362D03*
Y1676362D03*
Y1668362D03*
X429937Y1547810D03*
Y1551810D03*
X427061Y1583466D03*
X446872Y145710D03*
X445344Y505483D03*
Y509483D03*
Y513483D03*
Y517483D03*
Y521483D03*
Y525483D03*
Y542519D03*
Y547519D03*
X450536Y1547437D03*
X441399Y1600154D03*
X456655Y120948D03*
X455016Y213362D03*
Y222362D03*
X468363Y1400435D03*
X468332Y1396606D03*
X466429Y1610682D03*
Y1603682D03*
X466386Y1622735D03*
X466476Y1626732D03*
X471376Y1631003D03*
X471316Y1634947D03*
X472446Y1647242D03*
Y1663242D03*
X472376Y1677462D03*
Y1681462D03*
X485689Y66565D03*
X485799Y61205D03*
X485959Y55895D03*
X489352Y309398D03*
X498676Y615612D03*
X490372Y1424033D03*
X517341Y168443D03*
X507016Y223362D03*
X502516Y241862D03*
X516916Y489112D03*
X516102Y500469D03*
Y505969D03*
X516916Y495112D03*
X516102Y511469D03*
Y516969D03*
Y522469D03*
Y527969D03*
Y539819D03*
X515516Y615742D03*
X506187Y1422494D03*
X518826Y455062D03*
X526906Y500222D03*
X536356Y99172D03*
X536416Y112512D03*
X549736Y161362D03*
Y184862D03*
Y171862D03*
X536580Y269472D03*
X535466Y454270D03*
X564516Y102862D03*
Y98862D03*
X552486Y127788D03*
Y137774D03*
Y153878D03*
X566605Y310847D03*
X565341Y424392D03*
X565033Y446706D03*
X570056Y157932D03*
X579366Y157684D03*
X581972Y194378D03*
X581736Y230862D03*
X570736Y225362D03*
Y221362D03*
X577586Y493212D03*
Y488212D03*
Y497212D03*
X567586Y1355247D03*
Y1358777D03*
X592336Y136314D03*
Y125314D03*
X596271Y159480D03*
X588668Y288527D03*
X609851Y184062D03*
X599736Y416362D03*
X601736Y444362D03*
Y449362D03*
X599915Y454600D03*
X600736Y506862D03*
Y510862D03*
X631433Y88039D03*
Y92119D03*
X625552Y208076D03*
Y212076D03*
X627736Y234362D03*
Y230362D03*
X631736Y416362D03*
X617736Y426362D03*
X631736Y472862D03*
Y477862D03*
Y467862D03*
X616736Y472862D03*
Y477862D03*
Y462862D03*
Y467862D03*
X645160Y140699D03*
Y149871D03*
Y154345D03*
X646236Y184862D03*
X639650Y249202D03*
Y260202D03*
X637661Y294327D03*
Y290267D03*
Y306547D03*
X646736Y411362D03*
Y421362D03*
Y426362D03*
Y477862D03*
Y472862D03*
Y482862D03*
X633236Y526362D03*
X642236Y1714362D03*
Y1726362D03*
X680469Y119568D03*
Y123420D03*
X665534Y1647557D03*
X665609Y1659557D03*
X665636Y1664862D03*
Y1676862D03*
X668736Y1712362D03*
Y1728362D03*
X690736Y76962D03*
X690969Y91668D03*
X691738Y1640667D03*
X691663Y1636667D03*
X692136Y1662862D03*
Y1678862D03*
X710236Y221862D03*
X704628Y1567683D03*
Y1579683D03*
Y1571683D03*
Y1575683D03*
Y1587683D03*
Y1595683D03*
Y1591683D03*
X711649Y1680400D03*
X723649Y160788D03*
X720461Y1564088D03*
X719768Y1569493D03*
X726768D03*
X727869Y1614503D03*
X727768Y1609893D03*
X718849Y1680400D03*
X730009Y86998D03*
X730519Y101968D03*
X738249Y111252D03*
X730519Y105468D03*
X745761Y137864D03*
X745171Y1682362D03*
Y1678362D03*
X751649Y115288D03*
X751651Y119172D03*
X748176Y265322D03*
Y269322D03*
X760736Y413212D03*
Y403212D03*
Y408212D03*
Y398212D03*
X759856Y459862D03*
Y454862D03*
Y474862D03*
X759916Y493452D03*
X762036Y1384062D03*
Y1401562D03*
Y1397262D03*
X761936Y1414762D03*
X754628Y1583183D03*
X760731Y1698521D03*
X774936Y163254D03*
X772957Y308755D03*
X773042Y303410D03*
X775736Y393212D03*
X774856Y454862D03*
Y459862D03*
X762136Y1379962D03*
Y1375462D03*
X765655Y1573793D03*
X765668Y1581893D03*
Y1577893D03*
Y1590893D03*
X779676Y274822D03*
X786142Y303410D03*
X786057Y308755D03*
X788016Y385300D03*
X789936Y398212D03*
X789856Y444862D03*
Y439862D03*
Y449862D03*
Y454862D03*
Y459862D03*
Y469862D03*
X805586Y441060D03*
Y445100D03*
X805356Y454862D03*
Y459862D03*
Y449862D03*
Y464862D03*
X807168Y1573793D03*
Y1581793D03*
Y1597793D03*
Y1585793D03*
Y1605793D03*
X817816Y449200D03*
X825016D03*
X819356Y476800D03*
Y464862D03*
Y468900D03*
Y472900D03*
X824286Y511082D03*
Y506082D03*
Y527082D03*
Y519082D03*
X837341Y90451D03*
X839236Y135862D03*
Y129362D03*
X827493Y409260D03*
Y405260D03*
X848736Y129362D03*
Y135862D03*
X858108Y240441D03*
X856319Y265057D03*
X843763Y271049D03*
X856829Y280027D03*
Y283527D03*
X859516Y378362D03*
X849416Y473000D03*
Y469100D03*
X857136Y507162D03*
Y495300D03*
X849168Y1573793D03*
Y1581793D03*
Y1597793D03*
Y1585793D03*
Y1605793D03*
X871236Y171362D03*
Y176862D03*
X866016Y196500D03*
X865409Y227763D03*
Y223763D03*
X864559Y289311D03*
X865002Y386476D03*
Y402581D03*
Y398620D03*
X865054Y414276D03*
X881316Y201150D03*
Y195720D03*
X881241Y192055D03*
X877959Y293347D03*
X877982Y298665D03*
X891838Y874405D03*
X891168Y1573793D03*
Y1581793D03*
Y1597793D03*
Y1585793D03*
Y1605793D03*
X899369Y484913D03*
Y480913D03*
X899164Y493299D03*
Y489299D03*
X899149Y501573D03*
Y497573D03*
X892408Y920325D03*
X905005Y975134D03*
Y971234D03*
Y992834D03*
Y988934D03*
X933168Y1593393D03*
X943431Y184912D03*
X943351Y188852D03*
X948575Y424298D03*
X948498Y428124D03*
X948471Y437844D03*
X948548Y434018D03*
X945826Y997422D03*
X970109Y356896D03*
X982440Y171483D03*
X991516Y148299D03*
X998516D03*
X994428Y213233D03*
X1000826Y363352D03*
X1009892Y167278D03*
Y171278D03*
X1015106Y190176D03*
X1014986Y363222D03*
X1034349Y268264D03*
X1038385Y509606D03*
X1027794Y523628D03*
Y514176D03*
X1036126Y523642D03*
X1036546Y514182D03*
X1070937Y265574D03*
X1069671Y386723D03*
X1084237Y69602D03*
X1079205Y83698D03*
X1080126Y379251D03*
X1080006Y369061D03*
X1080066Y374131D03*
X1088306Y1670963D03*
X1104188Y60028D03*
X1110535Y72803D03*
Y77559D03*
X1134658Y1555301D03*
X1136066Y1597630D03*
Y1601630D03*
X1149053Y73679D03*
X1150596Y363231D03*
X1150526Y368041D03*
X1149198Y1626280D03*
X1168387Y61311D03*
Y65811D03*
X1168407Y57111D03*
X1157536Y211370D03*
X1182316Y111600D03*
X1175761Y194174D03*
Y190174D03*
Y206174D03*
Y210174D03*
Y222174D03*
X1195316Y97400D03*
Y89000D03*
Y101600D03*
X1195504Y212648D03*
X1197491Y240672D03*
Y244692D03*
X1194011Y1359636D03*
Y1363146D03*
X1213117Y53860D03*
X1204277Y61060D03*
X1208716Y93600D03*
X1216516D03*
X1209916Y113200D03*
X1217109Y119462D03*
Y132962D03*
X1217113Y148909D03*
Y144909D03*
X1217109Y153962D03*
Y157962D03*
Y168962D03*
X1208609Y164962D03*
X1217109D03*
Y176962D03*
X1208609D03*
X1217095Y172945D03*
X1210035Y171611D03*
X1217236Y194862D03*
X1207736Y200309D03*
Y195362D03*
X1203601Y1681767D03*
X1232906Y102608D03*
X1223010Y113982D03*
X1232907Y106609D03*
X1228627Y129409D03*
X1228609Y134262D03*
Y153115D03*
Y141110D03*
Y163462D03*
Y156962D03*
Y177962D03*
X1242398Y95008D03*
X1239109Y209462D03*
Y205862D03*
Y213462D03*
Y217462D03*
X1248109Y233462D03*
Y223462D03*
Y227462D03*
Y237462D03*
Y241462D03*
X1234876Y244332D03*
Y248332D03*
X1278807Y102928D03*
X1267270Y92724D03*
X1297527Y85138D03*
X1302550Y68562D03*
X1316316Y261662D03*
X1370132Y1403458D03*
X1370189Y1399053D03*
X1379556Y1411231D03*
X1370132Y1407458D03*
X1381153Y1415495D03*
X1394924Y1565037D03*
X1395098Y1576097D03*
X1394924Y1570037D03*
X1395416Y1609522D03*
X1405949Y1516435D03*
X1406189Y1532255D03*
X1405949Y1521335D03*
X1397116Y1521362D03*
X1406339Y1543475D03*
X1406189Y1537155D03*
X1406339Y1548375D03*
X1397016Y1537162D03*
Y1548362D03*
X1399416Y1582500D03*
Y1594000D03*
X1402516Y1630362D03*
Y1642362D03*
X1421399Y227948D03*
X1414916Y1593700D03*
X1424266Y1612812D03*
X1428516Y1637362D03*
X1441216Y60062D03*
X1441938Y1400204D03*
X1441972Y1396269D03*
X1440916Y1598400D03*
Y1611000D03*
X1436316Y1624500D03*
Y1628700D03*
X1451783Y1526689D03*
X1452023Y1542509D03*
X1452173Y1553729D03*
X1450176Y1590302D03*
X1471083Y64355D03*
X1466513Y1424033D03*
X1484899Y233448D03*
X1484601Y255378D03*
X1482316Y421982D03*
X1482328Y1422494D03*
X1502474Y280056D03*
X1526174Y150651D03*
X1517084Y231116D03*
Y239116D03*
Y249698D03*
Y262616D03*
X1516774Y280956D03*
X1517016Y272362D03*
X1517154Y268214D03*
X1516774Y288956D03*
X1532516Y125362D03*
Y121362D03*
X1537855Y310487D03*
X1546904Y127781D03*
X1550253Y634165D03*
X1560808Y651039D03*
X1589016Y199362D03*
X1588855Y256244D03*
X1597432Y1411169D03*
Y1415669D03*
Y1424669D03*
Y1429169D03*
Y1442669D03*
Y1447153D03*
X1636697Y624475D03*
X1635598Y652601D03*
X1636697Y658475D03*
X1635598Y686601D03*
X1636697Y692475D03*
X1635598Y720601D03*
X1641971Y180460D03*
X1644626Y414202D03*
X1654745Y524071D03*
X1654696Y520540D03*
X1654745Y528071D03*
Y532071D03*
Y540071D03*
Y536071D03*
X1642448Y614845D03*
X1653916Y631703D03*
X1654388Y649681D03*
X1653916Y665703D03*
X1654388Y683681D03*
X1653916Y699703D03*
X1654388Y717681D03*
X1660461Y195935D03*
X1662847Y594959D03*
X1661938Y607291D03*
X1668614Y1497362D03*
Y1512862D03*
Y1505362D03*
Y1524862D03*
Y1537862D03*
Y1541862D03*
Y1553557D03*
X1668689Y1565557D03*
Y1585321D03*
X1687149Y424694D03*
X1686011Y473878D03*
Y469878D03*
X1686036Y465940D03*
X1684447Y478790D03*
Y482790D03*
Y488290D03*
X1680004Y491790D03*
X1683585Y552241D03*
X1692520Y401485D03*
X1693792Y518107D03*
Y513107D03*
Y541507D03*
Y537507D03*
X1704551Y531613D03*
X1693792Y545507D03*
Y553527D03*
X1701983Y723005D03*
X1699264Y1500862D03*
Y1520362D03*
Y1541362D03*
X1699544Y1564057D03*
X1700264Y1583821D03*
X1711796Y165909D03*
X1711845Y161900D03*
Y157892D03*
X1711796Y170326D03*
X1715043Y424340D03*
Y420340D03*
X1719945Y490869D03*
Y486869D03*
Y482869D03*
Y494869D03*
X1710596Y499412D03*
X1707436Y701062D03*
X1720665Y1496270D03*
X1732310Y61639D03*
X1732358Y65749D03*
X1732313Y57454D03*
X1733134Y88787D03*
X1722434Y116867D03*
X1726550Y181234D03*
X1726381Y177072D03*
Y173072D03*
X1727895Y490869D03*
Y486869D03*
Y480669D03*
X1751175Y187509D03*
X1751103Y364048D03*
X1751236Y377452D03*
X1751103Y368048D03*
X1751236Y382952D03*
X1760554Y68637D03*
X1761064Y83607D03*
Y87107D03*
X1768794Y92891D03*
X1764943Y364148D03*
X1764736Y372452D03*
X1764943Y368148D03*
X1764736Y377452D03*
X1770067Y461393D03*
Y465893D03*
Y470193D03*
X1782194Y96927D03*
X1782152Y100939D03*
X1771891Y173903D03*
Y178403D03*
X1799815Y161465D03*
X1788904Y1506538D03*
X1815815Y413432D03*
Y417432D03*
X1822703Y170162D03*
X1829395Y399185D03*
X1823855Y434202D03*
X1832467Y453921D03*
X1832457Y467321D03*
Y463193D03*
X1842976Y172187D03*
X1835821Y192678D03*
G54D23*
X36595Y385068D03*
X46834Y363428D03*
X55190D03*
X54333Y1606850D03*
X57833Y1666350D03*
X53333D03*
X49333D03*
X61000Y1676216D03*
X70333Y1615850D03*
X69833Y1666350D03*
X73833D03*
X77833D03*
X65000Y1676216D03*
X90518Y637121D03*
X82014Y699608D03*
X92096Y694696D03*
X84474Y1520110D03*
X87500Y1561610D03*
X91500D03*
X81833Y1666350D03*
X90297Y1666396D03*
X85833Y1666350D03*
X108643Y523833D03*
X96774Y1526110D03*
X108800Y1608916D03*
X117597Y491407D03*
X113597D03*
X114720Y1680378D03*
X120910Y1723563D03*
X130317Y480329D03*
X135317D03*
X138489Y525465D03*
X134557Y1728198D03*
X149174Y480329D03*
X152470Y502879D03*
X149568Y1389686D03*
X152806Y1408475D03*
X158570Y1523521D03*
X154581Y1523480D03*
X159014Y1573925D03*
X154580D03*
X170673Y1409461D03*
X175067Y1730108D03*
X190110Y569488D03*
X187711Y1389686D03*
X181806Y1390706D03*
X177702D03*
X190949Y1408475D03*
X205320Y670078D03*
X201220D03*
X207716Y1408761D03*
X220387Y1390815D03*
X216090D03*
X212120Y1706778D03*
X237220Y62378D03*
X241220D03*
X249220D03*
X245220D03*
X251487Y104776D03*
X263580Y221118D03*
X270240Y239298D03*
X267759Y254747D03*
X271821D03*
X275797Y124059D03*
X276491Y254747D03*
X281077D03*
X286481D03*
X289274Y293404D03*
X284515D03*
X302517Y68508D03*
X301315Y95815D03*
X305315D03*
X291759Y254747D03*
X304651D03*
X298184Y293404D03*
X302765D03*
X293763D03*
X302684Y559883D03*
X303551Y1347832D03*
X322155Y232235D03*
X317995Y232265D03*
X317129Y254747D03*
X306736Y293404D03*
X316463D03*
X307019Y1366553D03*
X325617Y73879D03*
X338267Y210643D03*
X329648Y254693D03*
X329002Y293404D03*
X335679Y1325034D03*
X338917Y1343823D03*
X336205Y1350863D03*
X331773Y1348969D03*
X324656Y1366707D03*
X354672Y255184D03*
X342000Y255103D03*
X354145Y293082D03*
X341295Y292730D03*
X367306Y255302D03*
X366498Y292755D03*
X367717Y1311608D03*
X366903Y1335191D03*
X370874Y1330399D03*
X363805Y1326133D03*
X356784Y1343909D03*
X379860Y254987D03*
X379112Y292877D03*
X385797Y1395701D03*
X385123Y1631475D03*
X378497Y1631411D03*
X374500Y1642938D03*
X378509Y1682675D03*
X392616Y254977D03*
X392083Y293445D03*
X399935Y1311608D03*
X395933Y1312707D03*
X402973Y1330369D03*
X390029Y1329934D03*
X393699Y1402554D03*
X403125Y1419519D03*
X399134Y1419497D03*
X391293Y1631495D03*
X417765Y255296D03*
X404985Y254906D03*
X417218Y293765D03*
X404215Y293631D03*
X418616Y936164D03*
X410816D03*
X410795Y951181D03*
X414595D03*
X414626Y965580D03*
X418626D03*
X410826D03*
X418595Y951181D03*
X414600Y980093D03*
X410800D03*
X418600D03*
X414600Y994408D03*
X410800D03*
X418600D03*
X418550Y1008966D03*
X410838D03*
X414550D03*
X410816Y1023576D03*
X414591D03*
X418591D03*
X409980Y1393969D03*
X431873Y255296D03*
X429702Y293254D03*
X422395Y936164D03*
X422426Y965580D03*
X422395Y951181D03*
X422400Y980093D03*
X422350Y994408D03*
Y1008966D03*
X422391Y1023576D03*
X432063Y1311608D03*
X428061Y1312707D03*
X434983Y1330398D03*
X421224Y1329934D03*
X442265Y293430D03*
X448520Y416778D03*
X444020D03*
X442520Y470353D03*
X437520D03*
X451520D03*
X451014Y1397495D03*
X442020Y1564953D03*
X446020D03*
X452020Y1574953D03*
X437383Y1597170D03*
X458264Y260973D03*
X467736Y293914D03*
X467211Y366249D03*
X455720Y399278D03*
X462921Y425019D03*
X453020Y416778D03*
X457520D03*
X456520Y470353D03*
X461520D03*
X462704Y965580D03*
X466704Y951181D03*
Y965580D03*
X462704Y951181D03*
X458904D03*
Y965580D03*
X466704Y980093D03*
X458904D03*
X462704D03*
X466704Y994408D03*
X462704D03*
X458904D03*
X466704Y1008966D03*
X458904D03*
X462704D03*
X458904Y1023576D03*
X466704D03*
X462704D03*
X464191Y1311608D03*
X460189Y1312707D03*
X467644Y1330416D03*
X452961Y1329926D03*
X460020Y1574953D03*
X466320Y1596245D03*
X483500Y234878D03*
X474720Y363378D03*
X485020Y416778D03*
X480520D03*
X479169Y470212D03*
X474169D03*
X470504Y951181D03*
Y965580D03*
Y980093D03*
Y994408D03*
Y1008966D03*
Y1023576D03*
X485296Y1329926D03*
X478460Y1442595D03*
X501136Y293214D03*
X490720Y363378D03*
X498720D03*
X486720D03*
X499570Y424878D03*
X489520Y416778D03*
X494020D03*
X498169Y470212D03*
X493169D03*
X488169D03*
X492317Y1312707D03*
X496319Y1325034D03*
X499458Y1343855D03*
X510830Y106188D03*
X507750Y293099D03*
X506720Y363378D03*
X517720Y392878D03*
X505720D03*
X517020Y480968D03*
X517424Y1343909D03*
X506096Y1415333D03*
X518720Y363378D03*
X531720D03*
X523720D03*
X533720Y392878D03*
X521720D03*
X524445Y1326133D03*
X528447Y1347832D03*
X531610Y1366665D03*
X547330Y363258D03*
X548300Y408423D03*
X549552Y1366707D03*
X564698Y363218D03*
X554300Y408423D03*
X564300D03*
X559300D03*
X560969Y1348984D03*
X556586D03*
X557720Y1449878D03*
X552000D03*
X578582Y363173D03*
X573460Y363218D03*
X569340D03*
X571556Y375065D03*
X569152Y416503D03*
X598795Y143168D03*
X594220Y430878D03*
X606079Y121908D03*
X604725Y275146D03*
X607675Y320915D03*
X615635Y320971D03*
X618460Y121908D03*
X621536Y208592D03*
X618115Y275146D03*
X631146Y321006D03*
X623365Y320991D03*
X634500Y79878D03*
X638500D03*
X646815Y512400D03*
X642225Y1702710D03*
X646225D03*
X648320Y84278D03*
X659000Y91878D03*
X650845Y525196D03*
X654895Y518110D03*
X650794Y518123D03*
X663187Y1389711D03*
X651725Y1646210D03*
X654225Y1657710D03*
X650225Y1695710D03*
X667610Y110428D03*
X675220Y524878D03*
X680220D03*
Y511378D03*
X666425Y1408500D03*
X684643Y108901D03*
X688470Y391678D03*
X685220Y498378D03*
X695220Y524878D03*
Y511378D03*
X691321Y1390731D03*
X695425D03*
X684292Y1408586D03*
X708953Y128184D03*
X708720Y380878D03*
X713220Y390878D03*
X705220Y498378D03*
X711220D03*
X705220Y524878D03*
X701330Y1389711D03*
X704568Y1408500D03*
X711719Y1639867D03*
X728220Y380878D03*
Y390878D03*
X718220D03*
X717220Y498378D03*
X723220D03*
X729220D03*
X717220Y511378D03*
X723220D03*
X729220D03*
X722435Y1408586D03*
X715780Y1617446D03*
X719770Y1617436D03*
X723820D03*
X718830Y1649986D03*
X737093Y87993D03*
X737340Y115751D03*
X741270Y115675D03*
X733220Y380878D03*
X740200Y368241D03*
X738220Y390878D03*
X733220D03*
X735173Y524853D03*
X745220Y511378D03*
X735220D03*
X734006Y1390840D03*
X729709D03*
X743462Y1667261D03*
X739538Y1671271D03*
X760193Y93364D03*
X753089Y498393D03*
X749179Y498373D03*
X755859Y1689111D03*
X759359Y1723611D03*
X755359D03*
X764130Y113196D03*
X777220Y438378D03*
X763859Y1689111D03*
X794220Y425378D03*
X782800Y505578D03*
X783450Y516998D03*
X794600Y363216D03*
X802200D03*
X809800D03*
X809600Y383116D03*
X800498Y413142D03*
Y398542D03*
X831539Y62859D03*
X834615Y104297D03*
X835114Y117714D03*
X833715Y225084D03*
X832500Y267230D03*
X832400Y421416D03*
X828300D03*
X840200D03*
X856629Y63009D03*
X850015Y90267D03*
X858783Y224499D03*
X844200Y421416D03*
X863294Y266052D03*
X863571Y293901D03*
X867571D03*
X886503Y271423D03*
X880772Y876851D03*
X909293Y461944D03*
X913293D03*
X920747Y467743D03*
X921720Y1006878D03*
X924747Y467743D03*
X937747D03*
X933747D03*
X931496Y964703D03*
X927220Y1006878D03*
X941747Y467743D03*
X945747D03*
X947275Y976923D03*
X943750Y980168D03*
X985500Y148315D03*
X989605Y175569D03*
X985445Y175599D03*
X988835Y187969D03*
X1005735Y153959D03*
X1001395Y214439D03*
X1019939Y297429D03*
X1031270Y303578D03*
X1033268Y502318D03*
X1052705Y363211D03*
X1095457Y1641366D03*
X1099457D03*
X1115802Y1617786D03*
X1109287Y1669956D03*
X1122879Y1426015D03*
X1126117Y1444804D03*
X1120472Y1617776D03*
X1120432Y1625436D03*
X1151013Y1427035D03*
X1143984Y1444890D03*
X1160720Y183378D03*
X1155117Y1427035D03*
X1161022Y1426015D03*
X1164260Y1444804D03*
X1164830Y1648231D03*
X1159930D03*
X1163576Y1677565D03*
X1181476Y163822D03*
X1182127Y1444890D03*
X1175830Y1648231D03*
X1181930D03*
X1170930D03*
X1174576Y1677565D03*
X1195278Y136065D03*
X1193260Y1427035D03*
X1189156D03*
X1185080Y1619005D03*
X1197400Y1648541D03*
X1186830Y1648231D03*
X1192500Y1648541D03*
X1196146Y1677875D03*
X1185576Y1677565D03*
X1197240Y1694021D03*
X1192340D03*
X1195986Y1723355D03*
X1212202Y117633D03*
X1208010Y1694066D03*
X1203110D03*
X1213910Y1694331D03*
X1206756Y1723400D03*
X1220500Y207378D03*
X1218810Y1694331D03*
X1217556Y1723665D03*
X1263040Y103638D03*
X1258539Y103443D03*
X1259150Y300032D03*
X1255150D03*
X1274520Y81378D03*
X1281913Y79415D03*
X1271150Y300032D03*
X1279812Y1348068D03*
X1291823Y87785D03*
X1287913Y87735D03*
X1295767Y92232D03*
X1298407Y104983D03*
X1294937Y749481D03*
X1283280Y1366789D03*
X1311960Y52524D03*
X1309790Y62316D03*
X1311636Y72522D03*
X1307578Y72520D03*
X1308792Y91317D03*
X1310906Y100705D03*
X1314906D03*
X1311820Y1325034D03*
X1312346Y1350863D03*
X1308140Y1348930D03*
X1315058Y1343823D03*
X1300917Y1366943D03*
X1325902Y62373D03*
X1330102D03*
X1317831Y62316D03*
X1321869Y62298D03*
X1315649Y72521D03*
X1319721D03*
X1324120Y88424D03*
X1329891Y93839D03*
X1322906Y97219D03*
Y104249D03*
X1318906Y100699D03*
X1329646Y107485D03*
X1324093Y247978D03*
X1345083Y93859D03*
X1336549Y108461D03*
X1343858Y1311608D03*
X1339946Y1326133D03*
X1343044Y1335191D03*
X1347015Y1330399D03*
X1332925Y1343909D03*
X1349621Y106738D03*
X1358277Y1396111D03*
X1366124Y104045D03*
X1378550Y118677D03*
X1372074Y1312707D03*
X1376076Y1311608D03*
X1366170Y1329934D03*
X1379114Y1330369D03*
X1377075Y1419497D03*
X1394757Y936163D03*
X1386957D03*
X1390767Y965579D03*
X1394767D03*
X1394736Y951180D03*
X1390736D03*
X1386936D03*
X1386967Y965579D03*
X1394812Y980092D03*
X1390812D03*
X1387012D03*
X1390741Y994407D03*
X1386941D03*
X1394741D03*
X1394691Y1008965D03*
X1390691D03*
X1386891D03*
X1390732Y1023575D03*
X1386869D03*
X1394732D03*
X1386181Y1394169D03*
X1381066Y1419519D03*
X1385720Y1430378D03*
X1398557Y936163D03*
X1398567Y965579D03*
X1398536Y951180D03*
X1398612Y980092D03*
X1398541Y994407D03*
X1398491Y1008965D03*
X1398532Y1023575D03*
X1408204Y1311608D03*
X1404202Y1312707D03*
X1411124Y1330398D03*
X1397365Y1329934D03*
X1398700Y1600298D03*
X1427155Y1397495D03*
X1438845Y965579D03*
X1442845D03*
X1435045D03*
X1442845Y951180D03*
X1438845D03*
X1435045D03*
X1438845Y980092D03*
X1442845D03*
X1435045D03*
X1442845Y994407D03*
X1438845D03*
X1435045D03*
X1438845Y1008965D03*
X1442845D03*
X1435045D03*
X1438845Y1023575D03*
X1435045D03*
X1442845D03*
X1436330Y1312707D03*
X1440332Y1311608D03*
X1429102Y1329926D03*
X1443785Y1330416D03*
X1442573Y1652485D03*
X1451700Y291216D03*
X1445777Y364512D03*
X1449600Y396828D03*
X1446645Y951180D03*
Y965579D03*
Y980092D03*
Y994407D03*
Y1008965D03*
Y1023575D03*
X1461437Y1329926D03*
X1454938Y1442469D03*
X1454207Y1628081D03*
X1459117Y1628061D03*
X1462777Y364512D03*
X1477384Y413804D03*
X1468458Y1312707D03*
X1472460Y1325034D03*
X1475599Y1343855D03*
X1463747Y1628061D03*
X1467840Y1628118D03*
X1473527Y1658065D03*
X1489564Y364214D03*
X1493874D03*
X1481484Y364304D03*
X1489384Y413804D03*
X1493565Y1343909D03*
X1482237Y1415333D03*
X1500904Y382784D03*
X1500586Y1326133D03*
X1504588Y1347832D03*
X1507751Y1366665D03*
X1526118Y113121D03*
X1525693Y1366707D03*
X1539720Y584378D03*
X1532727Y1348984D03*
X1537110D03*
X1543779Y121294D03*
X1556747Y589431D03*
X1552720Y584378D03*
X1546312Y637732D03*
X1550162D03*
X1619515Y114575D03*
X1624353Y1423307D03*
X1627591Y1442096D03*
X1654110Y428718D03*
X1654032Y654025D03*
Y688025D03*
X1652487Y1424327D03*
X1656591D03*
X1645458Y1442182D03*
X1659610Y397218D03*
X1663610D03*
X1663376Y518104D03*
X1667376D03*
X1657632Y550430D03*
X1665706Y586072D03*
X1661506D03*
X1661132Y620525D03*
X1661120Y613978D03*
X1658085Y642127D03*
Y676127D03*
Y710127D03*
X1662496Y1423307D03*
X1665734Y1442096D03*
X1688504Y401576D03*
X1683601Y1442182D03*
X1694314Y428671D03*
X1690154Y428701D03*
X1693648Y466292D03*
X1697648D03*
X1703960Y544019D03*
X1690080Y552273D03*
X1695446Y704034D03*
X1703768Y698922D03*
X1695172Y1424436D03*
X1690875D03*
X1716875Y62485D03*
X1711832Y62249D03*
X1720895Y62485D03*
X1711832Y75737D03*
X1716965Y75725D03*
X1710426Y407679D03*
X1717686Y499493D03*
X1725520Y62378D03*
X1726608Y105900D03*
X1750918Y125183D03*
X1752324Y200508D03*
X1738290Y417356D03*
X1767638Y69632D03*
X1767891Y97336D03*
X1771891D03*
X1779226Y278120D03*
X1778810Y444078D03*
X1790738Y75003D03*
X1802150Y1499496D03*
X1797722Y1499559D03*
X1790011Y1511514D03*
X1813955Y143036D03*
X1849191Y163391D03*
X1836750Y376499D03*
G54D251*
X1280249Y133513D03*
G54D125*
X318333Y78520D03*
X316364D03*
X314395D03*
X312427D03*
X310459D03*
X308490D03*
X306521D03*
X318333Y80489D03*
X316364D03*
X314395D03*
X312427D03*
X310459D03*
X308490D03*
X306521D03*
X318333Y82457D03*
X316364D03*
X314395D03*
X312427D03*
X310459D03*
X308490D03*
X306521D03*
X318333Y84426D03*
X316364D03*
X314395D03*
X312427D03*
X310459D03*
X308490D03*
X306521D03*
X325002Y212333D03*
Y214302D03*
Y216271D03*
X326971Y212333D03*
Y214302D03*
Y216271D03*
X328939Y212333D03*
Y214302D03*
Y216271D03*
X330908Y212333D03*
Y214302D03*
Y216271D03*
X325002Y218239D03*
Y220207D03*
Y222176D03*
Y224145D03*
X326971Y218239D03*
Y220207D03*
Y222176D03*
Y224145D03*
X328939Y218239D03*
Y220207D03*
Y222176D03*
Y224145D03*
X330908Y218239D03*
Y220207D03*
Y222176D03*
Y224145D03*
X745035Y98005D03*
X743066D03*
X741097D03*
X745035Y99974D03*
X743066D03*
X741097D03*
X745035Y101942D03*
X743066D03*
X741097D03*
X745035Y103911D03*
X743066D03*
X741097D03*
X752909Y98005D03*
X750940D03*
X748971D03*
X747003D03*
X752909Y99974D03*
X750940D03*
X748971D03*
X747003D03*
X752909Y101942D03*
X750940D03*
X748971D03*
X747003D03*
X752909Y103911D03*
X750940D03*
X748971D03*
X747003D03*
X873313Y276064D03*
X871345D03*
X869376D03*
X867407D03*
X873313Y278033D03*
X871345D03*
X869376D03*
X867407D03*
X873313Y280001D03*
X871345D03*
X869376D03*
X867407D03*
X873313Y281970D03*
X871345D03*
X869376D03*
X867407D03*
X879219Y276064D03*
X877250D03*
X875281D03*
X879219Y278033D03*
X877250D03*
X875281D03*
X879219Y280001D03*
X877250D03*
X875281D03*
X879219Y281970D03*
X877250D03*
X875281D03*
X914362Y494165D03*
X916331D03*
X914362Y492196D03*
X916331D03*
X914362Y490228D03*
X916331D03*
X918299D03*
X920268D03*
X922236D03*
X914362Y488259D03*
X916331D03*
X918299D03*
X920268D03*
X922236D03*
X914362Y509913D03*
X916331D03*
X918299D03*
X920268D03*
X922236D03*
X914362Y507944D03*
X916331D03*
X918299D03*
X920268D03*
X922236D03*
X914362Y505976D03*
X916331D03*
X914362Y504007D03*
X916331D03*
X914362Y502039D03*
X916331D03*
X914362Y500070D03*
X916331D03*
X914362Y498102D03*
X916331D03*
X914362Y496133D03*
X916331D03*
X934047Y494165D03*
X936016D03*
X934047Y492196D03*
X936016D03*
X924205Y490228D03*
X926173D03*
X928142D03*
X930110D03*
X932079D03*
X934047D03*
X936016D03*
X924205Y488259D03*
X926173D03*
X928142D03*
X930110D03*
X932079D03*
X934047D03*
X936016D03*
X924205Y509913D03*
X926173D03*
X928142D03*
X930110D03*
X932079D03*
X934047D03*
X936016D03*
X924205Y507944D03*
X926173D03*
X928142D03*
X930110D03*
X932079D03*
X934047D03*
X936016D03*
X934047Y505976D03*
X936016D03*
X934047Y504007D03*
X936016D03*
X934047Y502039D03*
X936016D03*
X934047Y500070D03*
X936016D03*
X934047Y498102D03*
X936016D03*
X934047Y496133D03*
X936016D03*
X992452Y155667D03*
Y157636D03*
Y159605D03*
Y161573D03*
Y163541D03*
Y165510D03*
Y167479D03*
X994421Y155667D03*
Y157636D03*
Y159605D03*
Y161573D03*
Y163541D03*
Y165510D03*
Y167479D03*
X996389Y155667D03*
Y157636D03*
Y159605D03*
Y161573D03*
Y163541D03*
Y165510D03*
Y167479D03*
X998358Y155667D03*
Y157636D03*
Y159605D03*
Y161573D03*
Y163541D03*
Y165510D03*
Y167479D03*
X1697161Y408769D03*
Y410738D03*
Y412707D03*
X1699130Y408769D03*
Y410738D03*
Y412707D03*
X1701098Y408769D03*
Y410738D03*
Y412707D03*
X1703067Y408769D03*
Y410738D03*
Y412707D03*
X1697161Y414675D03*
Y416643D03*
Y418612D03*
Y420581D03*
X1699130Y414675D03*
Y416643D03*
Y418612D03*
Y420581D03*
X1701098Y414675D03*
Y416643D03*
Y418612D03*
Y420581D03*
X1703067Y414675D03*
Y416643D03*
Y418612D03*
Y420581D03*
X1783454Y79644D03*
X1781485D03*
X1779516D03*
X1777548D03*
X1775580D03*
X1773611D03*
X1771642D03*
X1783454Y81613D03*
X1781485D03*
X1779516D03*
X1777548D03*
X1775580D03*
X1773611D03*
X1771642D03*
X1783454Y83581D03*
X1781485D03*
X1779516D03*
X1777548D03*
X1775580D03*
X1773611D03*
X1771642D03*
X1783454Y85550D03*
X1781485D03*
X1779516D03*
X1777548D03*
X1775580D03*
X1773611D03*
X1771642D03*
G54D260*
X1316569Y268316D03*
Y275008D03*
X1325231Y268316D03*
Y275008D03*
G54D32*
X55374Y390301D03*
X618644Y148781D03*
G54D152*
X442900Y117195D03*
X450380D03*
Y107747D03*
X446640D03*
X442900D03*
X1531917Y116180D03*
X1539397D03*
Y106732D03*
X1535657D03*
X1531917D03*
G54D143*
X402220Y160951D03*
Y155833D03*
X394780D03*
Y158392D03*
Y160951D03*
X1796768Y150744D03*
X1789328D03*
X1796768Y155862D03*
X1789328Y153303D03*
Y155862D03*
G54D134*
X347677Y130002D03*
Y126262D03*
Y122522D03*
X357323D03*
Y130002D03*
X1460023Y60322D03*
Y64062D03*
Y67802D03*
X1450377D03*
Y60322D03*
G54D116*
X274299Y224782D03*
X1658169Y414202D03*
G36*
G01X947605Y1565571D02*
Y1574626D01*
X949967D01*
Y1578957D01*
X945223D01*
Y1582500D01*
X947585D01*
Y1579457D01*
X950223D01*
Y1582500D01*
X952585D01*
Y1579457D01*
X955223D01*
Y1582500D01*
X957585D01*
Y1579457D01*
X960223D01*
Y1582500D01*
X962585D01*
Y1578957D01*
X958341D01*
Y1574626D01*
X960203D01*
Y1572264D01*
X957160D01*
Y1571280D01*
X960203D01*
Y1568918D01*
X957160D01*
Y1567933D01*
X960203D01*
Y1565571D01*
X956660D01*
Y1574626D01*
X957841D01*
Y1578957D01*
X954404D01*
Y1574626D01*
X955676D01*
Y1572264D01*
X952632D01*
Y1571280D01*
X955676D01*
Y1568918D01*
X952632D01*
Y1567933D01*
X955676D01*
Y1565571D01*
X952132D01*
Y1574626D01*
X953904D01*
Y1578957D01*
X950467D01*
Y1574626D01*
X951148D01*
Y1572264D01*
X948105D01*
Y1571280D01*
X951148D01*
Y1568918D01*
X948105D01*
Y1567933D01*
X951148D01*
Y1565571D01*
X947605D01*
G37*
G36*
G01X970971D02*
Y1574626D01*
X973333D01*
Y1578957D01*
X968589D01*
Y1582500D01*
X970951D01*
Y1579457D01*
X973589D01*
Y1582500D01*
X975951D01*
Y1579457D01*
X978589D01*
Y1582500D01*
X980951D01*
Y1579457D01*
X983589D01*
Y1582500D01*
X985951D01*
Y1578957D01*
X981707D01*
Y1574626D01*
X983569D01*
Y1572264D01*
X980526D01*
Y1571280D01*
X983569D01*
Y1568918D01*
X980526D01*
Y1567933D01*
X983569D01*
Y1565571D01*
X980026D01*
Y1574626D01*
X981207D01*
Y1578957D01*
X977770D01*
Y1574626D01*
X979042D01*
Y1572264D01*
X975998D01*
Y1571280D01*
X979042D01*
Y1568918D01*
X975998D01*
Y1567933D01*
X979042D01*
Y1565571D01*
X975498D01*
Y1574626D01*
X977270D01*
Y1578957D01*
X973833D01*
Y1574626D01*
X974514D01*
Y1572264D01*
X971471D01*
Y1571280D01*
X974514D01*
Y1568918D01*
X971471D01*
Y1567933D01*
X974514D01*
Y1565571D01*
X970971D01*
G37*
G36*
G01X994337D02*
Y1574626D01*
X996699D01*
Y1578957D01*
X991955D01*
Y1582500D01*
X994317D01*
Y1579457D01*
X996955D01*
Y1582500D01*
X999317D01*
Y1579457D01*
X1001955D01*
Y1582500D01*
X1004317D01*
Y1579457D01*
X1006955D01*
Y1582500D01*
X1009317D01*
Y1578957D01*
X1005073D01*
Y1574626D01*
X1006935D01*
Y1572264D01*
X1003892D01*
Y1571280D01*
X1006935D01*
Y1568918D01*
X1003892D01*
Y1567933D01*
X1006935D01*
Y1565571D01*
X1003392D01*
Y1574626D01*
X1004573D01*
Y1578957D01*
X1001136D01*
Y1574626D01*
X1002408D01*
Y1572264D01*
X999364D01*
Y1571280D01*
X1002408D01*
Y1568918D01*
X999364D01*
Y1567933D01*
X1002408D01*
Y1565571D01*
X998864D01*
Y1574626D01*
X1000636D01*
Y1578957D01*
X997199D01*
Y1574626D01*
X997880D01*
Y1572264D01*
X994837D01*
Y1571280D01*
X997880D01*
Y1568918D01*
X994837D01*
Y1567933D01*
X997880D01*
Y1565571D01*
X994337D01*
G37*
G36*
G01X1017703D02*
Y1574626D01*
X1020065D01*
Y1578957D01*
X1015321D01*
Y1582500D01*
X1017683D01*
Y1579457D01*
X1020321D01*
Y1582500D01*
X1022683D01*
Y1579457D01*
X1025321D01*
Y1582500D01*
X1027683D01*
Y1579457D01*
X1030321D01*
Y1582500D01*
X1032683D01*
Y1578957D01*
X1028439D01*
Y1574626D01*
X1030301D01*
Y1572264D01*
X1027258D01*
Y1571280D01*
X1030301D01*
Y1568918D01*
X1027258D01*
Y1567933D01*
X1030301D01*
Y1565571D01*
X1026758D01*
Y1574626D01*
X1027939D01*
Y1578957D01*
X1024502D01*
Y1574626D01*
X1025774D01*
Y1572264D01*
X1022730D01*
Y1571280D01*
X1025774D01*
Y1568918D01*
X1022730D01*
Y1567933D01*
X1025774D01*
Y1565571D01*
X1022230D01*
Y1574626D01*
X1024002D01*
Y1578957D01*
X1020565D01*
Y1574626D01*
X1021246D01*
Y1572264D01*
X1018203D01*
Y1571280D01*
X1021246D01*
Y1568918D01*
X1018203D01*
Y1567933D01*
X1021246D01*
Y1565571D01*
X1017703D01*
G37*
G36*
G01X1041069D02*
Y1574626D01*
X1043431D01*
Y1578957D01*
X1038687D01*
Y1582500D01*
X1041049D01*
Y1579457D01*
X1043687D01*
Y1582500D01*
X1046049D01*
Y1579457D01*
X1048687D01*
Y1582500D01*
X1051049D01*
Y1579457D01*
X1053687D01*
Y1582500D01*
X1056049D01*
Y1578957D01*
X1051805D01*
Y1574626D01*
X1053667D01*
Y1572264D01*
X1050624D01*
Y1571280D01*
X1053667D01*
Y1568918D01*
X1050624D01*
Y1567933D01*
X1053667D01*
Y1565571D01*
X1050124D01*
Y1574626D01*
X1051305D01*
Y1578957D01*
X1047868D01*
Y1574626D01*
X1049140D01*
Y1572264D01*
X1046096D01*
Y1571280D01*
X1049140D01*
Y1568918D01*
X1046096D01*
Y1567933D01*
X1049140D01*
Y1565571D01*
X1045596D01*
Y1574626D01*
X1047368D01*
Y1578957D01*
X1043931D01*
Y1574626D01*
X1044612D01*
Y1572264D01*
X1041569D01*
Y1571280D01*
X1044612D01*
Y1568918D01*
X1041569D01*
Y1567933D01*
X1044612D01*
Y1565571D01*
X1041069D01*
G37*
G36*
G01X1064435D02*
Y1574626D01*
X1066797D01*
Y1578957D01*
X1062053D01*
Y1582500D01*
X1064415D01*
Y1579457D01*
X1067053D01*
Y1582500D01*
X1069415D01*
Y1579457D01*
X1072053D01*
Y1582500D01*
X1074415D01*
Y1579457D01*
X1077053D01*
Y1582500D01*
X1079415D01*
Y1578957D01*
X1075171D01*
Y1574626D01*
X1077033D01*
Y1572264D01*
X1073990D01*
Y1571280D01*
X1077033D01*
Y1568918D01*
X1073990D01*
Y1567933D01*
X1077033D01*
Y1565571D01*
X1073490D01*
Y1574626D01*
X1074671D01*
Y1578957D01*
X1071234D01*
Y1574626D01*
X1072506D01*
Y1572264D01*
X1069462D01*
Y1571280D01*
X1072506D01*
Y1568918D01*
X1069462D01*
Y1567933D01*
X1072506D01*
Y1565571D01*
X1068962D01*
Y1574626D01*
X1070734D01*
Y1578957D01*
X1067297D01*
Y1574626D01*
X1067978D01*
Y1572264D01*
X1064935D01*
Y1571280D01*
X1067978D01*
Y1568918D01*
X1064935D01*
Y1567933D01*
X1067978D01*
Y1565571D01*
X1064435D01*
G37*
G36*
G01X1087801D02*
Y1574626D01*
X1090163D01*
Y1578957D01*
X1085419D01*
Y1582500D01*
X1087781D01*
Y1579457D01*
X1090419D01*
Y1582500D01*
X1092781D01*
Y1579457D01*
X1095419D01*
Y1582500D01*
X1097781D01*
Y1579457D01*
X1100419D01*
Y1582500D01*
X1102781D01*
Y1578957D01*
X1098537D01*
Y1574626D01*
X1100399D01*
Y1572264D01*
X1097356D01*
Y1571280D01*
X1100399D01*
Y1568918D01*
X1097356D01*
Y1567933D01*
X1100399D01*
Y1565571D01*
X1096856D01*
Y1574626D01*
X1098037D01*
Y1578957D01*
X1094600D01*
Y1574626D01*
X1095872D01*
Y1572264D01*
X1092828D01*
Y1571280D01*
X1095872D01*
Y1568918D01*
X1092828D01*
Y1567933D01*
X1095872D01*
Y1565571D01*
X1092328D01*
Y1574626D01*
X1094100D01*
Y1578957D01*
X1090663D01*
Y1574626D01*
X1091344D01*
Y1572264D01*
X1088301D01*
Y1571280D01*
X1091344D01*
Y1568918D01*
X1088301D01*
Y1567933D01*
X1091344D01*
Y1565571D01*
X1087801D01*
G37*
G36*
G01X1731312Y1474558D02*
Y1483613D01*
X1733674D01*
Y1487944D01*
X1728930D01*
Y1491487D01*
X1731292D01*
Y1488444D01*
X1733930D01*
Y1491487D01*
X1736292D01*
Y1488444D01*
X1738930D01*
Y1491487D01*
X1741292D01*
Y1488444D01*
X1743930D01*
Y1491487D01*
X1746292D01*
Y1487944D01*
X1742048D01*
Y1483613D01*
X1743910D01*
Y1481251D01*
X1740867D01*
Y1480267D01*
X1743910D01*
Y1477905D01*
X1740867D01*
Y1476920D01*
X1743910D01*
Y1474558D01*
X1740367D01*
Y1483613D01*
X1741548D01*
Y1487944D01*
X1738111D01*
Y1483613D01*
X1739383D01*
Y1481251D01*
X1736339D01*
Y1480267D01*
X1739383D01*
Y1477905D01*
X1736339D01*
Y1476920D01*
X1739383D01*
Y1474558D01*
X1735839D01*
Y1483613D01*
X1737611D01*
Y1487944D01*
X1734174D01*
Y1483613D01*
X1734855D01*
Y1481251D01*
X1731812D01*
Y1480267D01*
X1734855D01*
Y1477905D01*
X1731812D01*
Y1476920D01*
X1734855D01*
Y1474558D01*
X1731312D01*
G37*
G54D242*
X1209735Y79660D03*
Y87140D03*
X1219065Y83400D03*
G54D206*
X834903Y529786D03*
G54D161*
X473500Y246362D03*
X498563Y607067D03*
X520000Y278543D03*
X549236Y1441207D03*
X688500Y1621900D03*
X1041435Y163357D03*
X1056225Y163131D03*
X1099970Y1722570D03*
X1679646Y175669D03*
X1771457Y1624646D03*
G54D170*
X494926Y1432143D03*
Y1455173D03*
X1471404Y1431721D03*
Y1454751D03*
G54D107*
X211090Y681519D03*
X1645883Y607063D03*
G54D233*
X1030333Y291567D03*
X1288040Y1365989D03*
X1320136Y1343344D03*
X1512904Y1365814D03*
G54D224*
X991369Y379186D03*
Y381154D03*
Y383123D03*
Y385091D03*
Y387060D03*
Y389028D03*
Y390997D03*
Y392965D03*
Y394934D03*
Y396902D03*
Y398871D03*
Y400839D03*
Y402808D03*
Y404776D03*
X1021881Y379186D03*
Y394934D03*
Y392965D03*
Y390997D03*
Y389028D03*
Y387060D03*
Y385091D03*
Y383123D03*
Y381154D03*
Y404776D03*
Y402808D03*
Y400839D03*
Y398871D03*
Y396902D03*
G54D117*
X269181Y224782D03*
X1653051Y414202D03*
G54D252*
X1285787Y127643D03*
G54D261*
X1388056Y1415546D03*
G54D15*
X19983Y193362D03*
Y200362D03*
X30703Y232362D03*
Y240362D03*
X35968Y401000D03*
X60090Y421746D03*
X62257Y1524094D03*
Y1532094D03*
Y1528194D03*
Y1548094D03*
Y1552094D03*
Y1544094D03*
Y1556094D03*
X84857Y391391D03*
Y395865D03*
Y382219D03*
X91284Y428319D03*
Y424319D03*
Y420319D03*
X80974Y436519D03*
Y432519D03*
X91284Y450519D03*
Y446519D03*
X90623Y667734D03*
X91518Y718879D03*
X91703Y1690362D03*
X99638Y169263D03*
X110908Y232128D03*
X107903Y493578D03*
X107933Y497374D03*
Y501374D03*
Y505374D03*
Y509374D03*
Y513374D03*
X98997Y512870D03*
X98803Y696262D03*
X110257Y1528594D03*
Y1532694D03*
Y1552594D03*
Y1556594D03*
X96171Y1593867D03*
Y1585852D03*
Y1589852D03*
X96246Y1611821D03*
Y1605867D03*
Y1623821D03*
X96156Y1634362D03*
Y1638362D03*
X99483Y1655800D03*
Y1651800D03*
X126902Y278875D03*
X126883Y274800D03*
X126902Y306236D03*
X119965Y404571D03*
X127221Y636153D03*
Y640103D03*
X122541Y1589352D03*
X127321Y1604367D03*
X127041Y1637862D03*
X124703Y1696362D03*
X130465Y396071D03*
Y388071D03*
Y392071D03*
Y384071D03*
X134433Y525374D03*
X133020Y1535855D03*
X133172Y1541874D03*
X133264Y1547935D03*
X128041Y1622321D03*
X143803Y1708362D03*
X141550Y1720092D03*
X130540Y1723182D03*
X146980Y510810D03*
Y514810D03*
Y518810D03*
Y526830D03*
X155791Y519281D03*
X151203Y1716362D03*
X161383Y413362D03*
X184879Y421383D03*
Y425383D03*
Y443383D03*
Y430883D03*
X178050Y1723592D03*
X185050Y1729092D03*
Y1733092D03*
X207874Y567981D03*
X200048Y584791D03*
X207874Y601981D03*
X200048Y618791D03*
X207874Y635981D03*
X200048Y652791D03*
X194125Y689683D03*
X196653Y675092D03*
X195933Y1535377D03*
X195874Y1539678D03*
X195766Y1548430D03*
X195674Y1552940D03*
X208203Y1709862D03*
X208101Y1714017D03*
X215037Y420735D03*
Y424735D03*
Y428735D03*
Y436735D03*
Y432735D03*
Y440735D03*
Y444735D03*
Y448735D03*
Y457222D03*
Y462235D03*
X237183Y142062D03*
X233503Y159071D03*
X225696Y1322859D03*
Y1326859D03*
X245203Y75862D03*
X250280Y115743D03*
X249491Y565976D03*
X249948Y598632D03*
X249649Y633848D03*
X245501Y703397D03*
X261964Y64455D03*
X261916Y60345D03*
X261919Y56160D03*
X260780Y87543D03*
X270036Y151203D03*
Y147203D03*
X273803Y210822D03*
X269567Y439605D03*
X269537Y451735D03*
Y447735D03*
X286783Y136962D03*
X285516Y229606D03*
X278483Y451862D03*
Y447862D03*
X290003Y569548D03*
Y566022D03*
X298400Y67513D03*
X298910Y85983D03*
Y82483D03*
X305140Y91767D03*
X293683Y139162D03*
X292603Y634283D03*
Y630757D03*
X290877Y685071D03*
Y688597D03*
X320040Y95803D03*
X320086Y99837D03*
X308083Y146702D03*
X317957Y228258D03*
X309202Y599318D03*
X317708Y595998D03*
X323883Y161562D03*
X323292Y559218D03*
X350521Y142869D03*
X339683Y141862D03*
X349680Y705779D03*
X356203Y225862D03*
X381703Y217362D03*
Y208862D03*
Y212862D03*
Y221362D03*
Y225362D03*
X387823Y1622722D03*
X388643Y119822D03*
Y132822D03*
X398415Y1398653D03*
X402404Y1537810D03*
Y1545810D03*
Y1560810D03*
Y1564810D03*
X406382Y1411231D03*
X407533Y1549942D03*
X414183Y1603500D03*
Y1615200D03*
X415703Y1672362D03*
Y1676362D03*
Y1668362D03*
X432904Y1547810D03*
Y1551810D03*
X430028Y1583466D03*
X421683Y1616600D03*
X421633Y1620402D03*
X421598Y1624692D03*
Y1628692D03*
Y1632842D03*
X422193Y1643159D03*
X422213Y1647216D03*
X421598Y1636842D03*
X449839Y145710D03*
X448311Y505483D03*
Y509483D03*
Y513483D03*
Y517483D03*
Y521483D03*
Y525483D03*
Y542519D03*
Y547519D03*
X444366Y1600154D03*
X459622Y120948D03*
X457983Y213362D03*
Y222362D03*
X453503Y1547437D03*
X471330Y1400435D03*
X471299Y1396606D03*
X469396Y1610682D03*
Y1603682D03*
X474343Y1631003D03*
X469353Y1622735D03*
X469443Y1626732D03*
X474283Y1634947D03*
X475413Y1647242D03*
Y1663242D03*
X475343Y1677462D03*
Y1681462D03*
X488656Y66565D03*
X488766Y61205D03*
X488926Y55895D03*
X492319Y309398D03*
X501643Y615612D03*
X493339Y1424033D03*
X509983Y223362D03*
X505483Y241862D03*
X509154Y1422494D03*
X520308Y168443D03*
X521793Y455062D03*
X519883Y489112D03*
X529873Y500222D03*
X519069Y500469D03*
Y505969D03*
X519883Y495112D03*
X519069Y511469D03*
Y516969D03*
Y522469D03*
Y527969D03*
Y539819D03*
X518483Y615742D03*
X539323Y99172D03*
X539383Y112512D03*
X539547Y269472D03*
X538433Y454270D03*
X555453Y127788D03*
Y137774D03*
Y153878D03*
X552703Y161362D03*
Y184862D03*
Y171862D03*
X567483Y102862D03*
Y98862D03*
X573023Y157932D03*
X582333Y157684D03*
X573703Y225362D03*
Y221362D03*
X569572Y310847D03*
X568308Y424392D03*
X568000Y446706D03*
X580553Y493212D03*
Y488212D03*
Y497212D03*
X570553Y1355247D03*
Y1358777D03*
X595303Y136314D03*
Y125314D03*
X599238Y159480D03*
X584939Y194378D03*
X584703Y230862D03*
X591635Y288527D03*
X612818Y184062D03*
X602703Y416362D03*
X604703Y444362D03*
Y449362D03*
X602882Y454600D03*
X603703Y506862D03*
Y510862D03*
X628519Y208076D03*
Y212076D03*
X630703Y234362D03*
Y230362D03*
X620703Y426362D03*
X619703Y472862D03*
Y477862D03*
Y462862D03*
Y467862D03*
X634400Y88039D03*
Y92119D03*
X648127Y140699D03*
Y149871D03*
Y154345D03*
X642617Y249202D03*
Y260202D03*
X640628Y294327D03*
Y290267D03*
Y306547D03*
X634703Y416362D03*
Y472862D03*
Y477862D03*
Y467862D03*
X636203Y526362D03*
X645203Y1714362D03*
Y1726362D03*
X649203Y184862D03*
X649703Y411362D03*
Y421362D03*
Y426362D03*
Y477862D03*
Y472862D03*
Y482862D03*
X668501Y1647557D03*
X668576Y1659557D03*
X668603Y1664862D03*
Y1676862D03*
X671703Y1712362D03*
Y1728362D03*
X693703Y76962D03*
X693936Y91668D03*
X683436Y119568D03*
Y123420D03*
X694705Y1640667D03*
X694630Y1636667D03*
X695103Y1662862D03*
Y1678862D03*
X713203Y221862D03*
X707595Y1567683D03*
Y1579683D03*
Y1571683D03*
Y1575683D03*
Y1587683D03*
Y1595683D03*
Y1591683D03*
X726616Y160788D03*
X723428Y1564088D03*
X722735Y1569493D03*
X721816Y1680400D03*
X714616D03*
X732976Y86998D03*
X733486Y101968D03*
X741216Y111252D03*
X733486Y105468D03*
X729735Y1569493D03*
X730836Y1614503D03*
X730735Y1609893D03*
X754616Y115288D03*
X754618Y119172D03*
X748728Y137864D03*
X751143Y265322D03*
Y269322D03*
X757595Y1583183D03*
X748138Y1682362D03*
Y1678362D03*
X777903Y163254D03*
X775924Y308755D03*
X776009Y303410D03*
X763703Y413212D03*
Y403212D03*
Y408212D03*
Y398212D03*
X777823Y454862D03*
Y459862D03*
X762823D03*
Y454862D03*
Y474862D03*
X762883Y493452D03*
X765103Y1379962D03*
Y1375462D03*
X765003Y1384062D03*
Y1401562D03*
Y1397262D03*
X764903Y1414762D03*
X768622Y1573793D03*
X768635Y1581893D03*
Y1577893D03*
Y1590893D03*
X763698Y1698521D03*
X782643Y274822D03*
X789109Y303410D03*
X789024Y308755D03*
X790983Y385300D03*
X778703Y393212D03*
X792903Y398212D03*
X792823Y444862D03*
Y439862D03*
Y449862D03*
Y454862D03*
Y459862D03*
Y469862D03*
X808553Y441060D03*
Y445100D03*
X808323Y454862D03*
Y459862D03*
Y449862D03*
Y464862D03*
X810135Y1573793D03*
Y1581793D03*
Y1597793D03*
Y1585793D03*
Y1605793D03*
X820783Y449200D03*
X822323Y476800D03*
Y464862D03*
Y468900D03*
Y472900D03*
X840308Y90451D03*
X842203Y135862D03*
Y129362D03*
X830460Y409260D03*
Y405260D03*
X827983Y449200D03*
X827253Y511082D03*
Y506082D03*
Y527082D03*
Y519082D03*
X851703Y129362D03*
Y135862D03*
X859286Y265057D03*
X846730Y271049D03*
X852383Y473000D03*
Y469100D03*
X852135Y1573793D03*
Y1581793D03*
Y1597793D03*
Y1585793D03*
Y1605793D03*
X874203Y171362D03*
Y176862D03*
X868983Y196500D03*
X868376Y227763D03*
Y223763D03*
X861075Y240441D03*
X859796Y280027D03*
X867526Y289311D03*
X859796Y283527D03*
X862483Y378362D03*
X867969Y386476D03*
Y402581D03*
Y398620D03*
X868021Y414276D03*
X860103Y507162D03*
Y495300D03*
X884283Y201150D03*
Y195720D03*
X884208Y192055D03*
X880926Y293347D03*
X880949Y298665D03*
X902336Y484913D03*
Y480913D03*
X902131Y493299D03*
Y489299D03*
X902116Y501573D03*
Y497573D03*
X894805Y874405D03*
X895375Y920325D03*
X907972Y975134D03*
Y971234D03*
Y992834D03*
Y988934D03*
X894135Y1573793D03*
Y1581793D03*
Y1597793D03*
Y1585793D03*
Y1605793D03*
X936135Y1593393D03*
X946398Y184912D03*
X946318Y188852D03*
X951542Y424298D03*
X951465Y428124D03*
X951438Y437844D03*
X951515Y434018D03*
X948793Y997422D03*
X973076Y356896D03*
X985407Y171483D03*
X994483Y148299D03*
X1001483D03*
X997395Y213233D03*
X1003793Y363352D03*
X1012859Y167278D03*
Y171278D03*
X1018073Y190176D03*
X1017953Y363222D03*
X1037316Y268264D03*
X1030761Y523628D03*
Y514176D03*
X1041352Y509606D03*
X1039093Y523642D03*
X1039513Y514182D03*
X1087204Y69602D03*
X1082172Y83698D03*
X1073904Y265574D03*
X1083093Y379251D03*
X1082973Y369061D03*
X1083033Y374131D03*
X1072638Y386723D03*
X1091273Y1670963D03*
X1107155Y60028D03*
X1113502Y72803D03*
Y77559D03*
X1152020Y73679D03*
X1137625Y1555301D03*
X1139033Y1597630D03*
Y1601630D03*
X1152165Y1626280D03*
X1160503Y211370D03*
X1153563Y363231D03*
X1153493Y368041D03*
X1171354Y61311D03*
Y65811D03*
X1171374Y57111D03*
X1178728Y194174D03*
Y190174D03*
Y206174D03*
Y210174D03*
Y222174D03*
X1198283Y97400D03*
Y89000D03*
Y101600D03*
X1185283Y111600D03*
X1198471Y212648D03*
X1200458Y240672D03*
Y244692D03*
X1196978Y1359636D03*
Y1363146D03*
X1216084Y53860D03*
X1207244Y61060D03*
X1211683Y93600D03*
X1212883Y113200D03*
X1211576Y164962D03*
Y176962D03*
X1213002Y171611D03*
X1210703Y200309D03*
Y195362D03*
X1206568Y1681767D03*
X1219483Y93600D03*
X1225977Y113982D03*
X1220076Y119462D03*
X1231594Y129409D03*
X1220076Y132962D03*
X1231576Y134262D03*
Y153115D03*
X1220080Y148909D03*
Y144909D03*
X1231576Y141110D03*
X1220076Y153962D03*
Y157962D03*
Y168962D03*
Y164962D03*
X1231576Y163462D03*
Y156962D03*
X1220076Y176962D03*
X1231576Y177962D03*
X1220062Y172945D03*
X1220203Y194862D03*
X1245365Y95008D03*
X1235873Y102608D03*
X1235874Y106609D03*
X1242076Y209462D03*
Y205862D03*
Y213462D03*
Y217462D03*
X1237843Y244332D03*
Y248332D03*
X1251076Y233462D03*
Y223462D03*
Y227462D03*
Y237462D03*
Y241462D03*
X1281774Y102928D03*
X1270237Y92724D03*
X1305517Y68562D03*
X1300494Y85138D03*
X1319283Y261662D03*
X1373099Y1403458D03*
X1373156Y1399053D03*
X1373099Y1407458D03*
X1382523Y1411231D03*
X1384120Y1415495D03*
X1408916Y1516435D03*
X1409156Y1532255D03*
X1408916Y1521335D03*
X1400083Y1521362D03*
X1409306Y1543475D03*
X1409156Y1537155D03*
X1409306Y1548375D03*
X1399983Y1537162D03*
Y1548362D03*
X1397891Y1565037D03*
X1402383Y1582500D03*
X1398065Y1576097D03*
X1397891Y1570037D03*
X1402383Y1594000D03*
X1398383Y1609522D03*
X1405483Y1630362D03*
Y1642362D03*
X1424366Y227948D03*
X1417883Y1593700D03*
X1427233Y1612812D03*
X1444183Y60062D03*
X1444905Y1400204D03*
X1444939Y1396269D03*
X1443883Y1598400D03*
Y1611000D03*
X1439283Y1624500D03*
Y1628700D03*
X1431483Y1637362D03*
X1454750Y1526689D03*
X1454990Y1542509D03*
X1455140Y1553729D03*
X1453143Y1590302D03*
X1474050Y64355D03*
X1469480Y1424033D03*
X1487866Y233448D03*
X1487568Y255378D03*
X1485283Y421982D03*
X1485295Y1422494D03*
X1505441Y280056D03*
X1520051Y231116D03*
Y239116D03*
Y249698D03*
Y262616D03*
X1519741Y280956D03*
X1519983Y272362D03*
X1520121Y268214D03*
X1519741Y288956D03*
X1535483Y125362D03*
Y121362D03*
X1529141Y150651D03*
X1540822Y310487D03*
X1549871Y127781D03*
X1553220Y634165D03*
X1563775Y651039D03*
X1591983Y199362D03*
X1591822Y256244D03*
X1600399Y1411169D03*
Y1415669D03*
Y1424669D03*
Y1429169D03*
Y1442669D03*
Y1447153D03*
X1639664Y624475D03*
X1638565Y652601D03*
X1639664Y658475D03*
X1638565Y686601D03*
X1639664Y692475D03*
X1638565Y720601D03*
X1644938Y180460D03*
X1647593Y414202D03*
X1645415Y614845D03*
X1663428Y195935D03*
X1657712Y524071D03*
X1657663Y520540D03*
X1657712Y528071D03*
Y532071D03*
Y540071D03*
Y536071D03*
X1665814Y594959D03*
X1664905Y607291D03*
X1656883Y631703D03*
X1657355Y649681D03*
X1656883Y665703D03*
X1657355Y683681D03*
X1656883Y699703D03*
X1657355Y717681D03*
X1671581Y1497362D03*
Y1512862D03*
Y1505362D03*
Y1524862D03*
Y1537862D03*
Y1541862D03*
Y1553557D03*
X1671656Y1565557D03*
Y1585321D03*
X1688978Y473878D03*
Y469878D03*
X1689003Y465940D03*
X1687414Y478790D03*
Y482790D03*
Y488290D03*
X1682971Y491790D03*
X1686552Y552241D03*
X1695487Y401485D03*
X1690116Y424694D03*
X1696759Y518107D03*
Y513107D03*
Y541507D03*
Y537507D03*
Y545507D03*
Y553527D03*
X1704950Y723005D03*
X1702231Y1500862D03*
Y1520362D03*
Y1541362D03*
X1702511Y1564057D03*
X1703231Y1583821D03*
X1714763Y165909D03*
X1714812Y161900D03*
Y157892D03*
X1714763Y170326D03*
X1718010Y424340D03*
Y420340D03*
X1713563Y499412D03*
X1707518Y531613D03*
X1710403Y701062D03*
X1735277Y61639D03*
X1735325Y65749D03*
X1735280Y57454D03*
X1736101Y88787D03*
X1725401Y116867D03*
X1729517Y181234D03*
X1729348Y177072D03*
Y173072D03*
X1722912Y490869D03*
Y486869D03*
Y482869D03*
Y494869D03*
X1730862Y490869D03*
Y486869D03*
Y480669D03*
X1723632Y1496270D03*
X1754142Y187509D03*
X1754070Y364048D03*
X1754203Y377452D03*
X1754070Y368048D03*
X1754203Y382952D03*
X1763521Y68637D03*
X1764031Y83607D03*
Y87107D03*
X1767910Y364148D03*
X1767703Y372452D03*
X1767910Y368148D03*
X1767703Y377452D03*
X1771761Y92891D03*
X1785161Y96927D03*
X1785119Y100939D03*
X1774858Y173903D03*
Y178403D03*
X1773034Y461393D03*
Y465893D03*
Y470193D03*
X1802782Y161465D03*
X1791871Y1506538D03*
X1818782Y413432D03*
Y417432D03*
X1825670Y170162D03*
X1832362Y399185D03*
X1826822Y434202D03*
X1835434Y453921D03*
X1835424Y467321D03*
Y463193D03*
X1845943Y172187D03*
X1838788Y192678D03*
G54D24*
X36595Y388035D03*
X46834Y366395D03*
X55190D03*
X54333Y1609817D03*
X57833Y1669317D03*
X53333D03*
X49333D03*
X61000Y1679183D03*
X70333Y1618817D03*
X69833Y1669317D03*
X73833D03*
X77833D03*
X65000Y1679183D03*
X90518Y640088D03*
X82014Y702575D03*
X92096Y697663D03*
X84474Y1523077D03*
X87500Y1564577D03*
X91500D03*
X81833Y1669317D03*
X90297Y1669363D03*
X85833Y1669317D03*
X108643Y526800D03*
X96774Y1529077D03*
X108800Y1611883D03*
X117597Y494374D03*
X113597D03*
X114720Y1683345D03*
X120910Y1726530D03*
X130317Y483296D03*
X135317D03*
X138489Y528432D03*
X134557Y1731165D03*
X149174Y483296D03*
X152470Y505846D03*
X149568Y1392653D03*
X152806Y1411442D03*
X158570Y1526488D03*
X154581Y1526447D03*
X159014Y1576892D03*
X154580D03*
X170673Y1412428D03*
X175067Y1733075D03*
X190110Y572455D03*
X187711Y1392653D03*
X181806Y1393673D03*
X177702D03*
X190949Y1411442D03*
X205320Y673045D03*
X201220D03*
X207716Y1411728D03*
X220387Y1393782D03*
X216090D03*
X212120Y1709745D03*
X237220Y65345D03*
X241220D03*
X249220D03*
X245220D03*
X251487Y107743D03*
X263580Y224085D03*
X270240Y242265D03*
X267759Y257714D03*
X271821D03*
X275797Y127026D03*
X276491Y257714D03*
X281077D03*
X286481D03*
X289274Y296371D03*
X284515D03*
X302517Y71475D03*
X301315Y98782D03*
X305315D03*
X291759Y257714D03*
X304651D03*
X298184Y296371D03*
X302765D03*
X293763D03*
X302684Y562850D03*
X303551Y1350799D03*
X322155Y235202D03*
X317995Y235232D03*
X317129Y257714D03*
X306736Y296371D03*
X316463D03*
X307019Y1369520D03*
X325617Y76846D03*
X338267Y213610D03*
X329648Y257660D03*
X329002Y296371D03*
X335679Y1328001D03*
X338917Y1346790D03*
X336205Y1353830D03*
X331773Y1351936D03*
X324656Y1369674D03*
X354672Y258151D03*
X342000Y258070D03*
X354145Y296049D03*
X341295Y295697D03*
X367306Y258269D03*
X366498Y295722D03*
X367717Y1314575D03*
X366903Y1338158D03*
X370874Y1333366D03*
X363805Y1329100D03*
X356784Y1346876D03*
X379860Y257954D03*
X379112Y295844D03*
X385797Y1398668D03*
X385123Y1634442D03*
X378497Y1634378D03*
X374500Y1645905D03*
X378509Y1685642D03*
X392616Y257944D03*
X392083Y296412D03*
X399935Y1314575D03*
X395933Y1315674D03*
X402973Y1333336D03*
X390029Y1332901D03*
X393699Y1405521D03*
X403125Y1422486D03*
X399134Y1422464D03*
X391293Y1634462D03*
X417765Y258263D03*
X404985Y257873D03*
X417218Y296732D03*
X404215Y296598D03*
X418616Y939131D03*
X410816D03*
X410795Y954148D03*
X414595D03*
X418595D03*
X414626Y968547D03*
X418626D03*
X410826D03*
X414600Y983060D03*
X410800D03*
X414600Y997375D03*
X410800D03*
X418600Y983060D03*
Y997375D03*
X418550Y1011933D03*
X410838D03*
X414550D03*
X410816Y1026543D03*
X414591D03*
X418591D03*
X409980Y1396936D03*
X431873Y258263D03*
X429702Y296221D03*
X422395Y939131D03*
Y954148D03*
X422426Y968547D03*
X422400Y983060D03*
X422350Y997375D03*
Y1011933D03*
X422391Y1026543D03*
X432063Y1314575D03*
X428061Y1315674D03*
X434983Y1333365D03*
X421224Y1332901D03*
X442265Y296397D03*
X448520Y419745D03*
X444020D03*
X442520Y473320D03*
X437520D03*
X451520D03*
X451014Y1400462D03*
X442020Y1567920D03*
X446020D03*
X452020Y1577920D03*
X437383Y1600137D03*
X458264Y263940D03*
X467736Y296881D03*
X467211Y369216D03*
X455720Y402245D03*
X462921Y427986D03*
X453020Y419745D03*
X457520D03*
X456520Y473320D03*
X461520D03*
X466704Y954148D03*
X462704D03*
X458904D03*
X462704Y968547D03*
X466704D03*
X458904D03*
X466704Y997375D03*
Y983060D03*
X458904D03*
X462704D03*
Y997375D03*
X458904D03*
X466704Y1011933D03*
X458904D03*
X462704D03*
X458904Y1026543D03*
X466704D03*
X462704D03*
X464191Y1314575D03*
X460189Y1315674D03*
X467644Y1333383D03*
X452961Y1332893D03*
X460020Y1577920D03*
X466320Y1599212D03*
X483500Y237845D03*
X474720Y366345D03*
X485020Y419745D03*
X480520D03*
X479169Y473179D03*
X474169D03*
X470504Y954148D03*
Y968547D03*
Y983060D03*
Y997375D03*
Y1011933D03*
Y1026543D03*
X485296Y1332893D03*
X478460Y1445562D03*
X501136Y296181D03*
X490720Y366345D03*
X498720D03*
X486720D03*
X499570Y427845D03*
X489520Y419745D03*
X494020D03*
X498169Y473179D03*
X493169D03*
X488169D03*
X492317Y1315674D03*
X496319Y1328001D03*
X499458Y1346822D03*
X510830Y109155D03*
X507750Y296066D03*
X506720Y366345D03*
X517720Y395845D03*
X505720D03*
X517020Y483935D03*
X517424Y1346876D03*
X506096Y1418300D03*
X518720Y366345D03*
X531720D03*
X523720D03*
X533720Y395845D03*
X521720D03*
X524445Y1329100D03*
X528447Y1350799D03*
X531610Y1369632D03*
X547330Y366225D03*
X548300Y411390D03*
X549552Y1369674D03*
X564698Y366185D03*
X554300Y411390D03*
X564300D03*
X559300D03*
X560969Y1351951D03*
X556586D03*
X557720Y1452845D03*
X552000D03*
X571556Y378032D03*
X578582Y366140D03*
X573460Y366185D03*
X569340D03*
X569152Y419470D03*
X598795Y146135D03*
X594220Y433845D03*
X606079Y124875D03*
X604725Y278113D03*
X607675Y323882D03*
X615635Y323938D03*
X618460Y124875D03*
X621536Y211559D03*
X618115Y278113D03*
X631146Y323973D03*
X623365Y323958D03*
X634500Y82845D03*
X638500D03*
X646815Y515367D03*
X642225Y1705677D03*
X646225D03*
X648320Y87245D03*
X659000Y94845D03*
X654895Y521077D03*
X650794Y521090D03*
X650845Y528163D03*
X663187Y1392678D03*
X651725Y1649177D03*
X654225Y1660677D03*
X650225Y1698677D03*
X667610Y113395D03*
X680220Y514345D03*
X675220Y527845D03*
X680220D03*
X666425Y1411467D03*
X684643Y111868D03*
X688470Y394645D03*
X685220Y501345D03*
X695220Y514345D03*
Y527845D03*
X691321Y1393698D03*
X695425D03*
X684292Y1411553D03*
X708953Y131151D03*
X708720Y383845D03*
X713220Y393845D03*
X705220Y501345D03*
X711220D03*
X705220Y527845D03*
X701330Y1392678D03*
X704568Y1411467D03*
X711719Y1642834D03*
X728220Y393845D03*
Y383845D03*
X718220Y393845D03*
X717220Y501345D03*
X723220D03*
X729220D03*
X717220Y514345D03*
X723220D03*
X729220D03*
X722435Y1411553D03*
X715780Y1620413D03*
X719770Y1620403D03*
X723820D03*
X718830Y1652953D03*
X737093Y90960D03*
X737340Y118718D03*
X741270Y118642D03*
X740200Y371208D03*
X738220Y393845D03*
X733220D03*
Y383845D03*
X745220Y514345D03*
X735220D03*
X735173Y527820D03*
X734006Y1393807D03*
X729709D03*
X743462Y1670228D03*
X739538Y1674238D03*
X760193Y96331D03*
X753089Y501360D03*
X749179Y501340D03*
X755859Y1692078D03*
X759359Y1726578D03*
X755359D03*
X764130Y116163D03*
X777220Y441345D03*
X763859Y1692078D03*
X794220Y428345D03*
X782800Y508545D03*
X783450Y519965D03*
X794600Y366183D03*
X802200D03*
X809800D03*
X809600Y386083D03*
X800498Y401509D03*
Y416109D03*
X831539Y65826D03*
X834615Y107264D03*
X835114Y120681D03*
X833715Y228051D03*
X832500Y270197D03*
X832400Y424383D03*
X828300D03*
X840200D03*
X856629Y65976D03*
X850015Y93234D03*
X858783Y227466D03*
X844200Y424383D03*
X863294Y269019D03*
X863571Y296868D03*
X867571D03*
X886503Y274390D03*
X880772Y879818D03*
X909293Y464911D03*
X913293D03*
X920747Y470710D03*
X921720Y1009845D03*
X924747Y470710D03*
X937747D03*
X933747D03*
X931496Y967670D03*
X927220Y1009845D03*
X941747Y470710D03*
X945747D03*
X947275Y979890D03*
X943750Y983135D03*
X985500Y151282D03*
X989605Y178536D03*
X985445Y178566D03*
X988835Y190936D03*
X1005735Y156926D03*
X1001395Y217406D03*
X1019939Y300396D03*
X1031270Y306545D03*
X1033268Y505285D03*
X1052705Y366178D03*
X1095457Y1644333D03*
X1099457D03*
X1115802Y1620753D03*
X1109287Y1672923D03*
X1122879Y1428982D03*
X1126117Y1447771D03*
X1120472Y1620743D03*
X1120432Y1628403D03*
X1151013Y1430002D03*
X1143984Y1447857D03*
X1160720Y186345D03*
X1155117Y1430002D03*
X1161022Y1428982D03*
X1164260Y1447771D03*
X1164830Y1651198D03*
X1159930D03*
X1163576Y1680532D03*
X1181476Y166789D03*
X1182127Y1447857D03*
X1175830Y1651198D03*
X1181930D03*
X1170930D03*
X1174576Y1680532D03*
X1195278Y139032D03*
X1193260Y1430002D03*
X1189156D03*
X1185080Y1621972D03*
X1197400Y1651508D03*
X1186830Y1651198D03*
X1192500Y1651508D03*
X1196146Y1680842D03*
X1185576Y1680532D03*
X1197240Y1696988D03*
X1192340D03*
X1195986Y1726322D03*
X1212202Y120600D03*
X1208010Y1697033D03*
X1203110D03*
X1213910Y1697298D03*
X1206756Y1726367D03*
X1220500Y210345D03*
X1218810Y1697298D03*
X1217556Y1726632D03*
X1263040Y106605D03*
X1258539Y106410D03*
X1259150Y302999D03*
X1255150D03*
X1274520Y84345D03*
X1281913Y82382D03*
X1271150Y302999D03*
X1279812Y1351035D03*
X1291823Y90752D03*
X1287913Y90702D03*
X1295767Y95199D03*
X1298407Y107950D03*
X1294937Y752448D03*
X1283280Y1369756D03*
X1311960Y55491D03*
X1309790Y65283D03*
X1311636Y75489D03*
X1307578Y75487D03*
X1308792Y94284D03*
X1310906Y103672D03*
X1314906D03*
X1311820Y1328001D03*
X1312346Y1353830D03*
X1308140Y1351897D03*
X1315058Y1346790D03*
X1300917Y1369910D03*
X1325902Y65340D03*
X1330102D03*
X1317831Y65283D03*
X1321869Y65265D03*
X1315649Y75488D03*
X1319721D03*
X1324120Y91391D03*
X1329891Y96806D03*
X1322906Y100186D03*
X1318906Y103666D03*
X1329646Y110452D03*
X1322906Y107216D03*
X1324093Y250945D03*
X1345083Y96826D03*
X1336549Y111428D03*
X1343858Y1314575D03*
X1339946Y1329100D03*
X1343044Y1338158D03*
X1347015Y1333366D03*
X1332925Y1346876D03*
X1349621Y109705D03*
X1358277Y1399078D03*
X1366124Y107012D03*
X1378550Y121644D03*
X1372074Y1315674D03*
X1376076Y1314575D03*
X1366170Y1332901D03*
X1379114Y1333336D03*
X1377075Y1422464D03*
X1394757Y939130D03*
X1386957D03*
X1394736Y954147D03*
X1390736D03*
X1386936D03*
X1390767Y968546D03*
X1394767D03*
X1386967D03*
X1390741Y997374D03*
X1386941D03*
X1394812Y983059D03*
X1390812D03*
X1387012D03*
X1394741Y997374D03*
X1394691Y1011932D03*
X1390691D03*
X1386891D03*
X1390732Y1026542D03*
X1386869D03*
X1394732D03*
X1386181Y1397136D03*
X1381066Y1422486D03*
X1385720Y1433345D03*
X1398557Y939130D03*
X1398536Y954147D03*
X1398567Y968546D03*
X1398612Y983059D03*
X1398541Y997374D03*
X1398491Y1011932D03*
X1398532Y1026542D03*
X1408204Y1314575D03*
X1404202Y1315674D03*
X1411124Y1333365D03*
X1397365Y1332901D03*
X1398700Y1603265D03*
X1427155Y1400462D03*
X1442845Y954147D03*
X1438845D03*
X1435045D03*
X1438845Y968546D03*
X1442845D03*
X1435045D03*
X1438845Y983059D03*
X1442845D03*
X1435045D03*
X1442845Y997374D03*
X1438845D03*
X1435045D03*
X1438845Y1011932D03*
X1442845D03*
X1435045D03*
X1438845Y1026542D03*
X1435045D03*
X1442845D03*
X1436330Y1315674D03*
X1440332Y1314575D03*
X1429102Y1332893D03*
X1443785Y1333383D03*
X1442573Y1655452D03*
X1451700Y294183D03*
X1445777Y367479D03*
X1449600Y399795D03*
X1446645Y954147D03*
Y968546D03*
Y983059D03*
Y997374D03*
Y1011932D03*
Y1026542D03*
X1461437Y1332893D03*
X1454938Y1445436D03*
X1454207Y1631048D03*
X1459117Y1631028D03*
X1462777Y367479D03*
X1477384Y416771D03*
X1468458Y1315674D03*
X1472460Y1328001D03*
X1475599Y1346822D03*
X1463747Y1631028D03*
X1467840Y1631085D03*
X1473527Y1661032D03*
X1489564Y367181D03*
X1493874D03*
X1481484Y367271D03*
X1489384Y416771D03*
X1493565Y1346876D03*
X1482237Y1418300D03*
X1500904Y385751D03*
X1500586Y1329100D03*
X1504588Y1350799D03*
X1507751Y1369632D03*
X1526118Y116088D03*
X1525693Y1369674D03*
X1539720Y587345D03*
X1532727Y1351951D03*
X1537110D03*
X1543779Y124261D03*
X1556747Y592398D03*
X1552720Y587345D03*
X1546312Y640699D03*
X1550162D03*
X1619515Y117542D03*
X1624353Y1426274D03*
X1627591Y1445063D03*
X1654110Y431685D03*
X1654032Y656992D03*
Y690992D03*
X1652487Y1427294D03*
X1656591D03*
X1645458Y1445149D03*
X1659610Y400185D03*
X1663610D03*
X1663376Y521071D03*
X1667376D03*
X1657632Y553397D03*
X1665706Y589039D03*
X1661506D03*
X1661132Y623492D03*
X1661120Y616945D03*
X1658085Y645094D03*
Y679094D03*
Y713094D03*
X1662496Y1426274D03*
X1665734Y1445063D03*
X1688504Y404543D03*
X1683601Y1445149D03*
X1694314Y431638D03*
X1690154Y431668D03*
X1693648Y469259D03*
X1697648D03*
X1703960Y546986D03*
X1690080Y555240D03*
X1703768Y701889D03*
X1695446Y707001D03*
X1695172Y1427403D03*
X1690875D03*
X1716875Y65452D03*
X1711832Y65216D03*
X1720895Y65452D03*
X1711832Y78704D03*
X1716965Y78692D03*
X1710426Y410646D03*
X1717686Y502460D03*
X1725520Y65345D03*
X1726608Y108867D03*
X1750918Y128150D03*
X1752324Y203475D03*
X1738290Y420323D03*
X1767638Y72599D03*
X1767891Y100303D03*
X1771891D03*
X1779226Y281087D03*
X1778810Y447045D03*
X1790738Y77970D03*
X1802150Y1502463D03*
X1797722Y1502526D03*
X1790011Y1514481D03*
X1813955Y146003D03*
X1849191Y166358D03*
X1836750Y379466D03*
G54D171*
X518430Y291864D03*
Y305446D03*
G54D108*
X218862Y685948D03*
X1638111Y602634D03*
G54D126*
X312277Y152338D03*
X321333Y148598D03*
Y156078D03*
X862232Y183600D03*
X871288Y187340D03*
X862232Y191080D03*
X1656982Y201640D03*
Y209120D03*
X1666038Y205380D03*
G54D144*
X393415Y209949D03*
Y212508D03*
Y215067D03*
Y217626D03*
Y220185D03*
Y222744D03*
Y225303D03*
X416415Y217626D03*
Y215067D03*
Y212508D03*
Y209949D03*
Y225303D03*
Y222744D03*
Y220185D03*
X471000Y212685D03*
Y215244D03*
Y217803D03*
Y220362D03*
Y222921D03*
Y225480D03*
Y228039D03*
X494000Y217803D03*
Y215244D03*
Y212685D03*
Y228039D03*
Y225480D03*
Y222921D03*
Y220362D03*
X598416Y222287D03*
Y224846D03*
Y227406D03*
Y229965D03*
X616014D03*
Y227406D03*
Y224846D03*
Y222287D03*
X1436383Y222771D03*
Y225330D03*
Y227889D03*
Y230448D03*
Y233007D03*
Y235566D03*
Y238125D03*
X1435880Y251265D03*
Y253824D03*
Y256383D03*
Y258942D03*
Y261501D03*
Y264060D03*
Y266619D03*
X1459383Y233007D03*
Y230448D03*
Y227889D03*
Y225330D03*
Y222771D03*
Y238125D03*
Y235566D03*
X1458880Y266619D03*
Y264060D03*
Y261501D03*
Y258942D03*
Y256383D03*
Y253824D03*
Y251265D03*
G54D207*
X892000Y886962D03*
X887000D03*
X882000D03*
Y907762D03*
X887000D03*
X892000D03*
X897000Y886962D03*
Y907762D03*
X1540989Y601238D03*
Y622038D03*
X1555989Y601238D03*
X1550989D03*
X1545989D03*
Y622038D03*
X1550989D03*
X1555989D03*
G54D33*
X59272Y1318588D03*
Y1322328D03*
Y1326068D03*
X69508Y1318588D03*
Y1326068D03*
X1753305Y1323508D03*
Y1316028D03*
X1743069D03*
Y1319768D03*
Y1323508D03*
G54D180*
X646505Y1665405D03*
X643945D03*
X641386D03*
Y1682983D03*
X643945D03*
X646505D03*
X649064Y1665405D03*
Y1682983D03*
X711558Y1651562D03*
X708999D03*
X706439D03*
X703880D03*
Y1669140D03*
X706439D03*
X708999D03*
X711558D03*
G54D42*
X93400Y280203D03*
Y282762D03*
Y285321D03*
Y297703D03*
Y300262D03*
Y302821D03*
X100880Y282762D03*
Y280203D03*
Y285321D03*
Y297703D03*
Y302821D03*
Y300262D03*
X412386Y1547487D03*
Y1550046D03*
X419866D03*
Y1547487D03*
X412386Y1552605D03*
X419866D03*
X575124Y257291D03*
Y252173D03*
X567644D03*
Y254732D03*
Y257291D03*
X591355Y164717D03*
X583875D03*
Y167276D03*
X591355Y169835D03*
X583875D03*
X609419Y252407D03*
Y254966D03*
Y257525D03*
X616899D03*
Y254966D03*
Y252407D03*
X832084Y471682D03*
Y474241D03*
Y476800D03*
X839564D03*
Y474241D03*
Y471682D03*
X838530Y500523D03*
Y505641D03*
X846010D03*
Y503082D03*
Y500523D03*
X1092381Y73343D03*
Y78461D03*
X1099861D03*
Y75902D03*
Y73343D03*
X1298814Y52503D03*
Y55062D03*
Y57621D03*
X1306294Y52503D03*
Y57621D03*
X1427940Y1585323D03*
Y1587882D03*
Y1590441D03*
X1435420D03*
Y1585323D03*
X1798179Y405497D03*
Y408056D03*
Y410615D03*
X1798168Y418775D03*
Y421334D03*
Y423893D03*
X1812549Y371171D03*
Y366053D03*
X1805069D03*
Y368612D03*
Y371171D03*
X1813109Y390411D03*
Y385293D03*
X1805629D03*
Y387852D03*
Y390411D03*
X1805659Y410615D03*
Y408056D03*
Y405497D03*
X1805648Y423893D03*
Y421334D03*
Y418775D03*
X1830565Y182361D03*
Y177243D03*
X1823085D03*
Y179802D03*
Y182361D03*
G54D216*
X963586Y1595126D03*
Y1612842D03*
X995198Y1595142D03*
Y1612858D03*
X1026798Y1595142D03*
Y1612858D03*
X1058398Y1595142D03*
Y1612858D03*
G54D225*
X1004657Y379678D03*
X1002688D03*
X1000719D03*
X998751D03*
X996782D03*
Y404284D03*
X998751D03*
X1000719D03*
X1002688D03*
X1004657D03*
X1016468Y379678D03*
X1014499D03*
X1012531D03*
X1010562D03*
X1008593D03*
X1006625D03*
Y404284D03*
X1008593D03*
X1010562D03*
X1012531D03*
X1014499D03*
X1016468D03*
G54D243*
X1208885Y100060D03*
Y103800D03*
Y107540D03*
X1219515Y100060D03*
Y107540D03*
X1710959Y210080D03*
Y215080D03*
Y220080D03*
Y225080D03*
G54D135*
X347876Y148462D03*
Y152202D03*
Y155942D03*
X357324Y148462D03*
Y155942D03*
X548670Y442656D03*
Y446396D03*
Y450136D03*
X558118Y442656D03*
Y450136D03*
X1516776Y122122D03*
Y129602D03*
X1526224D03*
Y125862D03*
Y122122D03*
G54D51*
X88406Y708379D03*
X1701838Y712505D03*
G54D162*
X470654Y303145D03*
X504054Y302445D03*
G54D270*
X1651534Y604566D03*
G54D60*
X86274Y1538094D03*
G54D153*
X450000Y278543D03*
X460000D03*
X470000D03*
X483500Y246362D03*
X480000Y278543D03*
X493500Y246362D03*
X490000Y278543D03*
X500000D03*
X510000D03*
X518563Y607067D03*
X508563D03*
X559236Y1441207D03*
X569236D03*
X688500Y1601900D03*
Y1611900D03*
X1041435Y143357D03*
Y153357D03*
X1056225Y143131D03*
Y153131D03*
X1099970Y1702570D03*
Y1712570D03*
X1689646Y115669D03*
X1679646D03*
X1689646Y125669D03*
Y135669D03*
X1679646Y125669D03*
Y135669D03*
X1689646Y145669D03*
Y155669D03*
X1679646Y145669D03*
Y155669D03*
X1689646Y165669D03*
X1679646D03*
X1689646Y175669D03*
X1771457Y1634646D03*
Y1644646D03*
G54D234*
X1055563Y253771D03*
X1080759D03*
G54D61*
X79187Y1543015D03*
G54D43*
X94705Y704442D03*
X1708137Y708568D03*
G54D217*
X969075Y150629D03*
Y166377D03*
G54D253*
X1283688Y129742D03*
G54D271*
X1643670Y602634D03*
G54D154*
X451062Y364503D03*
X448503D03*
X445944D03*
Y387503D03*
X448503D03*
X451062D03*
X451421Y434003D03*
X448862D03*
X446303D03*
X443744D03*
Y457003D03*
X446303D03*
X448862D03*
X451421D03*
X461298Y364503D03*
X458739D03*
X456180D03*
X453621D03*
Y387503D03*
X456180D03*
X458739D03*
X461298D03*
X459098Y434003D03*
X456539D03*
X453980D03*
Y457003D03*
X456539D03*
X459098D03*
X482952Y433862D03*
X480393D03*
Y456862D03*
X482952D03*
X495747Y433862D03*
X493188D03*
X490629D03*
X488070D03*
X485511D03*
Y456862D03*
X488070D03*
X490629D03*
X493188D03*
X495747D03*
X550024Y373573D03*
Y396573D03*
X565378Y373573D03*
X562819D03*
X560260D03*
X557701D03*
X555142D03*
X552583D03*
Y396573D03*
X555142D03*
X557701D03*
X560260D03*
X562819D03*
X565378D03*
X842596Y58448D03*
X840037D03*
Y81448D03*
X842596D03*
X847715Y58448D03*
X845156D03*
Y81448D03*
X847715D03*
X1460718Y378996D03*
X1458159D03*
X1455600D03*
Y401996D03*
X1458159D03*
X1460718D03*
X1470954Y378996D03*
X1468395D03*
X1465836D03*
X1463277D03*
Y401996D03*
X1465836D03*
X1468395D03*
X1470954D03*
X1492002Y378788D03*
X1489443D03*
X1486884D03*
X1484325D03*
X1481766D03*
X1479207D03*
Y401788D03*
X1481766D03*
X1484325D03*
X1486884D03*
X1489443D03*
X1492002D03*
X1494561Y378788D03*
Y401788D03*
G54D190*
X746517Y126419D03*
X757935D03*
G54D235*
X1079225Y55682D03*
Y59422D03*
Y63162D03*
X1088673Y55682D03*
Y63162D03*
X1223507Y54100D03*
X1232955D03*
X1223507Y61580D03*
X1232955D03*
Y57840D03*
G54D34*
X61771Y1631013D03*
X59212D03*
X56653D03*
Y1654045D03*
X59212D03*
X61771D03*
X77126Y1631013D03*
X74567D03*
X72008D03*
X69449D03*
X66889D03*
X64330D03*
Y1654045D03*
X66889D03*
X69449D03*
X72008D03*
X74567D03*
X77126D03*
X79685Y1631013D03*
Y1654045D03*
G54D145*
X397819Y1403108D03*
Y1408908D03*
X651490Y220802D03*
Y226602D03*
X656926Y220797D03*
Y226597D03*
X982385Y213233D03*
Y207433D03*
X987285D03*
Y213233D03*
X1047371Y367937D03*
Y373737D03*
X1133220Y1612190D03*
Y1606390D03*
X1542018Y298126D03*
Y303926D03*
X1750847Y280163D03*
X1745000Y290962D03*
Y296762D03*
X1750500Y296962D03*
X1750847Y285963D03*
X1750500Y302762D03*
X1830852Y1503991D03*
Y1509791D03*
G54D136*
X362889Y217622D03*
X371551Y221362D03*
X362889Y225102D03*
X513979Y444062D03*
X522641Y440322D03*
Y447802D03*
X660941Y110412D03*
X652279Y106672D03*
Y114152D03*
X843669Y374622D03*
Y382102D03*
X852331Y378362D03*
X1769520Y433793D03*
X1778182Y430053D03*
Y437533D03*
G54D262*
X1511063Y299780D03*
X1515393Y297812D03*
Y301748D03*
G54D172*
X536127Y250962D03*
X544001Y254702D03*
X536127Y258442D03*
X642563Y495000D03*
X650437Y491260D03*
Y498740D03*
X755505Y1674823D03*
Y1682303D03*
X763379Y1678563D03*
X793693Y505972D03*
X793673Y516142D03*
Y523622D03*
X806961Y393924D03*
Y408524D03*
Y401404D03*
Y416004D03*
X801567Y509712D03*
Y502232D03*
X801547Y519882D03*
X814835Y397664D03*
Y412264D03*
X1084394Y1650210D03*
X1076520Y1653950D03*
X1084394Y1657690D03*
G54D244*
X1212643Y228495D03*
X1210084D03*
X1207525D03*
Y236369D03*
X1210084D03*
X1212643D03*
X1313919Y81133D03*
Y89007D03*
X1329891Y72577D03*
X1327332D03*
X1324773D03*
Y80451D03*
X1327332D03*
X1329891D03*
X1319037Y81133D03*
X1316478D03*
Y89007D03*
X1319037D03*
G54D118*
X269772Y228719D03*
X271740D03*
Y220845D03*
X269772D03*
X273708Y228719D03*
Y220845D03*
X1516181Y294071D03*
X1514212D03*
X1512244D03*
X1510275D03*
Y305489D03*
X1512244D03*
X1514212D03*
X1516181D03*
X1655610Y410265D03*
X1653642D03*
Y418139D03*
X1655610D03*
X1657578Y410265D03*
Y418139D03*
G54D25*
X44967Y416860D03*
Y413710D03*
Y416860D03*
Y420010D03*
X60189Y410770D03*
Y413920D03*
Y417070D03*
Y413920D03*
X50339Y416945D03*
Y413795D03*
Y416945D03*
Y420095D03*
X65533Y410890D03*
Y414040D03*
Y417190D03*
Y414040D03*
X75585Y1517581D03*
Y1514431D03*
Y1517581D03*
Y1520731D03*
X78456Y1560677D03*
Y1557527D03*
Y1560677D03*
Y1563827D03*
X73389Y1560672D03*
Y1563822D03*
Y1560672D03*
Y1557522D03*
X80652Y1514436D03*
Y1517586D03*
D03*
X93571Y1517237D03*
Y1514087D03*
Y1517237D03*
X88426D03*
Y1514087D03*
Y1517237D03*
X80652Y1520736D03*
X93571Y1520387D03*
X88426D03*
X102250Y1560978D03*
Y1564128D03*
Y1567278D03*
Y1564128D03*
X97183Y1567273D03*
Y1564123D03*
Y1560973D03*
Y1564123D03*
X238297Y123968D03*
Y127118D03*
X499680Y85717D03*
Y88867D03*
X612740Y177372D03*
Y180522D03*
X612736Y177350D03*
Y174200D03*
X631025Y174144D03*
Y170994D03*
Y177294D03*
Y174144D03*
X625596D03*
Y170994D03*
Y177294D03*
Y174144D03*
X618352Y177412D03*
Y180562D03*
Y177412D03*
Y174262D03*
X680600Y369837D03*
Y366687D03*
Y372987D03*
Y369837D03*
X695600D03*
Y366687D03*
Y372987D03*
Y369837D03*
X690600D03*
Y366687D03*
Y372987D03*
Y369837D03*
X685600D03*
Y366687D03*
Y372987D03*
Y369837D03*
X710600D03*
Y366687D03*
Y372987D03*
Y369837D03*
X705600D03*
Y366687D03*
Y372987D03*
Y369837D03*
X700600D03*
Y366687D03*
Y372987D03*
Y369837D03*
X715600D03*
Y366687D03*
Y372987D03*
Y369837D03*
X1016770Y229573D03*
Y226423D03*
X1713418Y125092D03*
Y128242D03*
G54D181*
X667551Y149803D03*
Y151771D03*
Y153740D03*
Y155708D03*
Y165551D03*
Y167519D03*
Y169488D03*
Y171456D03*
Y173425D03*
Y175393D03*
Y177362D03*
Y179330D03*
Y181299D03*
Y183268D03*
Y185236D03*
Y187204D03*
Y189173D03*
Y191142D03*
Y193110D03*
Y195079D03*
Y197047D03*
Y199016D03*
Y200984D03*
Y202953D03*
Y204921D03*
Y206890D03*
Y208858D03*
Y210827D03*
Y212795D03*
Y214764D03*
Y216732D03*
Y218701D03*
Y220669D03*
X697276Y148819D03*
Y150787D03*
Y152756D03*
Y154724D03*
Y156693D03*
Y166535D03*
Y168504D03*
Y170472D03*
Y172441D03*
Y174409D03*
Y176378D03*
Y178346D03*
Y180315D03*
Y182283D03*
Y184252D03*
Y186220D03*
Y188189D03*
Y190157D03*
Y192126D03*
Y194094D03*
Y196063D03*
Y198031D03*
Y200000D03*
Y201968D03*
Y203937D03*
Y205905D03*
Y207874D03*
Y209842D03*
Y211811D03*
Y213779D03*
Y215748D03*
Y217716D03*
Y219685D03*
Y221653D03*
G54D226*
X994322Y382138D03*
Y384107D03*
Y386075D03*
Y388044D03*
Y390013D03*
Y391981D03*
Y393949D03*
Y395918D03*
Y397887D03*
Y399855D03*
Y401824D03*
X1018928Y395918D03*
Y393949D03*
Y391981D03*
Y390013D03*
Y388044D03*
Y386075D03*
Y384107D03*
Y382138D03*
Y401824D03*
Y399855D03*
Y397887D03*
G54D163*
X485673Y375319D03*
X479767D03*
Y382405D03*
X485673D03*
X499073Y375426D03*
X493167D03*
Y382512D03*
X499073D03*
X515173Y375319D03*
X509267D03*
Y382405D03*
X515173D03*
X513173Y404819D03*
X507267D03*
Y411905D03*
X513173D03*
X532173Y375819D03*
X526267D03*
Y382905D03*
X532173D03*
X529173Y404819D03*
X523267D03*
Y411905D03*
X529173D03*
G54D280*
X1759327Y286919D03*
G54D16*
X27737Y216362D03*
Y224362D03*
X36517Y200862D03*
Y192862D03*
X36237Y216362D03*
Y208362D03*
Y232362D03*
Y224342D03*
Y240362D03*
X33197Y302472D03*
X59291Y1520094D03*
Y1536094D03*
Y1540094D03*
Y1560094D03*
X62823Y302926D03*
X65625Y421746D03*
X78008Y424319D03*
Y420319D03*
X77707Y648574D03*
Y644564D03*
Y652564D03*
X79657Y278798D03*
Y295798D03*
Y286262D03*
Y303262D03*
X81908Y376026D03*
X81891Y386502D03*
X88318Y438519D03*
Y442519D03*
X85657Y644564D03*
Y648564D03*
Y656564D03*
Y652564D03*
X86536Y685488D03*
X85525Y694209D03*
X86525Y690644D03*
X93205Y1581852D03*
Y1597867D03*
X84155Y1589872D03*
X93280Y1601867D03*
Y1615821D03*
Y1619821D03*
X93190Y1630362D03*
Y1642362D03*
X88762Y1683071D03*
X88737Y1694362D03*
X88747Y1686622D03*
X109092Y186362D03*
X108032Y216596D03*
X111029Y282995D03*
Y278875D03*
Y274800D03*
Y300354D03*
Y306236D03*
X104967Y517925D03*
X107112Y685490D03*
X95767Y718880D03*
X107291Y1524594D03*
Y1544594D03*
Y1548594D03*
Y1536594D03*
Y1540594D03*
Y1560594D03*
Y1564594D03*
X127499Y404571D03*
X112831Y523785D03*
X125255Y656603D03*
X124255Y647103D03*
X125255Y652603D03*
X122691Y665515D03*
Y661515D03*
X122667Y669400D03*
X116250Y1535767D03*
X116352Y1541935D03*
X116423Y1548027D03*
X121737Y1678362D03*
Y1670362D03*
Y1674362D03*
X114737Y1696362D03*
X121737Y1692362D03*
Y1688362D03*
Y1708362D03*
Y1700362D03*
Y1704362D03*
X127574Y1727182D03*
Y1731182D03*
X128698Y643603D03*
X143562Y688207D03*
X142634Y1396275D03*
Y1392745D03*
X158417Y409362D03*
X143913Y415062D03*
Y423383D03*
Y427383D03*
Y419383D03*
Y431383D03*
Y435383D03*
Y439383D03*
Y443383D03*
X144014Y498810D03*
Y502810D03*
X143979Y506533D03*
X144014Y522810D03*
X157075Y1412173D03*
X148237Y1708362D03*
Y1712362D03*
X155237Y1716362D03*
X172413Y421383D03*
Y425383D03*
Y443383D03*
Y430883D03*
X165628Y1443390D03*
X180999Y393071D03*
Y385071D03*
Y389071D03*
Y405071D03*
X192068Y681291D03*
X191159Y693623D03*
X179999Y1535462D03*
X179885Y1544028D03*
X179965Y1548486D03*
X179988Y1539723D03*
X179956Y1552874D03*
Y1557874D03*
X182084Y1723592D03*
X201641Y420255D03*
Y414755D03*
Y425755D03*
Y436755D03*
Y431255D03*
Y442255D03*
Y447755D03*
Y453255D03*
Y458755D03*
Y462755D03*
Y468255D03*
X196618Y570901D03*
X197090Y588879D03*
X196618Y604901D03*
X197090Y622879D03*
X196618Y638901D03*
X197090Y656879D03*
X195218Y1412173D03*
X193385Y1719697D03*
X205135Y1718017D03*
X199142Y1733022D03*
X212071Y452735D03*
X215408Y567981D03*
X214309Y596107D03*
X215408Y601981D03*
X214309Y630107D03*
X215408Y635981D03*
X214309Y664107D03*
X211558Y673737D03*
X230537Y154126D03*
X242237Y71862D03*
X247314Y111743D03*
X256787Y458617D03*
X273784Y99183D03*
X270017Y136962D03*
X267067Y142892D03*
X267070Y159203D03*
Y155203D03*
X262737Y214022D03*
X266571Y422735D03*
X266553Y418579D03*
X266571Y426735D03*
X266603Y431039D03*
X266571Y443735D03*
X276917Y136962D03*
X277797Y210802D03*
X289137Y637809D03*
X295434Y71513D03*
X295464Y75673D03*
X296570Y151703D03*
Y156203D03*
X306236Y595318D03*
X322559Y69863D03*
X317074Y91803D03*
X320322Y563176D03*
X314732Y599926D03*
X312163Y1369807D03*
X340017Y161862D03*
X353237Y221862D03*
X346750Y709995D03*
X343186Y1347521D03*
X363717Y130162D03*
X363617Y156202D03*
X376237Y128452D03*
X376257Y124312D03*
X385677Y124322D03*
X385592Y128491D03*
X375314Y1334095D03*
X384867Y1627062D03*
X396113Y1330142D03*
X403421Y1404207D03*
Y1400684D03*
X403348Y1397038D03*
X403416Y1407727D03*
X394842Y1413619D03*
X396435Y1432571D03*
Y1427569D03*
X399438Y1541810D03*
Y1556810D03*
X419854Y67465D03*
Y62665D03*
X417714Y149373D03*
X408376Y161162D03*
X417714Y157466D03*
Y161466D03*
Y153477D03*
X409060Y1334095D03*
X415494Y1390306D03*
X408832Y1390325D03*
X405235Y1427569D03*
Y1432571D03*
X411217Y1611300D03*
Y1607400D03*
X409949Y1680267D03*
X423592Y117491D03*
X428981Y128515D03*
Y124015D03*
X428237Y214862D03*
Y209862D03*
X423237Y225362D03*
X423937Y232562D03*
Y236562D03*
Y240562D03*
X427672Y1330042D03*
X429938Y1543810D03*
Y1555810D03*
X427062Y1579466D03*
X451510Y75985D03*
X446838Y149864D03*
X436835Y498733D03*
Y504233D03*
Y509733D03*
Y515233D03*
Y520733D03*
Y526233D03*
Y542733D03*
X445345Y537483D03*
X436835Y547769D03*
Y552769D03*
X439570Y1334095D03*
X451106Y1393959D03*
X450118Y1420625D03*
Y1409125D03*
Y1413125D03*
Y1417125D03*
Y1427632D03*
Y1424125D03*
X450107Y1431134D03*
X450097Y1611923D03*
X456656Y115948D03*
X455838Y149864D03*
Y154864D03*
X460597Y1330533D03*
X466430Y1614682D03*
X466387Y1618626D03*
X472270Y66575D03*
X472244Y61129D03*
X472200Y55935D03*
X481338Y158864D03*
X480237Y391362D03*
X471698Y1334095D03*
X477983Y1400385D03*
X476588Y1411144D03*
X485167Y1631038D03*
X472447Y1643242D03*
Y1659242D03*
Y1651242D03*
Y1667242D03*
X472377Y1673462D03*
Y1685462D03*
X499597Y93582D03*
X501017Y228362D03*
X489353Y305398D03*
X489327Y313582D03*
X493237Y391362D03*
X491135Y547947D03*
X492757Y1319592D03*
X503967Y86422D03*
X507017Y209862D03*
X502517Y237862D03*
X505517Y288862D03*
X505274Y315404D03*
X508237Y420862D03*
X504035Y507819D03*
Y511819D03*
Y519819D03*
Y515819D03*
Y523819D03*
Y527819D03*
Y539819D03*
X503826Y1347521D03*
X523237Y420862D03*
X522897Y478492D03*
X526917Y489112D03*
Y495112D03*
X525355Y1338837D03*
X536337Y103352D03*
X536407Y108062D03*
X547487Y149802D03*
X535467Y442376D03*
Y450330D03*
Y446396D03*
X535954Y1370319D03*
X552487Y131756D03*
X559237Y167112D03*
Y161362D03*
X559737Y184862D03*
X554581Y253202D03*
Y257202D03*
X566706Y305247D03*
X565057Y442656D03*
X565034Y451710D03*
X570737Y167112D03*
X581967Y190092D03*
X581973Y198378D03*
Y210378D03*
Y202378D03*
Y206378D03*
X581737Y225362D03*
Y221362D03*
X575451Y262632D03*
X568932Y498546D03*
X579017Y514362D03*
X588337Y129642D03*
X595237Y174612D03*
X596331Y257532D03*
X586581Y252202D03*
X585062Y296657D03*
Y311571D03*
Y304052D03*
X591322Y363354D03*
X588087Y488212D03*
X591517Y524862D03*
X601737Y164612D03*
X611473Y202878D03*
Y207378D03*
X599947Y458688D03*
X599737Y482362D03*
X600737Y514862D03*
X618324Y184022D03*
X627081Y249202D03*
Y260202D03*
X631737Y411362D03*
X631517Y406862D03*
X631737Y426362D03*
Y421362D03*
Y441862D03*
Y431362D03*
X616737Y442862D03*
X631740Y436650D03*
X631737Y457862D03*
Y452862D03*
Y447862D03*
X616737Y457862D03*
X631737Y462862D03*
X631717Y482662D03*
X638570Y88035D03*
X638530Y92085D03*
X646517Y93362D03*
X645178Y134506D03*
X645161Y144982D03*
X646237Y161862D03*
Y166362D03*
Y171362D03*
X637237Y230362D03*
X637662Y298297D03*
Y315587D03*
Y310962D03*
Y302247D03*
X633017Y392862D03*
X646017D03*
X646517Y406862D03*
Y402362D03*
X646737Y416362D03*
Y441862D03*
Y431362D03*
Y452862D03*
Y457862D03*
Y447862D03*
Y467862D03*
Y462862D03*
X643742Y1653194D03*
X642242Y1695694D03*
X642237Y1718362D03*
Y1722362D03*
X652127Y120412D03*
X652762Y290371D03*
X656253Y1392770D03*
Y1396300D03*
X663737Y1720362D03*
X680470Y115868D03*
X670147Y391602D03*
X670694Y1412198D03*
X665589Y1642667D03*
X665610Y1655557D03*
X665535Y1651557D03*
X665637Y1672862D03*
Y1668862D03*
X668737Y1708362D03*
Y1724362D03*
Y1716362D03*
Y1732362D03*
X681917Y1442245D03*
X691664Y1632667D03*
X691739Y1644667D03*
X691749Y1648843D03*
X692137Y1658862D03*
X687137Y1670862D03*
X692137Y1666862D03*
Y1674862D03*
Y1682862D03*
X706940Y103308D03*
X710237Y161862D03*
Y157362D03*
X708837Y1412198D03*
X704659Y1563733D03*
X704629Y1583683D03*
X703597Y1607102D03*
Y1611022D03*
X704589Y1601963D03*
X718287Y1644550D03*
X718850Y1676500D03*
X730040Y95158D03*
X730010Y90998D03*
X745752Y142050D03*
X745172Y1674362D03*
X757135Y89348D03*
X751650Y111288D03*
X748217Y167537D03*
X748177Y276322D03*
X760737Y393212D03*
Y418212D03*
Y423212D03*
Y428212D03*
X759857Y464862D03*
Y469862D03*
Y488862D03*
Y483862D03*
Y479862D03*
X759867Y497659D03*
X762037Y1388562D03*
Y1392762D03*
Y1406062D03*
X761937Y1410262D03*
X754629Y1579183D03*
Y1587183D03*
Y1592183D03*
X774806Y158026D03*
X774820Y153728D03*
X777559Y299279D03*
X763759D03*
X763660Y311249D03*
X763187Y317432D03*
X775737Y413212D03*
Y408212D03*
Y403212D03*
Y398212D03*
Y418212D03*
Y423212D03*
X774857Y464862D03*
Y469862D03*
Y488862D03*
X765669Y1594893D03*
X779677Y267822D03*
Y281822D03*
X789937Y393462D03*
Y402500D03*
X789857Y464862D03*
Y474862D03*
X788417Y483262D03*
X802979Y269800D03*
X805357Y469862D03*
Y474862D03*
X807169Y1577793D03*
Y1593793D03*
Y1601793D03*
Y1609793D03*
X821625Y274885D03*
Y279885D03*
X824280Y494000D03*
X824287Y498082D03*
Y502082D03*
Y523082D03*
Y515082D03*
X831478Y58632D03*
X828237Y166862D03*
Y176362D03*
X833152Y275045D03*
Y280045D03*
X827495Y389012D03*
Y397276D03*
X827517Y384400D03*
X827494Y413260D03*
X835517Y446800D03*
X838737Y495362D03*
X848837Y162762D03*
X848427Y185812D03*
X856350Y273217D03*
X856320Y269057D03*
X849417Y476900D03*
X857137Y503162D03*
Y499062D03*
X857287Y515582D03*
Y519582D03*
X849169Y1577793D03*
Y1593793D03*
Y1601793D03*
Y1609793D03*
X871237Y166362D03*
X865003Y394620D03*
Y390620D03*
Y382415D03*
X865055Y406812D03*
Y418836D03*
X864837Y431462D03*
X879237Y176862D03*
Y171362D03*
X881232Y183169D03*
X881242Y187449D03*
X883445Y267407D03*
X877932Y289439D03*
X884839Y874405D03*
X885409Y920325D03*
X891169Y1577793D03*
Y1593793D03*
Y1601793D03*
Y1609793D03*
X933169Y1581393D03*
Y1585393D03*
Y1589393D03*
X955362Y484271D03*
X955337Y480262D03*
X955388Y540727D03*
X955389Y536806D03*
X958307Y997496D03*
X961496Y1551855D03*
X981641Y185347D03*
X981366Y276394D03*
X977811Y356910D03*
X986274Y363660D03*
X984862Y1551855D03*
X994429Y217233D03*
Y221233D03*
X993540Y363155D03*
X1015744Y195114D03*
X1015737Y199076D03*
X1013712Y203423D03*
Y210423D03*
Y214423D03*
Y218423D03*
Y222423D03*
X1008255Y363356D03*
X1018286Y517728D03*
Y512574D03*
X1008228Y1551855D03*
X1034350Y264130D03*
X1024350Y297264D03*
Y305313D03*
Y301313D03*
X1031594Y1551855D03*
X1041044Y291105D03*
X1042505Y502161D03*
X1069722Y382141D03*
X1054960Y1551855D03*
X1079206Y78553D03*
X1073681Y509645D03*
X1078326Y1551855D03*
X1076474Y1663950D03*
X1094736Y65262D03*
X1091627Y379251D03*
X1091507Y369061D03*
X1091567Y374131D03*
X1101692Y1551855D03*
X1098547Y1679870D03*
Y1675970D03*
X1097067Y1672030D03*
X1104149Y55505D03*
X1115945Y1429074D03*
Y1432604D03*
X1119127Y1612320D03*
X1119097Y1608420D03*
X1121620Y60545D03*
X1121520Y56545D03*
X1121620Y64545D03*
X1130386Y1448502D03*
X1148887Y211231D03*
X1137407Y377011D03*
X1150527Y373231D03*
X1142050Y1479313D03*
X1149487Y1618960D03*
X1168529Y1448502D03*
X1156178Y1622340D03*
Y1626220D03*
Y1630090D03*
X1160942Y1642600D03*
X1156178Y1633880D03*
X1182588Y61311D03*
X1182488Y65811D03*
X1182508Y57111D03*
X1175762Y202174D03*
Y198174D03*
Y186174D03*
Y218174D03*
Y214174D03*
X1172397Y1601100D03*
Y1609100D03*
Y1605100D03*
X1172277Y1612960D03*
X1179088D03*
X1182942Y1642600D03*
X1171942D03*
X1195317Y93200D03*
X1193493Y127804D03*
X1197492Y236592D03*
X1193512Y1642910D03*
X1193352Y1688390D03*
X1204278Y57130D03*
X1217110Y140962D03*
Y185462D03*
X1207737Y189362D03*
X1210922Y1673963D03*
X1203598Y1677873D03*
X1210852Y1681773D03*
X1204122Y1688435D03*
X1214922Y1688700D03*
X1228517Y94200D03*
Y98400D03*
X1228610Y168162D03*
Y172962D03*
X1242399Y98785D03*
X1239077Y191279D03*
X1248110Y201562D03*
X1239110Y197462D03*
X1248110Y211762D03*
Y205362D03*
Y215762D03*
Y219662D03*
X1248195Y245442D03*
X1259110Y217462D03*
Y233462D03*
Y221462D03*
Y229462D03*
Y225462D03*
Y243562D03*
Y238662D03*
Y247562D03*
X1259310Y251562D03*
X1267271Y88572D03*
Y96768D03*
X1278808Y98828D03*
X1266610Y233462D03*
X1296182Y81169D03*
X1288424Y1370043D03*
X1302551Y64572D03*
X1305280Y81775D03*
X1325081Y261514D03*
X1319327Y1347521D03*
X1351455Y1334095D03*
X1368769Y81111D03*
X1372254Y1330142D03*
X1379562Y1400684D03*
Y1404207D03*
X1370143Y1417374D03*
X1370983Y1413019D03*
X1379557Y1407727D03*
X1385201Y1334095D03*
X1391635Y1390306D03*
X1384193Y1390335D03*
X1408900Y227948D03*
X1403813Y1330042D03*
X1406925Y1565037D03*
X1406865Y1576197D03*
X1406925Y1570037D03*
X1399417Y1586400D03*
Y1590200D03*
X1402517Y1626362D03*
X1410992Y1622200D03*
X1402517Y1634362D03*
Y1638362D03*
X1415711Y1334095D03*
X1427247Y1393959D03*
X1426259Y1417125D03*
Y1413125D03*
Y1409125D03*
Y1420625D03*
Y1427632D03*
Y1424125D03*
X1426287Y1431150D03*
X1417350Y1516435D03*
X1417590Y1532255D03*
X1417350Y1521335D03*
X1417590Y1537155D03*
X1417740Y1548375D03*
Y1543475D03*
X1420787Y1603262D03*
X1424287Y1608442D03*
X1424227Y1616932D03*
X1445017Y211862D03*
Y215862D03*
X1436738Y1330533D03*
X1440197Y1590382D03*
X1440917Y1606800D03*
Y1602600D03*
X1436317Y1632900D03*
Y1620300D03*
X1441250Y1665495D03*
X1441160Y1673955D03*
X1441164Y1669629D03*
X1447839Y1334095D03*
X1454124Y1400385D03*
X1452729Y1411144D03*
X1452425Y1560037D03*
Y1565037D03*
X1450147Y1586262D03*
X1454482Y1612800D03*
X1471400Y225448D03*
Y233448D03*
X1463900Y242448D03*
X1471602Y263378D03*
Y255378D03*
X1463602Y271378D03*
X1468898Y1319592D03*
X1481425Y281456D03*
X1488917Y421982D03*
X1484897Y431972D03*
X1479967Y1347521D03*
X1495926Y280027D03*
X1508418Y288030D03*
X1501496Y1338837D03*
X1516517Y116462D03*
X1515517Y136162D03*
X1517085Y243362D03*
Y235116D03*
Y258616D03*
Y254616D03*
X1516775Y284956D03*
X1512895Y1369919D03*
X1542469Y152873D03*
X1543254Y634165D03*
X1563096Y655416D03*
Y659416D03*
X1565973Y735691D03*
Y732165D03*
X1589095Y219526D03*
Y227526D03*
X1588856Y248008D03*
X1588876Y243890D03*
X1588836Y252126D03*
X1604297Y654542D03*
X1602477Y722582D03*
X1597433Y1420169D03*
Y1433669D03*
Y1438169D03*
Y1452071D03*
X1611337Y586762D03*
X1617419Y1426366D03*
Y1429896D03*
X1626550Y117627D03*
Y129627D03*
Y121627D03*
X1631860Y1445794D03*
X1654746Y544622D03*
X1653925Y635791D03*
X1646099Y652601D03*
X1653925Y669791D03*
X1646099Y686601D03*
X1653925Y703791D03*
X1646099Y720601D03*
X1643124Y1476695D03*
X1661820Y550382D03*
X1662877Y598522D03*
X1670003Y1445794D03*
X1668615Y1493362D03*
Y1501362D03*
Y1516862D03*
Y1533862D03*
Y1520862D03*
Y1545862D03*
X1668690Y1561557D03*
X1668615Y1557557D03*
X1668690Y1581321D03*
X1684448Y495290D03*
Y499290D03*
X1701811Y369773D03*
Y373773D03*
X1699901Y401485D03*
X1693793Y525507D03*
Y529507D03*
Y533507D03*
Y549507D03*
X1703544Y655141D03*
X1700937Y688130D03*
Y691730D03*
Y695330D03*
X1701977Y726552D03*
X1711734Y174970D03*
X1714707Y364962D03*
X1719946Y474859D03*
Y478869D03*
X1722435Y112867D03*
X1736218Y486837D03*
X1722672Y688211D03*
X1748905Y100307D03*
X1751237Y372452D03*
X1741452Y1451841D03*
X1760585Y76797D03*
X1760555Y72637D03*
X1763527Y164362D03*
X1757158Y433221D03*
X1760258Y461393D03*
X1760368Y465893D03*
X1757773Y692742D03*
X1754542Y1475951D03*
X1782195Y92927D03*
X1771892Y169903D03*
X1779945Y291876D03*
X1779960Y295643D03*
Y299243D03*
X1784816Y403932D03*
Y410432D03*
Y418932D03*
Y425432D03*
X1787680Y70987D03*
X1799782Y165565D03*
X1792288Y367866D03*
X1791586Y390252D03*
X1795544Y1527366D03*
X1803307Y156557D03*
X1810267Y179897D03*
X1817249Y371329D03*
X1817086Y395552D03*
X1816316Y407932D03*
Y403225D03*
X1815816Y421432D03*
Y427932D03*
X1815758Y472521D03*
X1806658Y1494318D03*
Y1498318D03*
X1815231Y1504241D03*
X1823568Y363731D03*
Y367701D03*
X1823186Y379552D03*
Y383952D03*
X1832458Y459121D03*
X1835852Y182712D03*
X1842972Y176722D03*
G54D52*
X87225Y712316D03*
X1700657Y716442D03*
G54D127*
X317642Y1296728D03*
Y1330192D03*
X349650Y1273694D03*
Y1307158D03*
X381731Y1260612D03*
Y1294076D03*
X413909Y1260612D03*
Y1294076D03*
X446256Y1260612D03*
Y1294076D03*
X478433Y1260612D03*
Y1294076D03*
X510620Y1273793D03*
Y1307257D03*
X542985Y1296463D03*
Y1329927D03*
X1293783Y1296728D03*
Y1330192D03*
X1325791Y1273694D03*
Y1307158D03*
X1357872Y1260612D03*
Y1294076D03*
X1390050Y1260612D03*
Y1294076D03*
X1422397Y1260612D03*
Y1294076D03*
X1454574Y1260612D03*
Y1294076D03*
X1486761Y1273793D03*
Y1307257D03*
X1519126Y1296463D03*
Y1329927D03*
G54D109*
X213303Y685948D03*
G54D70*
X109696Y639477D03*
X108122D03*
X106547D03*
X104972D03*
X103397D03*
X101822D03*
Y658375D03*
X103397D03*
X104972D03*
X106547D03*
X108122D03*
X109696D03*
X125438Y500919D03*
X123863D03*
X122288D03*
X120713D03*
X119138D03*
Y519817D03*
X120713D03*
X122288D03*
X123863D03*
X125438D03*
X115996Y639477D03*
X114421D03*
X112846D03*
X111271D03*
Y658375D03*
X112846D03*
X114421D03*
X115996D03*
X133312Y500919D03*
X131737D03*
X130162D03*
X128587D03*
X127012D03*
Y519817D03*
X128587D03*
X130162D03*
X131737D03*
X133312D03*
X1672067Y527616D03*
X1670492D03*
X1668917D03*
Y546514D03*
X1670492D03*
X1672067D03*
X1683091Y527616D03*
X1681516D03*
X1679941D03*
X1678366D03*
X1676791D03*
X1675217D03*
X1673642D03*
Y546514D03*
X1675217D03*
X1676791D03*
X1678366D03*
X1679941D03*
X1681516D03*
X1683091D03*
X1703547Y474758D03*
X1701973D03*
X1700398D03*
X1698823D03*
X1697248D03*
X1695673D03*
Y493656D03*
X1697248D03*
X1698823D03*
X1700398D03*
X1701973D03*
X1703547D03*
X1709847Y474758D03*
X1708272D03*
X1706697D03*
X1705122D03*
Y493656D03*
X1706697D03*
X1708272D03*
X1709847D03*
G54D208*
X922441Y154311D03*
Y243799D03*
G54D44*
X91949Y702670D03*
X1705381Y706796D03*
G54D191*
X735882Y1585521D03*
X788079Y1585523D03*
X830079D03*
X872079D03*
X914079D03*
G54D263*
X1526675Y136146D03*
X1534155D03*
X1530415Y145202D03*
G54D245*
X1265107Y54022D03*
Y62422D03*
X1272587Y54022D03*
Y62422D03*
G54D35*
X53701Y1631013D03*
Y1654045D03*
X82637Y1631013D03*
Y1654045D03*
G54D155*
X442578Y1579509D03*
X440019D03*
X437460D03*
Y1586989D03*
X440019D03*
X442578D03*
X598661Y489622D03*
Y497102D03*
X604779Y426622D03*
X602220D03*
X599661D03*
Y434102D03*
X604779D03*
X603779Y489622D03*
X601220D03*
X603779Y497102D03*
X1213016Y1661115D03*
X1210457D03*
X1207898D03*
Y1668595D03*
X1210457D03*
X1213016D03*
G54D173*
X542554Y462744D03*
Y491680D03*
X565586Y462744D03*
Y491680D03*
X1790546Y438156D03*
Y467092D03*
X1813578Y438156D03*
Y467092D03*
G54D236*
X1100097Y1650635D03*
X1096357D03*
X1092617D03*
Y1661265D03*
X1096357D03*
X1100097D03*
G54D164*
X482720Y375319D03*
Y382405D03*
X496120Y375426D03*
Y382512D03*
X512220Y375319D03*
Y382405D03*
X510220Y404819D03*
Y411905D03*
X529220Y375819D03*
Y382905D03*
X526220Y404819D03*
Y411905D03*
G54D53*
X84430Y1310256D03*
X1093936Y1591739D03*
X1769097Y1308506D03*
G54D80*
X163677Y1344383D03*
Y1370367D03*
X201777Y1344383D03*
Y1370367D03*
X677296Y1344408D03*
Y1370392D03*
X715396Y1344408D03*
Y1370392D03*
X1136988Y1380712D03*
Y1406696D03*
X1175088Y1380712D03*
Y1406696D03*
X1638462Y1378004D03*
Y1403988D03*
X1676562Y1378004D03*
Y1403988D03*
G54D209*
X913386Y167579D03*
Y184114D03*
Y181752D03*
Y179390D03*
Y177027D03*
Y174665D03*
Y172303D03*
Y169941D03*
Y200649D03*
Y198287D03*
Y195925D03*
Y193563D03*
Y191201D03*
Y188838D03*
Y186476D03*
Y217185D03*
Y214823D03*
Y212461D03*
Y210098D03*
Y207736D03*
Y205374D03*
Y203012D03*
Y231358D03*
Y228996D03*
Y226634D03*
Y224272D03*
Y221909D03*
Y219547D03*
X931496Y167579D03*
Y184114D03*
Y181752D03*
Y179390D03*
Y177027D03*
Y174665D03*
Y172303D03*
Y169941D03*
Y200649D03*
Y198287D03*
Y195925D03*
Y193563D03*
Y191201D03*
Y188838D03*
Y186476D03*
Y217185D03*
Y214823D03*
Y212461D03*
Y210098D03*
Y207736D03*
Y205374D03*
Y203012D03*
Y231358D03*
Y228996D03*
Y226634D03*
Y224272D03*
Y221909D03*
Y219547D03*
G54D281*
X1756177Y288494D03*
Y290463D03*
Y292431D03*
Y294400D03*
Y286526D03*
X1774681Y294400D03*
Y292431D03*
Y290463D03*
G54D218*
X963586Y1600926D03*
Y1607042D03*
X995198Y1600942D03*
Y1607058D03*
X1026798Y1600942D03*
Y1607058D03*
X1058398Y1600942D03*
Y1607058D03*
G54D119*
X275630Y109804D03*
X708786Y113929D03*
X1750751Y110928D03*
G54D254*
X1289620Y135702D03*
G54D137*
X366075Y1378501D03*
Y1411375D03*
X1338716Y1378571D03*
Y1411445D03*
G54D128*
X317642Y1308834D03*
Y1318086D03*
X349650Y1285800D03*
Y1295052D03*
X381731Y1272718D03*
Y1281970D03*
X413909Y1272718D03*
Y1281970D03*
X446256Y1272718D03*
Y1281970D03*
X478433Y1272718D03*
Y1281970D03*
X510620Y1285899D03*
Y1295151D03*
X542985Y1308569D03*
Y1317821D03*
X1293783Y1308834D03*
Y1318086D03*
X1325791Y1285800D03*
Y1295052D03*
X1357872Y1272718D03*
Y1281970D03*
X1390050Y1272718D03*
Y1281970D03*
X1422397Y1272718D03*
Y1281970D03*
X1454574Y1272718D03*
Y1281970D03*
X1486761Y1285899D03*
Y1295151D03*
X1519126Y1308569D03*
Y1317821D03*
G54D146*
X401767Y1415210D03*
G54D62*
X80762Y1543015D03*
X82337D03*
X83912D03*
X85487D03*
X87061D03*
X88636D03*
X90211D03*
X91786D03*
G54D182*
X679353Y413289D03*
X676203D03*
X673054D03*
X669904D03*
X679353Y429037D03*
Y425888D03*
Y422738D03*
Y419588D03*
Y416439D03*
X676203Y429037D03*
Y425888D03*
Y422738D03*
Y419588D03*
Y416439D03*
X673054Y429037D03*
Y425888D03*
Y422738D03*
Y419588D03*
Y416439D03*
X669904Y429037D03*
Y425888D03*
Y422738D03*
Y419588D03*
Y416439D03*
X679353Y444785D03*
Y441636D03*
Y438486D03*
Y435336D03*
Y432187D03*
X676203Y444785D03*
Y441636D03*
Y438486D03*
Y435336D03*
Y432187D03*
X673054Y444785D03*
Y441636D03*
Y438486D03*
Y435336D03*
Y432187D03*
X669904Y444785D03*
Y441636D03*
Y438486D03*
Y435336D03*
Y432187D03*
X679353Y460533D03*
Y457384D03*
Y454234D03*
Y451084D03*
Y447935D03*
X676203Y460533D03*
Y457384D03*
Y454234D03*
Y451084D03*
Y447935D03*
X673054Y460533D03*
Y457384D03*
Y454234D03*
Y451084D03*
Y447935D03*
X669904Y460533D03*
Y457384D03*
Y454234D03*
Y451084D03*
Y447935D03*
X679353Y476281D03*
Y473132D03*
Y469982D03*
Y466832D03*
Y463683D03*
X676203Y476281D03*
Y473132D03*
Y469982D03*
Y466832D03*
Y463683D03*
X673054Y476281D03*
Y473132D03*
Y469982D03*
Y466832D03*
Y463683D03*
X669904Y476281D03*
Y473132D03*
Y469982D03*
Y466832D03*
Y463683D03*
X679353Y479431D03*
X676203D03*
X673054D03*
X669904D03*
X695101Y413289D03*
X691951D03*
X688802D03*
X685652D03*
X682503D03*
X695101Y429037D03*
Y425888D03*
Y422738D03*
Y419588D03*
Y416439D03*
X691951Y429037D03*
Y425888D03*
Y422738D03*
Y419588D03*
Y416439D03*
X688802Y429037D03*
Y425888D03*
Y422738D03*
Y419588D03*
Y416439D03*
X685652Y429037D03*
Y425888D03*
Y422738D03*
Y419588D03*
Y416439D03*
X682503Y429037D03*
Y425888D03*
Y422738D03*
Y419588D03*
Y416439D03*
X695101Y444785D03*
Y441636D03*
Y438486D03*
Y435336D03*
Y432187D03*
X691951Y444785D03*
Y441636D03*
Y438486D03*
Y435336D03*
Y432187D03*
X688802Y444785D03*
Y441636D03*
Y438486D03*
Y435336D03*
Y432187D03*
X685652Y444785D03*
Y441636D03*
Y438486D03*
Y435336D03*
Y432187D03*
X682503Y444785D03*
Y441636D03*
Y438486D03*
Y435336D03*
Y432187D03*
X695101Y460533D03*
Y457384D03*
Y454234D03*
Y451084D03*
Y447935D03*
X691951Y460533D03*
Y457384D03*
Y454234D03*
Y451084D03*
Y447935D03*
X688802Y460533D03*
Y457384D03*
Y454234D03*
Y451084D03*
Y447935D03*
X685652Y460533D03*
Y457384D03*
Y454234D03*
Y451084D03*
Y447935D03*
X682503Y460533D03*
Y457384D03*
Y454234D03*
Y451084D03*
Y447935D03*
X695101Y476281D03*
Y473132D03*
Y469982D03*
Y466832D03*
Y463683D03*
X691951Y476281D03*
Y473132D03*
Y469982D03*
Y466832D03*
Y463683D03*
X688802Y476281D03*
Y473132D03*
Y469982D03*
Y466832D03*
Y463683D03*
X685652Y476281D03*
Y473132D03*
Y469982D03*
Y466832D03*
Y463683D03*
X682503Y476281D03*
Y473132D03*
Y469982D03*
Y466832D03*
Y463683D03*
X695101Y479431D03*
X691951D03*
X688802D03*
X685652D03*
X682503D03*
X710849Y413289D03*
X707699D03*
X704550D03*
X701400D03*
X698251D03*
X710849Y429037D03*
Y425888D03*
Y422738D03*
Y419588D03*
Y416439D03*
X707699Y429037D03*
Y425888D03*
Y422738D03*
Y419588D03*
Y416439D03*
X704550Y429037D03*
Y425888D03*
Y422738D03*
Y419588D03*
Y416439D03*
X701400Y429037D03*
Y425888D03*
Y422738D03*
Y419588D03*
Y416439D03*
X698251Y429037D03*
Y425888D03*
Y422738D03*
Y419588D03*
Y416439D03*
X710849Y444785D03*
Y441636D03*
Y438486D03*
Y435336D03*
Y432187D03*
X707699Y444785D03*
Y441636D03*
Y438486D03*
Y435336D03*
Y432187D03*
X704550Y444785D03*
Y441636D03*
Y438486D03*
Y435336D03*
Y432187D03*
X701400Y444785D03*
Y441636D03*
Y438486D03*
Y435336D03*
Y432187D03*
X698251Y444785D03*
Y441636D03*
Y438486D03*
Y435336D03*
Y432187D03*
X710849Y460533D03*
Y457384D03*
Y454234D03*
Y451084D03*
Y447935D03*
X707699Y460533D03*
Y457384D03*
Y454234D03*
Y451084D03*
Y447935D03*
X704550Y460533D03*
Y457384D03*
Y454234D03*
Y451084D03*
Y447935D03*
X701400Y460533D03*
Y457384D03*
Y454234D03*
Y451084D03*
Y447935D03*
X698251Y460533D03*
Y457384D03*
Y454234D03*
Y451084D03*
Y447935D03*
X710849Y476281D03*
Y473132D03*
Y469982D03*
Y466832D03*
Y463683D03*
X707699Y476281D03*
Y473132D03*
Y469982D03*
Y466832D03*
Y463683D03*
X704550Y476281D03*
Y473132D03*
Y469982D03*
Y466832D03*
Y463683D03*
X701400Y476281D03*
Y473132D03*
Y469982D03*
Y466832D03*
Y463683D03*
X698251Y476281D03*
Y473132D03*
Y469982D03*
Y466832D03*
Y463683D03*
X710849Y479431D03*
X707699D03*
X704550D03*
X701400D03*
X698251D03*
X726597Y413289D03*
X723447D03*
X720298D03*
X717148D03*
X713999D03*
X726597Y429037D03*
Y425888D03*
Y422738D03*
Y419588D03*
Y416439D03*
X723447Y429037D03*
Y425888D03*
Y422738D03*
Y419588D03*
Y416439D03*
X720298Y429037D03*
Y425888D03*
Y422738D03*
Y419588D03*
Y416439D03*
X717148Y429037D03*
Y425888D03*
Y422738D03*
Y419588D03*
Y416439D03*
X713999Y429037D03*
Y425888D03*
Y422738D03*
Y419588D03*
Y416439D03*
X726597Y444785D03*
Y441636D03*
Y438486D03*
Y435336D03*
Y432187D03*
X723447Y444785D03*
Y441636D03*
Y438486D03*
Y435336D03*
Y432187D03*
X720298Y444785D03*
Y441636D03*
Y438486D03*
Y435336D03*
Y432187D03*
X717148Y444785D03*
Y441636D03*
Y438486D03*
Y435336D03*
Y432187D03*
X713999Y444785D03*
Y441636D03*
Y438486D03*
Y435336D03*
Y432187D03*
X726597Y460533D03*
Y457384D03*
Y454234D03*
Y451084D03*
Y447935D03*
X723447Y460533D03*
Y457384D03*
Y454234D03*
Y451084D03*
Y447935D03*
X720298Y460533D03*
Y457384D03*
Y454234D03*
Y451084D03*
Y447935D03*
X717148Y460533D03*
Y457384D03*
Y454234D03*
Y451084D03*
Y447935D03*
X713999Y460533D03*
Y457384D03*
Y454234D03*
Y451084D03*
Y447935D03*
X726597Y476281D03*
Y473132D03*
Y469982D03*
Y466832D03*
Y463683D03*
X723447Y476281D03*
Y473132D03*
Y469982D03*
Y466832D03*
Y463683D03*
X720298Y476281D03*
Y473132D03*
Y469982D03*
Y466832D03*
Y463683D03*
X717148Y476281D03*
Y473132D03*
Y469982D03*
Y466832D03*
Y463683D03*
X713999Y476281D03*
Y473132D03*
Y469982D03*
Y466832D03*
Y463683D03*
X726597Y479431D03*
X723447D03*
X720298D03*
X717148D03*
X713999D03*
X736046Y413289D03*
X732896D03*
X729747D03*
X736046Y429037D03*
Y425888D03*
Y422738D03*
Y419588D03*
Y416439D03*
X732896Y429037D03*
Y425888D03*
Y422738D03*
Y419588D03*
Y416439D03*
X729747Y429037D03*
Y425888D03*
Y422738D03*
Y419588D03*
Y416439D03*
X736046Y444785D03*
Y441636D03*
Y438486D03*
Y435336D03*
Y432187D03*
X732896Y444785D03*
Y441636D03*
Y438486D03*
Y435336D03*
Y432187D03*
X729747Y444785D03*
Y441636D03*
Y438486D03*
Y435336D03*
Y432187D03*
X736046Y460533D03*
Y457384D03*
Y454234D03*
Y451084D03*
Y447935D03*
X732896Y460533D03*
Y457384D03*
Y454234D03*
Y451084D03*
Y447935D03*
X729747Y460533D03*
Y457384D03*
Y454234D03*
Y451084D03*
Y447935D03*
X736046Y476281D03*
Y473132D03*
Y469982D03*
Y466832D03*
Y463683D03*
X732896Y476281D03*
Y473132D03*
Y469982D03*
Y466832D03*
Y463683D03*
X729747Y476281D03*
Y473132D03*
Y469982D03*
Y466832D03*
Y463683D03*
X736046Y479431D03*
X732896D03*
X729747D03*
X1285767Y150750D03*
X1288347Y148170D03*
X1290927D03*
X1285767Y153329D03*
X1290927Y233328D03*
X1294866D03*
X1288347Y230748D03*
X1285767Y228169D03*
Y224230D03*
X1357888Y148170D03*
X1361827D03*
X1357888Y233328D03*
X1361827D03*
X1366987Y150750D03*
X1364407Y148170D03*
X1366987Y157268D03*
Y153329D03*
X1364407Y233328D03*
X1366987Y230748D03*
Y228169D03*
Y224230D03*
G54D71*
X99460Y641839D03*
Y643414D03*
Y644989D03*
Y646564D03*
Y648139D03*
Y649713D03*
Y651288D03*
Y652863D03*
Y654438D03*
Y656013D03*
X116776Y503281D03*
Y504856D03*
Y506431D03*
Y508006D03*
Y509581D03*
Y511155D03*
Y512730D03*
Y514305D03*
Y515880D03*
Y517455D03*
X118358Y656013D03*
Y654438D03*
Y652863D03*
Y651288D03*
Y649713D03*
Y648139D03*
Y646564D03*
Y644989D03*
Y643414D03*
Y641839D03*
X135674Y509581D03*
Y508006D03*
Y506431D03*
Y504856D03*
Y503281D03*
Y517455D03*
Y515880D03*
Y514305D03*
Y512730D03*
Y511155D03*
X1666555Y529978D03*
Y531553D03*
Y533128D03*
Y534703D03*
Y536278D03*
Y537852D03*
Y539427D03*
Y541002D03*
Y542577D03*
Y544152D03*
X1685453Y542577D03*
Y541002D03*
Y539427D03*
Y537852D03*
Y536278D03*
Y534703D03*
Y533128D03*
Y531553D03*
Y529978D03*
Y544152D03*
X1693311Y477120D03*
Y478695D03*
Y480270D03*
Y481845D03*
Y483420D03*
Y484994D03*
Y486569D03*
Y488144D03*
Y489719D03*
Y491294D03*
X1712209Y477120D03*
Y491294D03*
Y489719D03*
Y488144D03*
Y486569D03*
Y484994D03*
Y483420D03*
Y481845D03*
Y480270D03*
Y478695D03*
G54D17*
X19360Y304152D03*
X46720Y200787D03*
Y192913D03*
X46745Y208661D03*
X46720Y216535D03*
Y232283D03*
X46359Y240157D03*
X36000Y295952D03*
X39600Y378562D03*
X44700Y375262D03*
X49357Y406260D03*
X40800Y400962D03*
X34356Y412914D03*
X34440Y406562D03*
X47940Y1635504D03*
X43450Y1638102D03*
X59410Y57052D03*
X56370Y66552D03*
X60220Y80860D03*
X63048Y78031D03*
X49594Y304848D03*
X50200Y375262D03*
X63350Y371362D03*
X57342Y375262D03*
X53500Y371362D03*
X52185Y409088D03*
X64922Y405732D03*
X60522D03*
X60333Y1623834D03*
X50333D03*
X55333D03*
X62075Y1661030D03*
X65088Y1666334D03*
X62833Y1671334D03*
X65710Y376042D03*
X70500Y381562D03*
X76200Y395865D03*
X71136Y390398D03*
X76600Y386364D03*
X71480Y399442D03*
X72274Y1530094D03*
X68274Y1533594D03*
X70250Y1544094D03*
X69274Y1539094D03*
X77040Y1601102D03*
X65120Y1609909D03*
X65520Y1615972D03*
X66000Y1623800D03*
X76000D03*
X81000D03*
X71000D03*
X78333Y1661334D03*
X73333D03*
X68088Y1660691D03*
X77833Y1678902D03*
X73833Y1674252D03*
X69833Y1678582D03*
X94585Y164327D03*
X96880Y216535D03*
X96540Y232283D03*
X96396Y416383D03*
X96496Y430383D03*
X96396Y425383D03*
X97496Y446519D03*
X97096Y436383D03*
X97396Y441383D03*
X95250Y637848D03*
X94250Y649702D03*
X94408Y644740D03*
X94160Y657130D03*
X86050Y1527962D03*
X85487Y1556594D03*
X92928Y1556094D03*
X86000Y1623800D03*
X90100Y1650862D03*
X83333Y1661214D03*
X87600Y1655562D03*
X81833Y1674526D03*
X99480Y177165D03*
X106045Y303798D03*
X98896Y420883D03*
X113700Y536792D03*
X108550D03*
X102310Y685500D03*
X112270Y1518907D03*
X102070Y1524694D03*
X101274Y1535594D03*
X100236Y1549531D03*
X100274Y1540594D03*
X101363Y1600667D03*
X101558Y1619821D03*
X104500Y1655800D03*
X109960Y1677362D03*
X118820Y274800D03*
X116482Y409571D03*
X129480Y536662D03*
X124435Y536727D03*
X118880Y536862D03*
X125620Y631065D03*
X119263Y1601131D03*
X123750Y1616882D03*
X119058Y1637862D03*
X117100Y1651800D03*
X121645Y1683362D03*
X114720Y1691362D03*
X114991Y1702633D03*
X138482Y384071D03*
Y392881D03*
X135482Y388571D03*
Y404385D03*
X134896Y429883D03*
X138896Y426608D03*
X134896Y422883D03*
Y443383D03*
X138896Y433383D03*
Y439883D03*
X134896Y436383D03*
X143922Y531783D03*
X133160Y532002D03*
X138793Y1535926D03*
X139453Y1548920D03*
X139247Y1542048D03*
X142884Y1555204D03*
X138300Y1625200D03*
X152877Y411530D03*
X147800Y1414500D03*
X158307Y1531330D03*
X154685Y1558156D03*
X159794Y1558238D03*
X175982Y383071D03*
X173482Y387571D03*
X175982Y392071D03*
X173482Y396571D03*
Y405571D03*
X175982Y401071D03*
X166690Y427733D03*
X166917Y421148D03*
X167359Y443845D03*
X166580Y433115D03*
X171570Y1535141D03*
X174501Y1539847D03*
X175121Y1545985D03*
X172623Y1551715D03*
X169754Y1542489D03*
X175064Y1557874D03*
X181266Y234993D03*
X220054Y462235D03*
X223554Y458235D03*
X220200Y454162D03*
X237220Y57362D03*
X242220D03*
X242200Y119302D03*
X237933Y107835D03*
X239740Y134102D03*
X236920Y146829D03*
X237400Y163962D03*
X228024Y316772D03*
X252220Y57362D03*
X247220D03*
X253090Y87362D03*
X246297Y132012D03*
X254825Y151937D03*
X254940Y146879D03*
X259500Y162662D03*
X260300Y304762D03*
X275000Y153862D03*
X275053Y148703D03*
X275000Y159203D03*
X276234Y165350D03*
X276190Y215532D03*
X270740Y215582D03*
X262140Y234282D03*
X269740D03*
X271620Y266602D03*
X267759Y262672D03*
X274600Y305762D03*
X265824Y305962D03*
X271877Y750415D03*
X272208Y768516D03*
X282000Y143962D03*
X277000D03*
X287200D03*
X292500Y144013D03*
X286234Y165350D03*
X281234D03*
X277340Y234282D03*
X291754Y266962D03*
X281120Y267002D03*
X276620Y262572D03*
X286320Y262752D03*
X279400Y296463D03*
X277046Y735442D03*
X283350Y728483D03*
X285046Y737964D03*
X297700Y144162D03*
X302290Y191222D03*
X307640Y234652D03*
X304354Y263002D03*
X299120Y302112D03*
X304500Y303862D03*
X294760Y553672D03*
X293027Y755985D03*
X316900Y139962D03*
X314249Y223352D03*
X316954Y262752D03*
X316224Y305762D03*
X321100Y360422D03*
X309573Y567704D03*
X319590Y567906D03*
X339195Y131052D03*
X337464Y137082D03*
X335000Y162862D03*
X329648Y262677D03*
X341295Y300452D03*
X332000Y302862D03*
X332808Y357484D03*
X327310Y363143D03*
X327470Y374917D03*
X327550Y388243D03*
X327060Y400371D03*
X327150Y409452D03*
X331020Y594362D03*
X342500Y155942D03*
X342000Y263087D03*
X354672Y263068D03*
X354145Y300892D03*
X355671Y364133D03*
X354100Y720743D03*
X367341Y151303D03*
X373720Y214862D03*
X367326Y263050D03*
X366498Y300723D03*
X364667Y357923D03*
X359000Y359762D03*
X360680Y383412D03*
X357946Y369798D03*
X360140Y375392D03*
X361040Y389478D03*
X360880Y400628D03*
X359669Y686744D03*
X371850Y1534062D03*
X369000Y1639500D03*
X386720Y212508D03*
X386690Y229142D03*
X386540Y223342D03*
X379954Y263232D03*
X379107Y300712D03*
X386670Y297482D03*
X387070Y359122D03*
X385780Y352352D03*
X386540Y367222D03*
X388811Y383335D03*
X386750Y394832D03*
X388735Y388879D03*
X388692Y401745D03*
X385700Y1609400D03*
X389690Y1650552D03*
X381640Y1651162D03*
X375914Y1659005D03*
X378509Y1677584D03*
X394210Y133422D03*
X392554Y263232D03*
X405154Y263472D03*
X392083Y301160D03*
X404215Y301544D03*
X394100Y357592D03*
X403260Y1391142D03*
X394367Y1421475D03*
X396824Y1650332D03*
X409900Y155833D03*
X417754Y263642D03*
X417219Y301637D03*
X417390Y359132D03*
X415630Y374921D03*
X415970Y386252D03*
X415830Y396152D03*
X416498Y402729D03*
X415710Y412972D03*
X414333Y1385292D03*
X417920Y1395170D03*
X411121Y1405157D03*
X422708Y1437560D03*
X413697Y1428315D03*
X416999Y1441908D03*
X407296Y1543686D03*
X407260Y1556810D03*
X407810Y1675512D03*
X423500Y123647D03*
X423580Y129222D03*
X429780Y149373D03*
X423220Y209949D03*
X425780Y220022D03*
X432054Y263264D03*
X429708Y301092D03*
X433956Y381770D03*
X433996Y394722D03*
X437520Y464837D03*
X430320Y1383862D03*
X432243Y1391779D03*
X430291Y1437778D03*
X433897Y1434670D03*
X424921Y1546310D03*
X436383Y1591964D03*
X438749Y1611713D03*
X431500Y1610300D03*
X426510Y1620392D03*
X433021Y1647466D03*
X426968Y1646026D03*
X426728Y1636495D03*
X431035Y1641851D03*
X442650Y101912D03*
X450380Y123012D03*
X442224Y301142D03*
X455000Y340362D03*
X446416Y394306D03*
X454513Y394372D03*
X442802Y424850D03*
X447552Y427100D03*
X452552Y425100D03*
X442520Y464837D03*
X451520D03*
X453423Y505483D03*
X455423Y510983D03*
X453423Y526167D03*
X454885Y539483D03*
X453423Y547519D03*
X445339Y1415731D03*
X443850Y1423404D03*
X445294Y1430415D03*
X445520Y1547437D03*
X447740Y1591180D03*
X445225Y1613427D03*
X446920Y1644280D03*
X465455Y69991D03*
Y64991D03*
Y59991D03*
X464321Y149864D03*
X463821Y154864D03*
X465000Y340362D03*
X467500Y399187D03*
X458052Y427100D03*
X456520Y464837D03*
X461520D03*
X466520D03*
X457423Y529983D03*
Y543899D03*
X461239Y1420649D03*
X471530Y1414650D03*
X459520Y1557437D03*
X457220Y1594495D03*
X459900Y1614582D03*
X460710Y1619602D03*
X465500Y1632442D03*
X466910Y1643242D03*
X467430Y1661242D03*
Y1666242D03*
X464586Y1674991D03*
X486370Y262952D03*
X474310Y293022D03*
X474460Y382405D03*
X485673Y370314D03*
X480174Y370316D03*
X482720Y387370D03*
X479451Y424709D03*
X484201Y426959D03*
X474169Y464696D03*
X479169D03*
X487110Y1399562D03*
X478180Y1454892D03*
X504040Y374320D03*
X500670Y370180D03*
X494720Y370337D03*
X504040Y385560D03*
X490810Y387640D03*
X500220Y391362D03*
X502040Y411905D03*
X492970Y409252D03*
X489201Y424959D03*
X494701Y426959D03*
X493169Y464696D03*
X498169D03*
X488169D03*
X503169D03*
X498423Y511249D03*
X493950Y523893D03*
X498923Y517983D03*
X494423Y514983D03*
X493987Y530097D03*
X499215Y527188D03*
X499123Y538283D03*
X500070Y1424140D03*
X513260Y78242D03*
X518250Y370250D03*
X510720Y370361D03*
X508690Y399850D03*
X517460Y399960D03*
X510220Y416970D03*
X517184Y475952D03*
X522228Y78079D03*
X534565Y139862D03*
X526730Y178803D03*
X536489Y264692D03*
X520830Y376860D03*
X535910Y370450D03*
X527720Y370430D03*
X520890Y387900D03*
X525670Y399850D03*
X533720Y400160D03*
X520760Y417110D03*
X529960Y417620D03*
X530630Y478492D03*
X534990Y481051D03*
X531400Y465696D03*
X535810Y468255D03*
X531380Y470814D03*
X530490Y483610D03*
X535080Y491292D03*
X534890Y486169D03*
X535444Y498578D03*
X546900Y127788D03*
X546461Y135734D03*
X547600Y155028D03*
X544720Y171362D03*
X544820Y161362D03*
X544720Y183921D03*
X549306Y179934D03*
X544390Y236512D03*
X550390Y231742D03*
X542050Y231722D03*
X537720Y278212D03*
X552760Y300922D03*
X552583Y366842D03*
X546830Y403292D03*
X543240Y445136D03*
Y450136D03*
X567520Y87362D03*
X567507Y81049D03*
X562820Y84262D03*
X562783Y78299D03*
X564200Y135562D03*
X567500Y184862D03*
X554306Y179934D03*
X562440Y253826D03*
X562564Y259202D03*
X558240Y300872D03*
X557490Y361932D03*
X553210Y403652D03*
X564170Y403477D03*
X558590Y403597D03*
X572220Y83562D03*
X572231Y77862D03*
X578765Y152912D03*
X578720Y167112D03*
X585031Y215378D03*
X580320Y252173D03*
X575050Y383602D03*
X580629Y370896D03*
X576907Y374655D03*
X570700Y397162D03*
X569600Y403562D03*
X572430Y459232D03*
X576950Y462552D03*
X572400Y466192D03*
X576920Y469832D03*
X572379Y473373D03*
X576970Y475932D03*
X572540Y478492D03*
X577000Y481051D03*
X572520Y483532D03*
X572400Y488682D03*
X572380Y493802D03*
X583150Y509262D03*
X598190Y83462D03*
X592265Y77757D03*
X586068Y134531D03*
X585986Y124754D03*
X600071Y138202D03*
X596720Y164717D03*
X589956Y200878D03*
X596576Y195237D03*
X590900Y195562D03*
X589956Y206962D03*
X601230Y216482D03*
X595900Y216612D03*
X591420Y213922D03*
X592936Y298082D03*
X593265Y311693D03*
X593311Y304016D03*
X599661Y421362D03*
X601820Y439362D03*
X599900Y524862D03*
X617585Y97257D03*
X613020Y94162D03*
X603880Y93902D03*
X605090Y137542D03*
X603410Y132682D03*
X614000Y133862D03*
X617500Y129862D03*
X617660Y168965D03*
X613660Y168966D03*
X603981Y158281D03*
X607940Y173930D03*
Y178930D03*
X602000Y195162D03*
X607200Y194062D03*
X611200Y197262D03*
X612531Y212721D03*
X608995Y216257D03*
X604230Y257532D03*
X616790Y283292D03*
X608920D03*
X602795Y477362D03*
X610700Y485320D03*
X603779Y502082D03*
X629684Y77928D03*
X623290Y78482D03*
X629500Y134362D03*
X626699Y129862D03*
X620612Y133862D03*
X633500Y147862D03*
Y141362D03*
X626929Y163506D03*
X624101Y166335D03*
X629430Y200710D03*
X622064Y250202D03*
X621893Y259030D03*
X629870Y296338D03*
X631861Y290182D03*
X628603Y304016D03*
X624460Y465262D03*
Y470362D03*
X624470Y475462D03*
X626680Y525972D03*
X648258Y79502D03*
X643387Y83184D03*
X645230Y116302D03*
X640000Y154345D03*
X639982Y144844D03*
X637055Y159515D03*
X635820Y180570D03*
X641766Y180757D03*
X635820Y185570D03*
Y190570D03*
X634880Y249202D03*
X634820Y260202D03*
X640720Y423062D03*
X639545Y445195D03*
X639428Y480474D03*
X657165Y79131D03*
X658490Y139140D03*
X654390Y152972D03*
X654156Y169197D03*
X654370Y158572D03*
X654470Y163972D03*
X654310Y186192D03*
X654325Y174437D03*
X653210Y199320D03*
Y206320D03*
Y213320D03*
X655620Y410662D03*
Y415662D03*
Y430662D03*
Y425662D03*
Y420662D03*
X655820Y442662D03*
Y437662D03*
Y447662D03*
X655700Y464664D03*
X655820Y472662D03*
X655557Y477064D03*
X655500Y481862D03*
X662000Y1416500D03*
X663720Y1715362D03*
Y1726362D03*
X673987Y87662D03*
X672520Y121560D03*
X678520Y130640D03*
X682140Y393432D03*
X672820Y396522D03*
X676720Y493562D03*
X668647Y1637403D03*
X673593Y1655557D03*
X686210Y91492D03*
X683500Y381200D03*
X693300Y395362D03*
X687500Y399402D03*
X697930Y391282D03*
X695257Y499926D03*
X699174Y519473D03*
X686647Y1636667D03*
X691593Y1653972D03*
X687120Y1665862D03*
Y1676862D03*
X710450Y152512D03*
X702705Y379398D03*
X707220Y399362D03*
X708400Y392000D03*
X700185Y385010D03*
X711187Y493470D03*
X705220Y493362D03*
X714162Y1574333D03*
X713052Y1579683D03*
X713102Y1601307D03*
X714380Y1589960D03*
X712512Y1596338D03*
X711558Y1675700D03*
X719600Y105062D03*
X718053Y165297D03*
X729460Y399052D03*
X723350Y388952D03*
X722187Y493470D03*
X727187D03*
X717187D03*
X723450Y597072D03*
X731960Y1634110D03*
X731040Y1652930D03*
X738186Y398695D03*
X732187Y493470D03*
X738070Y493833D03*
X737600Y500178D03*
X759350Y116180D03*
X763740Y108400D03*
X753600Y143438D03*
X753500Y151312D03*
X764342Y162084D03*
X755900Y170562D03*
X756160Y267322D03*
X755960Y274322D03*
X750020Y410662D03*
X750120Y415712D03*
X750020Y420712D03*
X750080Y430712D03*
X750010Y425712D03*
X750020Y435792D03*
X750220Y447162D03*
X750290Y452162D03*
Y457162D03*
X750220Y472162D03*
Y467162D03*
Y477162D03*
X749880Y482202D03*
X749612Y1583023D03*
X749662Y1590733D03*
X755859Y1697330D03*
X758273Y1718740D03*
X780180Y133460D03*
X780260Y124600D03*
X779100Y142760D03*
X773900Y170064D03*
X774660Y267722D03*
Y282922D03*
Y275322D03*
X771490Y354942D03*
X765000Y354862D03*
X768720Y459862D03*
X769985Y525724D03*
X774152Y1576893D03*
Y1594893D03*
X796800Y266800D03*
X794057Y301569D03*
X793896Y309026D03*
X789140Y380540D03*
X784278Y403212D03*
X786830Y411600D03*
X784730Y432682D03*
X787520Y510512D03*
Y524802D03*
X810810Y135132D03*
X810640Y128262D03*
X810480Y141762D03*
X798204Y279146D03*
X811600Y378200D03*
X801800Y388800D03*
X799220Y423862D03*
X807530Y502232D03*
X807640Y519957D03*
X801652Y1578393D03*
X801653Y1598793D03*
X801652Y1604293D03*
X814114Y120773D03*
X822530Y125698D03*
X828614D03*
X814800Y264580D03*
X815060Y280072D03*
X813490Y273862D03*
X819500Y418300D03*
X819220Y425425D03*
X815310Y436050D03*
X827100Y471682D03*
Y479200D03*
X815902Y1578643D03*
X815509Y1600536D03*
X831539Y70643D03*
X834114Y135698D03*
X833614Y129198D03*
X839460Y146042D03*
X833320Y145912D03*
X831295Y171632D03*
X845220Y192862D03*
X839220D03*
X834920Y220303D03*
X843510Y228962D03*
X839080Y233252D03*
X838680Y224752D03*
X840063Y285022D03*
X840850Y278948D03*
X836064Y396620D03*
X835564Y389140D03*
X836290Y415562D03*
X836330Y405972D03*
X836260Y410760D03*
X829800Y429300D03*
X844500Y447100D03*
X844570Y469130D03*
X832620Y506082D03*
X832125Y521156D03*
X843652Y1578393D03*
X843653Y1598793D03*
X843652Y1604293D03*
X856629Y70793D03*
X846190Y145262D03*
X856430Y182260D03*
X849320Y196532D03*
X853340Y199932D03*
X855400Y204772D03*
X853842Y225002D03*
X849600Y228152D03*
X859564Y389140D03*
X859621Y395261D03*
X859876Y414276D03*
Y406812D03*
X854820Y437422D03*
X848900Y433400D03*
X851941Y503082D03*
X857902Y1578643D03*
X857509Y1600536D03*
X864967Y60983D03*
X866190Y163822D03*
X866220Y170862D03*
X866451Y175862D03*
X869900Y209562D03*
X868020Y264232D03*
X872820Y430963D03*
X863925Y737697D03*
X889350Y195489D03*
X893700Y201799D03*
X887142Y879195D03*
X892408Y879200D03*
X885652Y1578393D03*
X885653Y1598793D03*
X885652Y1604293D03*
X899500Y201899D03*
X897640Y915099D03*
X899902Y1578643D03*
X899509Y1600536D03*
X923897Y445545D03*
X912288Y472430D03*
X920273Y972460D03*
X925723Y972420D03*
X921868Y999472D03*
X926464Y1001808D03*
X938980Y980382D03*
X931083Y972420D03*
X939942Y991629D03*
X932220Y1001862D03*
X928152Y1579393D03*
Y1589893D03*
Y1594893D03*
X933979Y1661327D03*
X942100Y1671100D03*
X955430Y180139D03*
X956920Y490462D03*
X950820Y489762D03*
X974120Y194129D03*
X967239Y320073D03*
X975720Y386862D03*
X975330Y396132D03*
X970788Y501230D03*
X964347Y501262D03*
X977479Y171040D03*
X977070Y211709D03*
X988500Y224653D03*
X991934Y368443D03*
X979559Y399362D03*
X983970Y392562D03*
X997460Y226019D03*
X1000009Y368081D03*
X1003293Y371455D03*
X997394Y415578D03*
X1001721Y421758D03*
X996154Y422700D03*
X1007249Y426399D03*
X1003235Y430097D03*
X1003220Y512862D03*
X1010388Y189009D03*
X1010976Y195562D03*
X1017163Y367963D03*
X1019300Y371830D03*
X1023762Y370425D03*
X1010736Y371866D03*
X1013168Y368145D03*
X1023330Y413692D03*
X1016520Y414362D03*
X1036278Y303993D03*
X1029239Y371893D03*
X1037334Y383729D03*
X1039952Y398756D03*
X1036659Y388000D03*
Y393000D03*
X1028330Y413692D03*
X1038330D03*
X1033330D03*
X1039065Y418999D03*
X1031065D03*
X1026065D03*
X1042334Y383729D03*
X1044952Y398756D03*
X1042687Y404063D03*
X1043330Y413692D03*
X1053410Y503402D03*
X1045720Y591672D03*
X1063330Y382062D03*
X1061470Y585862D03*
X1071957Y1659450D03*
X1075430Y68192D03*
X1079240Y72682D03*
X1087316Y78461D03*
X1077582Y390962D03*
X1078102Y1586860D03*
X1086457Y1644450D03*
X1084457Y1663950D03*
X1096272Y60182D03*
X1105316Y72266D03*
X1105423Y77559D03*
X1101500Y379235D03*
Y374235D03*
Y369235D03*
X1104902Y1586660D03*
X1105557Y1649250D03*
X1105457Y1664450D03*
X1096680Y1667260D03*
X1111970Y1607740D03*
Y1613140D03*
X1130163Y59940D03*
X1124858Y197309D03*
X1133720Y642862D03*
X1131220Y1599140D03*
X1138530Y1612150D03*
X1126940Y1612030D03*
X1138530Y1606750D03*
X1126940Y1606230D03*
X1129620Y1620851D03*
X1147722Y206345D03*
X1144620Y221652D03*
X1145500Y374235D03*
X1150140Y610362D03*
X1142187Y1582738D03*
X1152187D03*
X1144899Y1630878D03*
X1170665Y71388D03*
X1155823Y192102D03*
X1157445Y216982D03*
X1159460Y366025D03*
X1158300Y585862D03*
X1170740Y602132D03*
X1161595Y1574738D03*
Y1582738D03*
X1165100Y1633450D03*
X1163970Y1620600D03*
X1164000Y1625720D03*
X1169825Y1678062D03*
X1158825D03*
X1177310Y65769D03*
X1177234Y59978D03*
X1174545Y106767D03*
X1184510Y188962D03*
X1183460Y205342D03*
X1177570Y602052D03*
X1175217Y595762D03*
X1171595Y1582738D03*
X1174595Y1590738D03*
X1186790Y1613820D03*
X1180825Y1678062D03*
X1203700Y89400D03*
X1203050Y100750D03*
X1200590Y231532D03*
X1188810Y296088D03*
X1198436Y1546492D03*
Y1556192D03*
X1187720Y1558682D03*
X1202200Y1661580D03*
X1191395Y1678372D03*
X1203040Y1671240D03*
X1191235Y1723852D03*
X1202005Y1723897D03*
X1215070Y61580D03*
X1218220Y199862D03*
X1212805Y1724162D03*
X1225700Y108962D03*
X1227074Y119962D03*
X1236300Y168362D03*
X1229720Y197302D03*
X1233282Y201875D03*
X1221330Y216000D03*
X1231720Y217862D03*
Y209862D03*
X1232720Y377862D03*
X1243653Y59957D03*
X1240700Y89700D03*
X1251107Y98785D03*
X1238148Y138705D03*
X1245784Y155522D03*
X1239664Y164272D03*
X1249166Y176737D03*
X1248064Y185012D03*
X1242383Y177862D03*
X1237910Y173375D03*
X1242378Y222323D03*
X1261969Y169722D03*
X1255848Y178605D03*
X1262332Y192601D03*
X1262300Y207572D03*
X1255954Y212694D03*
X1256615Y205266D03*
X1258883Y280558D03*
X1264146Y277191D03*
Y282191D03*
X1266227Y764045D03*
X1284648Y265431D03*
X1283346Y281903D03*
X1270646Y277191D03*
Y282191D03*
X1280675Y277013D03*
X1284794Y272284D03*
X1279987Y287375D03*
X1297710Y68562D03*
X1297785Y63033D03*
X1298270Y76142D03*
X1296253Y100049D03*
X1286750Y101712D03*
X1300964Y91012D03*
X1291257Y105595D03*
X1287793Y95682D03*
X1296929Y116962D03*
X1288693Y283769D03*
X1308440Y86532D03*
X1305422Y100454D03*
X1312792Y113732D03*
X1313405Y108420D03*
X1302060Y113852D03*
X1311241Y125232D03*
X1304714Y265246D03*
X1304930Y278552D03*
X1305090Y284722D03*
X1305164Y272652D03*
X1329891Y87412D03*
X1317901Y95732D03*
X1318146Y110924D03*
X1323546Y113188D03*
X1325641Y118859D03*
X1321810Y125106D03*
X1331593Y125262D03*
X1347082Y120593D03*
X1337731Y121164D03*
X1381940Y104063D03*
X1368124Y114039D03*
X1377470Y1391032D03*
X1378660Y1428340D03*
X1388340Y104132D03*
X1394550Y104022D03*
X1391038Y178871D03*
X1395773Y177016D03*
X1396781Y182349D03*
X1392025Y184062D03*
X1391443Y223513D03*
X1394493Y230962D03*
X1398984Y234392D03*
X1390474Y1385142D03*
X1393957Y1395078D03*
X1387262Y1405157D03*
X1395907Y1430227D03*
X1398569Y1437860D03*
X1411875Y121234D03*
X1411837Y126967D03*
X1411685Y133004D03*
X1401640Y158194D03*
X1407290Y160650D03*
X1410833Y249912D03*
X1412194Y242692D03*
X1411094Y255322D03*
X1406461Y1383862D03*
X1408384Y1391779D03*
X1410477Y1440117D03*
X1410038Y1434670D03*
X1409483Y1593883D03*
X1403250Y1608192D03*
X1410500Y1633862D03*
X1414400Y1627200D03*
X1418034Y244822D03*
X1416694Y252432D03*
X1421480Y1415731D03*
X1419991Y1423404D03*
X1416272Y1433949D03*
X1421435Y1430415D03*
X1425850Y1516362D03*
X1426090Y1532182D03*
X1426240Y1543402D03*
X1415368Y1569131D03*
X1422680Y1593382D03*
X1428700Y1600600D03*
X1415730Y1611422D03*
X1431600Y1630300D03*
Y1625300D03*
X1428500Y1642362D03*
X1435013Y153882D03*
X1435220Y141942D03*
X1435013Y147636D03*
X1435060Y159212D03*
X1447340Y157402D03*
X1447200Y286400D03*
X1436270Y312592D03*
X1437666Y1421828D03*
X1447617Y1416417D03*
X1445530Y1524094D03*
X1445970Y1539914D03*
X1446210Y1551134D03*
X1447408Y1569037D03*
Y1564037D03*
X1442499Y1585323D03*
X1434220Y1595900D03*
X1446380Y1660462D03*
X1450270Y143022D03*
X1450720Y153362D03*
X1448820Y148092D03*
X1450720Y161862D03*
X1449740Y166912D03*
X1450720Y173862D03*
X1449700Y299067D03*
X1453900Y286400D03*
X1455692Y731401D03*
X1462194Y1399885D03*
X1462421Y1609800D03*
X1458890Y1648942D03*
X1452757Y1649112D03*
X1466356Y64062D03*
X1466383Y220108D03*
Y225330D03*
X1476070Y1423740D03*
X1464880Y1649112D03*
X1511200Y131862D03*
X1504360Y244592D03*
X1512244Y311522D03*
X1509420Y316192D03*
X1525940Y108192D03*
X1526930Y203740D03*
X1524853Y235376D03*
X1528860Y239792D03*
X1524840Y244842D03*
X1529150Y251402D03*
X1524810Y254652D03*
X1533630Y57052D03*
X1530910Y64900D03*
X1534367Y75003D03*
X1531429Y77832D03*
X1532500Y130362D03*
X1542230Y292732D03*
X1541568Y594020D03*
X1535007Y608685D03*
X1543895Y629286D03*
X1545610Y116180D03*
X1546813Y132712D03*
X1548938Y593832D03*
X1549590Y629295D03*
X1577365Y1417315D03*
X1576407Y1438525D03*
X1588550Y185702D03*
X1588720Y193962D03*
X1582340Y200611D03*
X1581830Y217482D03*
X1588100Y205442D03*
X1591830Y232482D03*
X1586830D03*
X1581830D03*
Y227482D03*
Y222482D03*
X1580240Y242232D03*
X1581810Y247902D03*
X1586647Y1433669D03*
X1595730Y205662D03*
X1604200Y234642D03*
X1596830Y232482D03*
Y237482D03*
X1613466Y114472D03*
X1634339Y121224D03*
Y116224D03*
Y131224D03*
X1654900Y195935D03*
X1654610Y405002D03*
X1646010Y423702D03*
X1653610D03*
X1672596Y220541D03*
X1664866Y225162D03*
X1661610Y405202D03*
X1661210Y423702D03*
X1674630Y521222D03*
X1672401Y556845D03*
X1668975Y559364D03*
X1669563Y552923D03*
X1678994Y217231D03*
X1680020Y420132D03*
X1685935Y504815D03*
X1681910Y559380D03*
X1675706Y559419D03*
X1676453Y1561557D03*
X1706100Y57052D03*
X1705798Y154052D03*
X1704625Y165909D03*
X1704600Y171656D03*
X1705920Y159812D03*
X1698592Y561310D03*
X1702130Y1385722D03*
X1705960Y1377442D03*
X1694248Y1500862D03*
Y1520362D03*
Y1541362D03*
X1694453Y1560821D03*
X1721240Y57422D03*
X1716230Y57202D03*
X1711140D03*
X1716910Y120432D03*
X1716600Y113622D03*
X1717100Y377962D03*
X1709590Y374282D03*
Y369282D03*
X1709680Y545432D03*
X1717880Y687680D03*
X1726600Y57232D03*
X1728310Y88442D03*
X1731470Y358022D03*
X1738480Y358082D03*
X1735870Y387082D03*
X1728860Y387032D03*
X1731150Y427410D03*
X1734420Y475672D03*
X1731120Y495912D03*
X1735010Y500178D03*
X1741886Y123728D03*
X1751222Y291276D03*
X1745910Y363112D03*
X1745490Y357002D03*
X1746120Y368132D03*
X1745910Y373522D03*
X1742770Y387112D03*
X1742947Y413323D03*
X1743170Y400460D03*
X1766490Y169122D03*
X1759220Y382952D03*
Y377452D03*
X1761720Y438342D03*
X1777598Y308286D03*
X1780667Y303994D03*
X1783608Y464140D03*
X1779740Y459942D03*
X1784010Y453904D03*
X1778430Y466699D03*
X1795346Y372732D03*
X1800030Y390411D03*
X1800980Y433132D03*
X1795060Y433182D03*
X1795161Y472622D03*
X1797720Y477852D03*
X1819450Y145070D03*
X1808110Y161427D03*
X1818274Y362293D03*
Y385293D03*
X1811404Y403225D03*
X1806460Y433002D03*
X1818700Y433182D03*
X1820790Y439462D03*
X1820650Y446226D03*
X1821580Y464140D03*
X1820790Y451344D03*
X1820840Y456463D03*
X1825210Y153961D03*
X1826080Y163660D03*
X1836657Y177243D03*
X1830080Y188482D03*
X1826308Y374586D03*
X1824404Y403225D03*
X1823904Y427432D03*
X1826525Y439697D03*
X1826340Y445972D03*
X1826200Y456482D03*
X1827430Y461581D03*
X1826520Y451292D03*
X1843830Y159800D03*
X1889250Y1843218D03*
X1906004Y1851586D03*
X1913834Y1850536D03*
X1924795Y1842075D03*
X1924635Y1852355D03*
X1937505Y1842525D03*
X1937655Y1853285D03*
X1958420Y1842549D03*
X1964170Y1842429D03*
X1955295Y1853985D03*
X1962935Y1853905D03*
X1978235Y1848699D03*
G54D272*
X1683921Y386516D03*
X1708421D03*
G54D227*
X1006625Y391981D03*
G54D26*
X40120Y744554D03*
Y1000853D03*
Y1287664D03*
X69820Y744554D03*
Y1000853D03*
Y1287664D03*
X99520Y744554D03*
Y1000853D03*
Y1287664D03*
X129220Y744554D03*
Y1000853D03*
Y1287664D03*
X158920Y744554D03*
Y1000853D03*
Y1287664D03*
X188620Y744554D03*
Y1000853D03*
Y1287664D03*
X218320Y744554D03*
Y1000853D03*
Y1287664D03*
X248020Y744554D03*
Y1000853D03*
Y1287664D03*
X633320Y744554D03*
Y1000853D03*
Y1287664D03*
X663020Y744554D03*
Y1000853D03*
Y1287664D03*
X692720Y744554D03*
Y1000853D03*
Y1287664D03*
X722420Y744554D03*
Y1000853D03*
Y1287664D03*
X752120Y744554D03*
Y1000853D03*
Y1287664D03*
X781820Y744554D03*
Y1000853D03*
Y1287664D03*
X811520Y744554D03*
Y1000853D03*
Y1287664D03*
X841220Y744554D03*
Y1000853D03*
Y1287664D03*
X1016262Y744554D03*
Y1000853D03*
Y1287664D03*
X1045962Y744554D03*
Y1000853D03*
Y1287664D03*
X1075662Y744554D03*
Y1000853D03*
Y1287664D03*
X1105362Y744554D03*
Y1000853D03*
Y1287664D03*
X1135062Y744554D03*
Y1000853D03*
Y1287664D03*
X1164762Y744554D03*
Y1000853D03*
Y1287664D03*
X1194462Y744554D03*
Y1000853D03*
Y1287664D03*
X1224162Y744554D03*
Y1000853D03*
Y1287664D03*
X1609462Y744554D03*
Y1000853D03*
Y1287664D03*
X1639162Y744554D03*
Y1000853D03*
Y1287664D03*
X1668862Y744554D03*
Y1000853D03*
Y1287664D03*
X1698562Y744554D03*
Y1000853D03*
Y1287664D03*
X1728262Y744554D03*
Y1000853D03*
Y1287664D03*
X1757962Y744554D03*
Y1000853D03*
Y1287664D03*
X1787662Y744554D03*
Y1000853D03*
Y1287664D03*
X1817362Y744554D03*
Y1000853D03*
Y1287664D03*
G54D219*
X999456Y189090D03*
G54D63*
X93361Y1543015D03*
G54D45*
X89981Y702670D03*
X1703413Y706796D03*
G54D27*
X48191Y766798D03*
Y770144D03*
X32049Y766798D03*
Y770144D03*
X48191Y773491D03*
Y776837D03*
Y780184D03*
Y783530D03*
Y786877D03*
X32049Y773491D03*
Y776837D03*
Y780184D03*
Y783530D03*
Y786877D03*
X48191Y790223D03*
Y793570D03*
Y796916D03*
Y800263D03*
Y803609D03*
X32049Y790223D03*
Y793570D03*
Y796916D03*
Y800263D03*
Y803609D03*
X48191Y806955D03*
Y810302D03*
Y813648D03*
Y816995D03*
Y820341D03*
X32049Y806955D03*
Y810302D03*
Y813648D03*
Y816995D03*
Y820341D03*
X48191Y823688D03*
Y827034D03*
Y830381D03*
Y833727D03*
X32049Y823688D03*
Y827034D03*
Y830381D03*
Y833727D03*
X48191Y837074D03*
Y840420D03*
Y843766D03*
Y847113D03*
Y850459D03*
X32049Y837074D03*
Y840420D03*
Y843766D03*
Y847113D03*
Y850459D03*
X48191Y853806D03*
Y857152D03*
Y860499D03*
Y863845D03*
Y867192D03*
X32049Y853806D03*
Y857152D03*
Y860499D03*
Y863845D03*
Y867192D03*
X48191Y870538D03*
Y873885D03*
Y877231D03*
Y880577D03*
Y883924D03*
X32049Y870538D03*
Y873885D03*
Y877231D03*
Y880577D03*
Y883924D03*
X48191Y887270D03*
Y890617D03*
Y893963D03*
Y897310D03*
Y900656D03*
X32049Y887270D03*
Y890617D03*
Y893963D03*
Y897310D03*
Y900656D03*
X48191Y904003D03*
Y907349D03*
Y910696D03*
Y914042D03*
Y917389D03*
X32049Y904003D03*
Y907349D03*
Y910696D03*
Y914042D03*
Y917389D03*
X48191Y920735D03*
Y924081D03*
Y927428D03*
Y930774D03*
Y934121D03*
X32049Y920735D03*
Y924081D03*
Y927428D03*
Y930774D03*
Y934121D03*
X48191Y937467D03*
Y940814D03*
Y944160D03*
Y947507D03*
X32049Y937467D03*
Y940814D03*
Y944160D03*
Y947507D03*
X48191Y950853D03*
Y954200D03*
Y957546D03*
Y960892D03*
Y964239D03*
X32049Y950853D03*
Y954200D03*
Y957546D03*
Y960892D03*
Y964239D03*
X48191Y967585D03*
Y970932D03*
Y974278D03*
Y977625D03*
Y980971D03*
X32049Y967585D03*
Y970932D03*
Y974278D03*
Y977625D03*
Y980971D03*
X48191Y984318D03*
Y987664D03*
Y991011D03*
Y994357D03*
X32049Y984318D03*
Y987664D03*
Y991011D03*
Y994357D03*
X48191Y1017782D03*
Y1021129D03*
Y1024475D03*
Y1027822D03*
Y1031168D03*
X32049Y1017782D03*
Y1021129D03*
Y1024475D03*
Y1027822D03*
Y1031168D03*
X48191Y1034515D03*
Y1037861D03*
Y1041207D03*
Y1044554D03*
Y1047900D03*
X32049Y1034515D03*
Y1037861D03*
Y1041207D03*
Y1044554D03*
Y1047900D03*
X48191Y1051247D03*
Y1054593D03*
Y1057940D03*
Y1061286D03*
X32049Y1051247D03*
Y1054593D03*
Y1057940D03*
Y1061286D03*
X48191Y1064633D03*
Y1067979D03*
Y1071326D03*
Y1074672D03*
Y1078018D03*
X32049Y1064633D03*
Y1067979D03*
Y1071326D03*
Y1074672D03*
Y1078018D03*
X48191Y1081365D03*
Y1084711D03*
Y1088058D03*
Y1091404D03*
Y1094751D03*
X32049Y1081365D03*
Y1084711D03*
Y1088058D03*
Y1091404D03*
Y1094751D03*
X48191Y1098097D03*
Y1101444D03*
Y1104790D03*
Y1108137D03*
Y1111483D03*
X32049Y1098097D03*
Y1101444D03*
Y1104790D03*
Y1108137D03*
Y1111483D03*
X48191Y1114829D03*
Y1118176D03*
Y1121522D03*
Y1124869D03*
Y1128215D03*
X32049Y1114829D03*
Y1118176D03*
Y1121522D03*
Y1124869D03*
Y1128215D03*
X48191Y1131562D03*
Y1134908D03*
Y1138255D03*
Y1141601D03*
Y1144948D03*
X32049Y1131562D03*
Y1134908D03*
Y1138255D03*
Y1141601D03*
Y1144948D03*
X48191Y1148294D03*
Y1151641D03*
Y1154987D03*
Y1158333D03*
Y1161680D03*
X32049Y1148294D03*
Y1151641D03*
Y1154987D03*
Y1158333D03*
Y1161680D03*
X48191Y1165026D03*
Y1168373D03*
Y1171719D03*
Y1175066D03*
X32049Y1165026D03*
Y1168373D03*
Y1171719D03*
Y1175066D03*
X48191Y1178412D03*
Y1181759D03*
Y1185105D03*
Y1188452D03*
Y1191798D03*
X32049Y1178412D03*
Y1181759D03*
Y1185105D03*
Y1188452D03*
Y1191798D03*
X48191Y1195144D03*
Y1198491D03*
Y1201837D03*
Y1205184D03*
Y1208530D03*
X32049Y1195144D03*
Y1198491D03*
Y1201837D03*
Y1205184D03*
Y1208530D03*
X48191Y1211877D03*
Y1215223D03*
Y1218570D03*
Y1221916D03*
Y1225263D03*
X32049Y1211877D03*
Y1215223D03*
Y1218570D03*
Y1221916D03*
Y1225263D03*
X48191Y1228609D03*
Y1231955D03*
Y1235302D03*
Y1238648D03*
Y1241995D03*
X32049Y1228609D03*
Y1231955D03*
Y1235302D03*
Y1238648D03*
Y1241995D03*
X48191Y1245341D03*
Y1248688D03*
Y1252034D03*
Y1255381D03*
Y1258727D03*
X32049Y1245341D03*
Y1248688D03*
Y1252034D03*
Y1255381D03*
Y1258727D03*
X48191Y1262074D03*
Y1265420D03*
X32049Y1262074D03*
Y1265420D03*
X61749Y766798D03*
Y770144D03*
Y773491D03*
Y776837D03*
Y780184D03*
Y783530D03*
Y786877D03*
Y790223D03*
Y793570D03*
Y796916D03*
Y800263D03*
Y803609D03*
Y806955D03*
Y810302D03*
Y813648D03*
Y816995D03*
Y820341D03*
Y823688D03*
Y827034D03*
Y830381D03*
Y833727D03*
Y837074D03*
Y840420D03*
Y843766D03*
Y847113D03*
Y850459D03*
Y853806D03*
Y857152D03*
Y860499D03*
Y863845D03*
Y867192D03*
Y870538D03*
Y873885D03*
Y877231D03*
Y880577D03*
Y883924D03*
Y887270D03*
Y890617D03*
Y893963D03*
Y897310D03*
Y900656D03*
Y904003D03*
Y907349D03*
Y910696D03*
Y914042D03*
Y917389D03*
Y920735D03*
Y924081D03*
Y927428D03*
Y930774D03*
Y934121D03*
Y937467D03*
Y940814D03*
Y944160D03*
Y947507D03*
Y950853D03*
Y954200D03*
Y957546D03*
Y960892D03*
Y964239D03*
Y967585D03*
Y970932D03*
Y974278D03*
Y977625D03*
Y980971D03*
Y984318D03*
Y987664D03*
Y991011D03*
Y994357D03*
Y1017782D03*
Y1021129D03*
Y1024475D03*
Y1027822D03*
Y1031168D03*
Y1034515D03*
Y1037861D03*
Y1041207D03*
Y1044554D03*
Y1047900D03*
Y1051247D03*
Y1054593D03*
Y1057940D03*
Y1061286D03*
Y1064633D03*
Y1067979D03*
Y1071326D03*
Y1074672D03*
Y1078018D03*
Y1081365D03*
Y1084711D03*
Y1088058D03*
Y1091404D03*
Y1094751D03*
Y1098097D03*
Y1101444D03*
Y1104790D03*
Y1108137D03*
Y1111483D03*
Y1114829D03*
Y1118176D03*
Y1121522D03*
Y1124869D03*
Y1128215D03*
Y1131562D03*
Y1134908D03*
Y1138255D03*
Y1141601D03*
Y1144948D03*
Y1148294D03*
Y1151641D03*
Y1154987D03*
Y1158333D03*
Y1161680D03*
Y1165026D03*
Y1168373D03*
Y1171719D03*
Y1175066D03*
Y1178412D03*
Y1181759D03*
Y1185105D03*
Y1188452D03*
Y1191798D03*
Y1195144D03*
Y1198491D03*
Y1201837D03*
Y1205184D03*
Y1208530D03*
Y1211877D03*
Y1215223D03*
Y1218570D03*
Y1221916D03*
Y1225263D03*
Y1228609D03*
Y1231955D03*
Y1235302D03*
Y1238648D03*
Y1241995D03*
Y1245341D03*
Y1248688D03*
Y1252034D03*
Y1255381D03*
Y1258727D03*
Y1262074D03*
Y1265420D03*
X77891Y766798D03*
Y770144D03*
Y773491D03*
Y776837D03*
Y780184D03*
Y783530D03*
Y786877D03*
Y790223D03*
Y793570D03*
Y796916D03*
Y800263D03*
Y803609D03*
Y806955D03*
Y810302D03*
Y813648D03*
Y816995D03*
Y820341D03*
Y823688D03*
Y827034D03*
Y830381D03*
Y833727D03*
Y837074D03*
Y840420D03*
Y843766D03*
Y847113D03*
Y850459D03*
Y853806D03*
Y857152D03*
Y860499D03*
Y863845D03*
Y867192D03*
Y870538D03*
Y873885D03*
Y877231D03*
Y880577D03*
Y883924D03*
Y887270D03*
Y890617D03*
Y893963D03*
Y897310D03*
Y900656D03*
Y904003D03*
Y907349D03*
Y910696D03*
Y914042D03*
Y917389D03*
Y920735D03*
Y924081D03*
Y927428D03*
Y930774D03*
Y934121D03*
Y937467D03*
Y940814D03*
Y944160D03*
Y947507D03*
Y950853D03*
Y954200D03*
Y957546D03*
Y960892D03*
Y964239D03*
Y967585D03*
Y970932D03*
Y974278D03*
Y977625D03*
Y980971D03*
Y984318D03*
Y987664D03*
Y991011D03*
Y994357D03*
Y1017782D03*
Y1021129D03*
Y1024475D03*
Y1027822D03*
Y1031168D03*
Y1034515D03*
Y1037861D03*
Y1041207D03*
Y1044554D03*
Y1047900D03*
Y1051247D03*
Y1054593D03*
Y1057940D03*
Y1061286D03*
Y1064633D03*
Y1067979D03*
Y1071326D03*
Y1074672D03*
Y1078018D03*
Y1081365D03*
Y1084711D03*
Y1088058D03*
Y1091404D03*
Y1094751D03*
Y1098097D03*
Y1101444D03*
Y1104790D03*
Y1108137D03*
Y1111483D03*
Y1114829D03*
Y1118176D03*
Y1121522D03*
Y1124869D03*
Y1128215D03*
Y1131562D03*
Y1134908D03*
Y1138255D03*
Y1141601D03*
Y1144948D03*
Y1148294D03*
Y1151641D03*
Y1154987D03*
Y1158333D03*
Y1161680D03*
Y1165026D03*
Y1168373D03*
Y1171719D03*
Y1175066D03*
Y1178412D03*
Y1181759D03*
Y1185105D03*
Y1188452D03*
Y1191798D03*
Y1195144D03*
Y1198491D03*
Y1201837D03*
Y1205184D03*
Y1208530D03*
Y1211877D03*
Y1215223D03*
Y1218570D03*
Y1221916D03*
Y1225263D03*
Y1228609D03*
Y1231955D03*
Y1235302D03*
Y1238648D03*
Y1241995D03*
Y1245341D03*
Y1248688D03*
Y1252034D03*
Y1255381D03*
Y1258727D03*
Y1262074D03*
Y1265420D03*
X91449Y766798D03*
Y770144D03*
Y773491D03*
Y776837D03*
Y780184D03*
Y783530D03*
Y786877D03*
Y790223D03*
Y793570D03*
Y796916D03*
Y800263D03*
Y803609D03*
Y806955D03*
Y810302D03*
Y813648D03*
Y816995D03*
Y820341D03*
Y823688D03*
Y827034D03*
Y830381D03*
Y833727D03*
Y837074D03*
Y840420D03*
Y843766D03*
Y847113D03*
Y850459D03*
Y853806D03*
Y857152D03*
Y860499D03*
Y863845D03*
Y867192D03*
Y870538D03*
Y873885D03*
Y877231D03*
Y880577D03*
Y883924D03*
Y887270D03*
Y890617D03*
Y893963D03*
Y897310D03*
Y900656D03*
Y904003D03*
Y907349D03*
Y910696D03*
Y914042D03*
Y917389D03*
Y920735D03*
Y924081D03*
Y927428D03*
Y930774D03*
Y934121D03*
Y937467D03*
Y940814D03*
Y944160D03*
Y947507D03*
Y950853D03*
Y954200D03*
Y957546D03*
Y960892D03*
Y964239D03*
Y967585D03*
Y970932D03*
Y974278D03*
Y977625D03*
Y980971D03*
Y984318D03*
Y987664D03*
Y991011D03*
Y994357D03*
Y1017782D03*
Y1021129D03*
Y1024475D03*
Y1027822D03*
Y1031168D03*
Y1034515D03*
Y1037861D03*
Y1041207D03*
Y1044554D03*
Y1047900D03*
Y1051247D03*
Y1054593D03*
Y1057940D03*
Y1061286D03*
Y1064633D03*
Y1067979D03*
Y1071326D03*
Y1074672D03*
Y1078018D03*
Y1081365D03*
Y1084711D03*
Y1088058D03*
Y1091404D03*
Y1094751D03*
Y1098097D03*
Y1101444D03*
Y1104790D03*
Y1108137D03*
Y1111483D03*
Y1114829D03*
Y1118176D03*
Y1121522D03*
Y1124869D03*
Y1128215D03*
Y1131562D03*
Y1134908D03*
Y1138255D03*
Y1141601D03*
Y1144948D03*
Y1148294D03*
Y1151641D03*
Y1154987D03*
Y1158333D03*
Y1161680D03*
Y1165026D03*
Y1168373D03*
Y1171719D03*
Y1175066D03*
Y1178412D03*
Y1181759D03*
Y1185105D03*
Y1188452D03*
Y1191798D03*
Y1195144D03*
Y1198491D03*
Y1201837D03*
Y1205184D03*
Y1208530D03*
Y1211877D03*
Y1215223D03*
Y1218570D03*
Y1221916D03*
Y1225263D03*
Y1228609D03*
Y1231955D03*
Y1235302D03*
Y1238648D03*
Y1241995D03*
Y1245341D03*
Y1248688D03*
Y1252034D03*
Y1255381D03*
Y1258727D03*
Y1262074D03*
Y1265420D03*
X107591Y766798D03*
Y770144D03*
Y773491D03*
Y776837D03*
Y780184D03*
Y783530D03*
Y786877D03*
Y790223D03*
Y793570D03*
Y796916D03*
Y800263D03*
Y803609D03*
Y806955D03*
Y810302D03*
Y813648D03*
Y816995D03*
Y820341D03*
Y823688D03*
Y827034D03*
Y830381D03*
Y833727D03*
Y837074D03*
Y840420D03*
Y843766D03*
Y847113D03*
Y850459D03*
Y853806D03*
Y857152D03*
Y860499D03*
Y863845D03*
Y867192D03*
Y870538D03*
Y873885D03*
Y877231D03*
Y880577D03*
Y883924D03*
Y887270D03*
Y890617D03*
Y893963D03*
Y897310D03*
Y900656D03*
Y904003D03*
Y907349D03*
Y910696D03*
Y914042D03*
Y917389D03*
Y920735D03*
Y924081D03*
Y927428D03*
Y930774D03*
Y934121D03*
Y937467D03*
Y940814D03*
Y944160D03*
Y947507D03*
Y950853D03*
Y954200D03*
Y957546D03*
Y960892D03*
Y964239D03*
Y967585D03*
Y970932D03*
Y974278D03*
Y977625D03*
Y980971D03*
Y984318D03*
Y987664D03*
Y991011D03*
Y994357D03*
Y1017782D03*
Y1021129D03*
Y1024475D03*
Y1027822D03*
Y1031168D03*
Y1034515D03*
Y1037861D03*
Y1041207D03*
Y1044554D03*
Y1047900D03*
Y1051247D03*
Y1054593D03*
Y1057940D03*
Y1061286D03*
Y1064633D03*
Y1067979D03*
Y1071326D03*
Y1074672D03*
Y1078018D03*
Y1081365D03*
Y1084711D03*
Y1088058D03*
Y1091404D03*
Y1094751D03*
Y1098097D03*
Y1101444D03*
Y1104790D03*
Y1108137D03*
Y1111483D03*
Y1114829D03*
Y1118176D03*
Y1121522D03*
Y1124869D03*
Y1128215D03*
Y1131562D03*
Y1134908D03*
Y1138255D03*
Y1141601D03*
Y1144948D03*
Y1148294D03*
Y1151641D03*
Y1154987D03*
Y1158333D03*
Y1161680D03*
Y1165026D03*
Y1168373D03*
Y1171719D03*
Y1175066D03*
Y1178412D03*
Y1181759D03*
Y1185105D03*
Y1188452D03*
Y1191798D03*
Y1195144D03*
Y1198491D03*
Y1201837D03*
Y1205184D03*
Y1208530D03*
Y1211877D03*
Y1215223D03*
Y1218570D03*
Y1221916D03*
Y1225263D03*
Y1228609D03*
Y1231955D03*
Y1235302D03*
Y1238648D03*
Y1241995D03*
Y1245341D03*
Y1248688D03*
Y1252034D03*
Y1255381D03*
Y1258727D03*
Y1262074D03*
Y1265420D03*
X121149Y766798D03*
Y770144D03*
Y773491D03*
Y776837D03*
Y780184D03*
Y783530D03*
Y786877D03*
Y790223D03*
Y793570D03*
Y796916D03*
Y800263D03*
Y803609D03*
Y806955D03*
Y810302D03*
Y813648D03*
Y816995D03*
Y820341D03*
Y823688D03*
Y827034D03*
Y830381D03*
Y833727D03*
Y837074D03*
Y840420D03*
Y843766D03*
Y847113D03*
Y850459D03*
Y853806D03*
Y857152D03*
Y860499D03*
Y863845D03*
Y867192D03*
Y870538D03*
Y873885D03*
Y877231D03*
Y880577D03*
Y883924D03*
Y887270D03*
Y890617D03*
Y893963D03*
Y897310D03*
Y900656D03*
Y904003D03*
Y907349D03*
Y910696D03*
Y914042D03*
Y917389D03*
Y920735D03*
Y924081D03*
Y927428D03*
Y930774D03*
Y934121D03*
Y937467D03*
Y940814D03*
Y944160D03*
Y947507D03*
Y950853D03*
Y954200D03*
Y957546D03*
Y960892D03*
Y964239D03*
Y967585D03*
Y970932D03*
Y974278D03*
Y977625D03*
Y980971D03*
Y984318D03*
Y987664D03*
Y991011D03*
Y994357D03*
Y1017782D03*
Y1021129D03*
Y1024475D03*
Y1027822D03*
Y1031168D03*
Y1034515D03*
Y1037861D03*
Y1041207D03*
Y1044554D03*
Y1047900D03*
Y1051247D03*
Y1054593D03*
Y1057940D03*
Y1061286D03*
Y1064633D03*
Y1067979D03*
Y1071326D03*
Y1074672D03*
Y1078018D03*
Y1081365D03*
Y1084711D03*
Y1088058D03*
Y1091404D03*
Y1094751D03*
Y1098097D03*
Y1101444D03*
Y1104790D03*
Y1108137D03*
Y1111483D03*
Y1114829D03*
Y1118176D03*
Y1121522D03*
Y1124869D03*
Y1128215D03*
Y1131562D03*
Y1134908D03*
Y1138255D03*
Y1141601D03*
Y1144948D03*
Y1148294D03*
Y1151641D03*
Y1154987D03*
Y1158333D03*
Y1161680D03*
Y1165026D03*
Y1168373D03*
Y1171719D03*
Y1175066D03*
Y1178412D03*
Y1181759D03*
Y1185105D03*
Y1188452D03*
Y1191798D03*
Y1195144D03*
Y1198491D03*
Y1201837D03*
Y1205184D03*
Y1208530D03*
Y1211877D03*
Y1215223D03*
Y1218570D03*
Y1221916D03*
Y1225263D03*
Y1228609D03*
Y1231955D03*
Y1235302D03*
Y1238648D03*
Y1241995D03*
Y1245341D03*
Y1248688D03*
Y1252034D03*
Y1255381D03*
Y1258727D03*
Y1262074D03*
Y1265420D03*
X137291Y766798D03*
Y770144D03*
Y773491D03*
Y776837D03*
Y780184D03*
Y783530D03*
Y786877D03*
Y790223D03*
Y793570D03*
Y796916D03*
Y800263D03*
Y803609D03*
Y806955D03*
Y810302D03*
Y813648D03*
Y816995D03*
Y820341D03*
Y823688D03*
Y827034D03*
Y830381D03*
Y833727D03*
Y837074D03*
Y840420D03*
Y843766D03*
Y847113D03*
Y850459D03*
Y853806D03*
Y857152D03*
Y860499D03*
Y863845D03*
Y867192D03*
Y870538D03*
Y873885D03*
Y877231D03*
Y880577D03*
Y883924D03*
Y887270D03*
Y890617D03*
Y893963D03*
Y897310D03*
Y900656D03*
Y904003D03*
Y907349D03*
Y910696D03*
Y914042D03*
Y917389D03*
Y920735D03*
Y924081D03*
Y927428D03*
Y930774D03*
Y934121D03*
Y937467D03*
Y940814D03*
Y944160D03*
Y947507D03*
Y950853D03*
Y954200D03*
Y957546D03*
Y960892D03*
Y964239D03*
Y967585D03*
Y970932D03*
Y974278D03*
Y977625D03*
Y980971D03*
Y984318D03*
Y987664D03*
Y991011D03*
Y994357D03*
Y1017782D03*
Y1021129D03*
Y1024475D03*
Y1027822D03*
Y1031168D03*
Y1034515D03*
Y1037861D03*
Y1041207D03*
Y1044554D03*
Y1047900D03*
Y1051247D03*
Y1054593D03*
Y1057940D03*
Y1061286D03*
Y1064633D03*
Y1067979D03*
Y1071326D03*
Y1074672D03*
Y1078018D03*
Y1081365D03*
Y1084711D03*
Y1088058D03*
Y1091404D03*
Y1094751D03*
Y1098097D03*
Y1101444D03*
Y1104790D03*
Y1108137D03*
Y1111483D03*
Y1114829D03*
Y1118176D03*
Y1121522D03*
Y1124869D03*
Y1128215D03*
Y1131562D03*
Y1134908D03*
Y1138255D03*
Y1141601D03*
Y1144948D03*
Y1148294D03*
Y1151641D03*
Y1154987D03*
Y1158333D03*
Y1161680D03*
Y1165026D03*
Y1168373D03*
Y1171719D03*
Y1175066D03*
Y1178412D03*
Y1181759D03*
Y1185105D03*
Y1188452D03*
Y1191798D03*
Y1195144D03*
Y1198491D03*
Y1201837D03*
Y1205184D03*
Y1208530D03*
Y1211877D03*
Y1215223D03*
Y1218570D03*
Y1221916D03*
Y1225263D03*
Y1228609D03*
Y1231955D03*
Y1235302D03*
Y1238648D03*
Y1241995D03*
Y1245341D03*
Y1248688D03*
Y1252034D03*
Y1255381D03*
Y1258727D03*
Y1262074D03*
Y1265420D03*
X150849Y766798D03*
Y770144D03*
Y773491D03*
Y776837D03*
Y780184D03*
Y783530D03*
Y786877D03*
Y790223D03*
Y793570D03*
Y796916D03*
Y800263D03*
Y803609D03*
Y806955D03*
Y810302D03*
Y813648D03*
Y816995D03*
Y820341D03*
Y823688D03*
Y827034D03*
Y830381D03*
Y833727D03*
Y837074D03*
Y840420D03*
Y843766D03*
Y847113D03*
Y850459D03*
Y853806D03*
Y857152D03*
Y860499D03*
Y863845D03*
Y867192D03*
Y870538D03*
Y873885D03*
Y877231D03*
Y880577D03*
Y883924D03*
Y887270D03*
Y890617D03*
Y893963D03*
Y897310D03*
Y900656D03*
Y904003D03*
Y907349D03*
Y910696D03*
Y914042D03*
Y917389D03*
Y920735D03*
Y924081D03*
Y927428D03*
Y930774D03*
Y934121D03*
Y937467D03*
Y940814D03*
Y944160D03*
Y947507D03*
Y950853D03*
Y954200D03*
Y957546D03*
Y960892D03*
Y964239D03*
Y967585D03*
Y970932D03*
Y974278D03*
Y977625D03*
Y980971D03*
Y984318D03*
Y987664D03*
Y991011D03*
Y994357D03*
Y1017782D03*
Y1021129D03*
Y1024475D03*
Y1027822D03*
Y1031168D03*
Y1034515D03*
Y1037861D03*
Y1041207D03*
Y1044554D03*
Y1047900D03*
Y1051247D03*
Y1054593D03*
Y1057940D03*
Y1061286D03*
Y1064633D03*
Y1067979D03*
Y1071326D03*
Y1074672D03*
Y1078018D03*
Y1081365D03*
Y1084711D03*
Y1088058D03*
Y1091404D03*
Y1094751D03*
Y1098097D03*
Y1101444D03*
Y1104790D03*
Y1108137D03*
Y1111483D03*
Y1114829D03*
Y1118176D03*
Y1121522D03*
Y1124869D03*
Y1128215D03*
Y1131562D03*
Y1134908D03*
Y1138255D03*
Y1141601D03*
Y1144948D03*
Y1148294D03*
Y1151641D03*
Y1154987D03*
Y1158333D03*
Y1161680D03*
Y1165026D03*
Y1168373D03*
Y1171719D03*
Y1175066D03*
Y1178412D03*
Y1181759D03*
Y1185105D03*
Y1188452D03*
Y1191798D03*
Y1195144D03*
Y1198491D03*
Y1201837D03*
Y1205184D03*
Y1208530D03*
Y1211877D03*
Y1215223D03*
Y1218570D03*
Y1221916D03*
Y1225263D03*
Y1228609D03*
Y1231955D03*
Y1235302D03*
Y1238648D03*
Y1241995D03*
Y1245341D03*
Y1248688D03*
Y1252034D03*
Y1255381D03*
Y1258727D03*
Y1262074D03*
Y1265420D03*
X166991Y766798D03*
Y770144D03*
Y773491D03*
Y776837D03*
Y780184D03*
Y783530D03*
Y786877D03*
Y790223D03*
Y793570D03*
Y796916D03*
Y800263D03*
Y803609D03*
Y806955D03*
Y810302D03*
Y813648D03*
Y816995D03*
Y820341D03*
Y823688D03*
Y827034D03*
Y830381D03*
Y833727D03*
Y837074D03*
Y840420D03*
Y843766D03*
Y847113D03*
Y850459D03*
Y853806D03*
Y857152D03*
Y860499D03*
Y863845D03*
Y867192D03*
Y870538D03*
Y873885D03*
Y877231D03*
Y880577D03*
Y883924D03*
Y887270D03*
Y890617D03*
Y893963D03*
Y897310D03*
Y900656D03*
Y904003D03*
Y907349D03*
Y910696D03*
Y914042D03*
Y917389D03*
Y920735D03*
Y924081D03*
Y927428D03*
Y930774D03*
Y934121D03*
Y937467D03*
Y940814D03*
Y944160D03*
Y947507D03*
Y950853D03*
Y954200D03*
Y957546D03*
Y960892D03*
Y964239D03*
Y967585D03*
Y970932D03*
Y974278D03*
Y977625D03*
Y980971D03*
Y984318D03*
Y987664D03*
Y991011D03*
Y994357D03*
Y1017782D03*
Y1021129D03*
Y1024475D03*
Y1027822D03*
Y1031168D03*
Y1034515D03*
Y1037861D03*
Y1041207D03*
Y1044554D03*
Y1047900D03*
Y1051247D03*
Y1054593D03*
Y1057940D03*
Y1061286D03*
Y1064633D03*
Y1067979D03*
Y1071326D03*
Y1074672D03*
Y1078018D03*
Y1081365D03*
Y1084711D03*
Y1088058D03*
Y1091404D03*
Y1094751D03*
Y1098097D03*
Y1101444D03*
Y1104790D03*
Y1108137D03*
Y1111483D03*
Y1114829D03*
Y1118176D03*
Y1121522D03*
Y1124869D03*
Y1128215D03*
Y1131562D03*
Y1134908D03*
Y1138255D03*
Y1141601D03*
Y1144948D03*
Y1148294D03*
Y1151641D03*
Y1154987D03*
Y1158333D03*
Y1161680D03*
Y1165026D03*
Y1168373D03*
Y1171719D03*
Y1175066D03*
Y1178412D03*
Y1181759D03*
Y1185105D03*
Y1188452D03*
Y1191798D03*
Y1195144D03*
Y1198491D03*
Y1201837D03*
Y1205184D03*
Y1208530D03*
Y1211877D03*
Y1215223D03*
Y1218570D03*
Y1221916D03*
Y1225263D03*
Y1228609D03*
Y1231955D03*
Y1235302D03*
Y1238648D03*
Y1241995D03*
Y1245341D03*
Y1248688D03*
Y1252034D03*
Y1255381D03*
Y1258727D03*
Y1262074D03*
Y1265420D03*
X180549Y766798D03*
Y770144D03*
Y773491D03*
Y776837D03*
Y780184D03*
Y783530D03*
Y786877D03*
Y790223D03*
Y793570D03*
Y796916D03*
Y800263D03*
Y803609D03*
Y806955D03*
Y810302D03*
Y813648D03*
Y816995D03*
Y820341D03*
Y823688D03*
Y827034D03*
Y830381D03*
Y833727D03*
Y837074D03*
Y840420D03*
Y843766D03*
Y847113D03*
Y850459D03*
Y853806D03*
Y857152D03*
Y860499D03*
Y863845D03*
Y867192D03*
Y870538D03*
Y873885D03*
Y877231D03*
Y880577D03*
Y883924D03*
Y887270D03*
Y890617D03*
Y893963D03*
Y897310D03*
Y900656D03*
Y904003D03*
Y907349D03*
Y910696D03*
Y914042D03*
Y917389D03*
Y920735D03*
Y924081D03*
Y927428D03*
Y930774D03*
Y934121D03*
Y937467D03*
Y940814D03*
Y944160D03*
Y947507D03*
Y950853D03*
Y954200D03*
Y957546D03*
Y960892D03*
Y964239D03*
Y967585D03*
Y970932D03*
Y974278D03*
Y977625D03*
Y980971D03*
Y984318D03*
Y987664D03*
Y991011D03*
Y994357D03*
Y1017782D03*
Y1021129D03*
Y1024475D03*
Y1027822D03*
Y1031168D03*
Y1034515D03*
Y1037861D03*
Y1041207D03*
Y1044554D03*
Y1047900D03*
Y1051247D03*
Y1054593D03*
Y1057940D03*
Y1061286D03*
Y1064633D03*
Y1067979D03*
Y1071326D03*
Y1074672D03*
Y1078018D03*
Y1081365D03*
Y1084711D03*
Y1088058D03*
Y1091404D03*
Y1094751D03*
Y1098097D03*
Y1101444D03*
Y1104790D03*
Y1108137D03*
Y1111483D03*
Y1114829D03*
Y1118176D03*
Y1121522D03*
Y1124869D03*
Y1128215D03*
Y1131562D03*
Y1134908D03*
Y1138255D03*
Y1141601D03*
Y1144948D03*
Y1148294D03*
Y1151641D03*
Y1154987D03*
Y1158333D03*
Y1161680D03*
Y1165026D03*
Y1168373D03*
Y1171719D03*
Y1175066D03*
Y1178412D03*
Y1181759D03*
Y1185105D03*
Y1188452D03*
Y1191798D03*
Y1195144D03*
Y1198491D03*
Y1201837D03*
Y1205184D03*
Y1208530D03*
Y1211877D03*
Y1215223D03*
Y1218570D03*
Y1221916D03*
Y1225263D03*
Y1228609D03*
Y1231955D03*
Y1235302D03*
Y1238648D03*
Y1241995D03*
Y1245341D03*
Y1248688D03*
Y1252034D03*
Y1255381D03*
Y1258727D03*
Y1262074D03*
Y1265420D03*
X210249Y766798D03*
Y770144D03*
X196691Y766798D03*
Y770144D03*
X210249Y773491D03*
Y776837D03*
Y780184D03*
Y783530D03*
Y786877D03*
X196691Y773491D03*
Y776837D03*
Y780184D03*
Y783530D03*
Y786877D03*
X210249Y790223D03*
Y793570D03*
Y796916D03*
Y800263D03*
Y803609D03*
X196691Y790223D03*
Y793570D03*
Y796916D03*
Y800263D03*
Y803609D03*
X210249Y806955D03*
Y810302D03*
Y813648D03*
Y816995D03*
Y820341D03*
X196691Y806955D03*
Y810302D03*
Y813648D03*
Y816995D03*
Y820341D03*
X210249Y823688D03*
Y827034D03*
Y830381D03*
Y833727D03*
X196691Y823688D03*
Y827034D03*
Y830381D03*
Y833727D03*
X210249Y837074D03*
Y840420D03*
Y843766D03*
Y847113D03*
Y850459D03*
X196691Y837074D03*
Y840420D03*
Y843766D03*
Y847113D03*
Y850459D03*
X210249Y853806D03*
Y857152D03*
Y860499D03*
Y863845D03*
Y867192D03*
X196691Y853806D03*
Y857152D03*
Y860499D03*
Y863845D03*
Y867192D03*
X210249Y870538D03*
Y873885D03*
Y877231D03*
Y880577D03*
Y883924D03*
X196691Y870538D03*
Y873885D03*
Y877231D03*
Y880577D03*
Y883924D03*
X210249Y887270D03*
Y890617D03*
Y893963D03*
Y897310D03*
Y900656D03*
X196691Y887270D03*
Y890617D03*
Y893963D03*
Y897310D03*
Y900656D03*
X210249Y904003D03*
Y907349D03*
Y910696D03*
Y914042D03*
Y917389D03*
X196691Y904003D03*
Y907349D03*
Y910696D03*
Y914042D03*
Y917389D03*
X210249Y920735D03*
Y924081D03*
Y927428D03*
Y930774D03*
Y934121D03*
X196691Y920735D03*
Y924081D03*
Y927428D03*
Y930774D03*
Y934121D03*
X210249Y937467D03*
Y940814D03*
Y944160D03*
Y947507D03*
X196691Y937467D03*
Y940814D03*
Y944160D03*
Y947507D03*
X210249Y950853D03*
Y954200D03*
Y957546D03*
Y960892D03*
Y964239D03*
X196691Y950853D03*
Y954200D03*
Y957546D03*
Y960892D03*
Y964239D03*
X210249Y967585D03*
Y970932D03*
Y974278D03*
Y977625D03*
Y980971D03*
X196691Y967585D03*
Y970932D03*
Y974278D03*
Y977625D03*
Y980971D03*
X210249Y984318D03*
Y987664D03*
Y991011D03*
Y994357D03*
X196691Y984318D03*
Y987664D03*
Y991011D03*
Y994357D03*
X210249Y1017782D03*
Y1021129D03*
Y1024475D03*
Y1027822D03*
Y1031168D03*
X196691Y1017782D03*
Y1021129D03*
Y1024475D03*
Y1027822D03*
Y1031168D03*
X210249Y1034515D03*
Y1037861D03*
Y1041207D03*
Y1044554D03*
Y1047900D03*
X196691Y1034515D03*
Y1037861D03*
Y1041207D03*
Y1044554D03*
Y1047900D03*
X210249Y1051247D03*
Y1054593D03*
Y1057940D03*
Y1061286D03*
X196691Y1051247D03*
Y1054593D03*
Y1057940D03*
Y1061286D03*
X210249Y1064633D03*
Y1067979D03*
Y1071326D03*
Y1074672D03*
Y1078018D03*
X196691Y1064633D03*
Y1067979D03*
Y1071326D03*
Y1074672D03*
Y1078018D03*
X210249Y1081365D03*
Y1084711D03*
Y1088058D03*
Y1091404D03*
Y1094751D03*
X196691Y1081365D03*
Y1084711D03*
Y1088058D03*
Y1091404D03*
Y1094751D03*
X210249Y1098097D03*
Y1101444D03*
Y1104790D03*
Y1108137D03*
Y1111483D03*
X196691Y1098097D03*
Y1101444D03*
Y1104790D03*
Y1108137D03*
Y1111483D03*
X210249Y1114829D03*
Y1118176D03*
Y1121522D03*
Y1124869D03*
Y1128215D03*
X196691Y1114829D03*
Y1118176D03*
Y1121522D03*
Y1124869D03*
Y1128215D03*
X210249Y1131562D03*
Y1134908D03*
Y1138255D03*
Y1141601D03*
Y1144948D03*
X196691Y1131562D03*
Y1134908D03*
Y1138255D03*
Y1141601D03*
Y1144948D03*
X210249Y1148294D03*
Y1151641D03*
Y1154987D03*
Y1158333D03*
Y1161680D03*
X196691Y1148294D03*
Y1151641D03*
Y1154987D03*
Y1158333D03*
Y1161680D03*
X210249Y1165026D03*
Y1168373D03*
Y1171719D03*
Y1175066D03*
X196691Y1165026D03*
Y1168373D03*
Y1171719D03*
Y1175066D03*
X210249Y1178412D03*
Y1181759D03*
Y1185105D03*
Y1188452D03*
Y1191798D03*
X196691Y1178412D03*
Y1181759D03*
Y1185105D03*
Y1188452D03*
Y1191798D03*
X210249Y1195144D03*
Y1198491D03*
Y1201837D03*
Y1205184D03*
Y1208530D03*
X196691Y1195144D03*
Y1198491D03*
Y1201837D03*
Y1205184D03*
Y1208530D03*
X210249Y1211877D03*
Y1215223D03*
Y1218570D03*
Y1221916D03*
Y1225263D03*
X196691Y1211877D03*
Y1215223D03*
Y1218570D03*
Y1221916D03*
Y1225263D03*
X210249Y1228609D03*
Y1231955D03*
Y1235302D03*
Y1238648D03*
Y1241995D03*
X196691Y1228609D03*
Y1231955D03*
Y1235302D03*
Y1238648D03*
Y1241995D03*
X210249Y1245341D03*
Y1248688D03*
Y1252034D03*
Y1255381D03*
Y1258727D03*
X196691Y1245341D03*
Y1248688D03*
Y1252034D03*
Y1255381D03*
Y1258727D03*
X210249Y1262074D03*
Y1265420D03*
X196691Y1262074D03*
Y1265420D03*
X226391Y766798D03*
Y770144D03*
Y773491D03*
Y776837D03*
Y780184D03*
Y783530D03*
Y786877D03*
Y790223D03*
Y793570D03*
Y796916D03*
Y800263D03*
Y803609D03*
Y806955D03*
Y810302D03*
Y813648D03*
Y816995D03*
Y820341D03*
Y823688D03*
Y827034D03*
Y830381D03*
Y833727D03*
Y837074D03*
Y840420D03*
Y843766D03*
Y847113D03*
Y850459D03*
Y853806D03*
Y857152D03*
Y860499D03*
Y863845D03*
Y867192D03*
Y870538D03*
Y873885D03*
Y877231D03*
Y880577D03*
Y883924D03*
Y887270D03*
Y890617D03*
Y893963D03*
Y897310D03*
Y900656D03*
Y904003D03*
Y907349D03*
Y910696D03*
Y914042D03*
Y917389D03*
Y920735D03*
Y924081D03*
Y927428D03*
Y930774D03*
Y934121D03*
Y937467D03*
Y940814D03*
Y944160D03*
Y947507D03*
Y950853D03*
Y954200D03*
Y957546D03*
Y960892D03*
Y964239D03*
Y967585D03*
Y970932D03*
Y974278D03*
Y977625D03*
Y980971D03*
Y984318D03*
Y987664D03*
Y991011D03*
Y994357D03*
Y1017782D03*
Y1021129D03*
Y1024475D03*
Y1027822D03*
Y1031168D03*
Y1034515D03*
Y1037861D03*
Y1041207D03*
Y1044554D03*
Y1047900D03*
Y1051247D03*
Y1054593D03*
Y1057940D03*
Y1061286D03*
Y1064633D03*
Y1067979D03*
Y1071326D03*
Y1074672D03*
Y1078018D03*
Y1081365D03*
Y1084711D03*
Y1088058D03*
Y1091404D03*
Y1094751D03*
Y1098097D03*
Y1101444D03*
Y1104790D03*
Y1108137D03*
Y1111483D03*
Y1114829D03*
Y1118176D03*
Y1121522D03*
Y1124869D03*
Y1128215D03*
Y1131562D03*
Y1134908D03*
Y1138255D03*
Y1141601D03*
Y1144948D03*
Y1148294D03*
Y1151641D03*
Y1154987D03*
Y1158333D03*
Y1161680D03*
Y1165026D03*
Y1168373D03*
Y1171719D03*
Y1175066D03*
Y1178412D03*
Y1181759D03*
Y1185105D03*
Y1188452D03*
Y1191798D03*
Y1195144D03*
Y1198491D03*
Y1201837D03*
Y1205184D03*
Y1208530D03*
Y1211877D03*
Y1215223D03*
Y1218570D03*
Y1221916D03*
Y1225263D03*
Y1228609D03*
Y1231955D03*
Y1235302D03*
Y1238648D03*
Y1241995D03*
Y1245341D03*
Y1248688D03*
Y1252034D03*
Y1255381D03*
Y1258727D03*
Y1262074D03*
Y1265420D03*
X239949Y766798D03*
Y770144D03*
Y773491D03*
Y776837D03*
Y780184D03*
Y783530D03*
Y786877D03*
Y790223D03*
Y793570D03*
Y796916D03*
Y800263D03*
Y803609D03*
Y806955D03*
Y810302D03*
Y813648D03*
Y816995D03*
Y820341D03*
Y823688D03*
Y827034D03*
Y830381D03*
Y833727D03*
Y837074D03*
Y840420D03*
Y843766D03*
Y847113D03*
Y850459D03*
Y853806D03*
Y857152D03*
Y860499D03*
Y863845D03*
Y867192D03*
Y870538D03*
Y873885D03*
Y877231D03*
Y880577D03*
Y883924D03*
Y887270D03*
Y890617D03*
Y893963D03*
Y897310D03*
Y900656D03*
Y904003D03*
Y907349D03*
Y910696D03*
Y914042D03*
Y917389D03*
Y920735D03*
Y924081D03*
Y927428D03*
Y930774D03*
Y934121D03*
Y937467D03*
Y940814D03*
Y944160D03*
Y947507D03*
Y950853D03*
Y954200D03*
Y957546D03*
Y960892D03*
Y964239D03*
Y967585D03*
Y970932D03*
Y974278D03*
Y977625D03*
Y980971D03*
Y984318D03*
Y987664D03*
Y991011D03*
Y994357D03*
Y1017782D03*
Y1021129D03*
Y1024475D03*
Y1027822D03*
Y1031168D03*
Y1034515D03*
Y1037861D03*
Y1041207D03*
Y1044554D03*
Y1047900D03*
Y1051247D03*
Y1054593D03*
Y1057940D03*
Y1061286D03*
Y1064633D03*
Y1067979D03*
Y1071326D03*
Y1074672D03*
Y1078018D03*
Y1081365D03*
Y1084711D03*
Y1088058D03*
Y1091404D03*
Y1094751D03*
Y1098097D03*
Y1101444D03*
Y1104790D03*
Y1108137D03*
Y1111483D03*
Y1114829D03*
Y1118176D03*
Y1121522D03*
Y1124869D03*
Y1128215D03*
Y1131562D03*
Y1134908D03*
Y1138255D03*
Y1141601D03*
Y1144948D03*
Y1148294D03*
Y1151641D03*
Y1154987D03*
Y1158333D03*
Y1161680D03*
Y1165026D03*
Y1168373D03*
Y1171719D03*
Y1175066D03*
Y1178412D03*
Y1181759D03*
Y1185105D03*
Y1188452D03*
Y1191798D03*
Y1195144D03*
Y1198491D03*
Y1201837D03*
Y1205184D03*
Y1208530D03*
Y1211877D03*
Y1215223D03*
Y1218570D03*
Y1221916D03*
Y1225263D03*
Y1228609D03*
Y1231955D03*
Y1235302D03*
Y1238648D03*
Y1241995D03*
Y1245341D03*
Y1248688D03*
Y1252034D03*
Y1255381D03*
Y1258727D03*
Y1262074D03*
Y1265420D03*
X256091Y766798D03*
Y770144D03*
Y773491D03*
Y776837D03*
Y780184D03*
Y783530D03*
Y786877D03*
Y790223D03*
Y793570D03*
Y796916D03*
Y800263D03*
Y803609D03*
Y806955D03*
Y810302D03*
Y813648D03*
Y816995D03*
Y820341D03*
Y823688D03*
Y827034D03*
Y830381D03*
Y833727D03*
Y837074D03*
Y840420D03*
Y843766D03*
Y847113D03*
Y850459D03*
Y853806D03*
Y857152D03*
Y860499D03*
Y863845D03*
Y867192D03*
Y870538D03*
Y873885D03*
Y877231D03*
Y880577D03*
Y883924D03*
Y887270D03*
Y890617D03*
Y893963D03*
Y897310D03*
Y900656D03*
Y904003D03*
Y907349D03*
Y910696D03*
Y914042D03*
Y917389D03*
Y920735D03*
Y924081D03*
Y927428D03*
Y930774D03*
Y934121D03*
Y937467D03*
Y940814D03*
Y944160D03*
Y947507D03*
Y950853D03*
Y954200D03*
Y957546D03*
Y960892D03*
Y964239D03*
Y967585D03*
Y970932D03*
Y974278D03*
Y977625D03*
Y980971D03*
Y984318D03*
Y987664D03*
Y991011D03*
Y994357D03*
Y1017782D03*
Y1021129D03*
Y1024475D03*
Y1027822D03*
Y1031168D03*
Y1034515D03*
Y1037861D03*
Y1041207D03*
Y1044554D03*
Y1047900D03*
Y1051247D03*
Y1054593D03*
Y1057940D03*
Y1061286D03*
Y1064633D03*
Y1067979D03*
Y1071326D03*
Y1074672D03*
Y1078018D03*
Y1081365D03*
Y1084711D03*
Y1088058D03*
Y1091404D03*
Y1094751D03*
Y1098097D03*
Y1101444D03*
Y1104790D03*
Y1108137D03*
Y1111483D03*
Y1114829D03*
Y1118176D03*
Y1121522D03*
Y1124869D03*
Y1128215D03*
Y1131562D03*
Y1134908D03*
Y1138255D03*
Y1141601D03*
Y1144948D03*
Y1148294D03*
Y1151641D03*
Y1154987D03*
Y1158333D03*
Y1161680D03*
Y1165026D03*
Y1168373D03*
Y1171719D03*
Y1175066D03*
Y1178412D03*
Y1181759D03*
Y1185105D03*
Y1188452D03*
Y1191798D03*
Y1195144D03*
Y1198491D03*
Y1201837D03*
Y1205184D03*
Y1208530D03*
Y1211877D03*
Y1215223D03*
Y1218570D03*
Y1221916D03*
Y1225263D03*
Y1228609D03*
Y1231955D03*
Y1235302D03*
Y1238648D03*
Y1241995D03*
Y1245341D03*
Y1248688D03*
Y1252034D03*
Y1255381D03*
Y1258727D03*
Y1262074D03*
Y1265420D03*
X625249Y766798D03*
Y770144D03*
Y773491D03*
Y776837D03*
Y780184D03*
Y783530D03*
Y786877D03*
Y790223D03*
Y793570D03*
Y796916D03*
Y800263D03*
Y803609D03*
Y806955D03*
Y810302D03*
Y813648D03*
Y816995D03*
Y820341D03*
Y823688D03*
Y827034D03*
Y830381D03*
Y833727D03*
Y837074D03*
Y840420D03*
Y843766D03*
Y847113D03*
Y850459D03*
Y853806D03*
Y857152D03*
Y860499D03*
Y863845D03*
Y867192D03*
Y870538D03*
Y873885D03*
Y877231D03*
Y880577D03*
Y883924D03*
Y887270D03*
Y890617D03*
Y893963D03*
Y897310D03*
Y900656D03*
Y904003D03*
Y907349D03*
Y910696D03*
Y914042D03*
Y917389D03*
Y920735D03*
Y924081D03*
Y927428D03*
Y930774D03*
Y934121D03*
Y937467D03*
Y940814D03*
Y944160D03*
Y947507D03*
Y950853D03*
Y954200D03*
Y957546D03*
Y960892D03*
Y964239D03*
Y967585D03*
Y970932D03*
Y974278D03*
Y977625D03*
Y980971D03*
Y984318D03*
Y987664D03*
Y991011D03*
Y994357D03*
Y1017782D03*
Y1021129D03*
Y1024475D03*
Y1027822D03*
Y1031168D03*
Y1034515D03*
Y1037861D03*
Y1041207D03*
Y1044554D03*
Y1047900D03*
Y1051247D03*
Y1054593D03*
Y1057940D03*
Y1061286D03*
Y1064633D03*
Y1067979D03*
Y1071326D03*
Y1074672D03*
Y1078018D03*
Y1081365D03*
Y1084711D03*
Y1088058D03*
Y1091404D03*
Y1094751D03*
Y1098097D03*
Y1101444D03*
Y1104790D03*
Y1108137D03*
Y1111483D03*
Y1114829D03*
Y1118176D03*
Y1121522D03*
Y1124869D03*
Y1128215D03*
Y1131562D03*
Y1134908D03*
Y1138255D03*
Y1141601D03*
Y1144948D03*
Y1148294D03*
Y1151641D03*
Y1154987D03*
Y1158333D03*
Y1161680D03*
Y1165026D03*
Y1168373D03*
Y1171719D03*
Y1175066D03*
Y1178412D03*
Y1181759D03*
Y1185105D03*
Y1188452D03*
Y1191798D03*
Y1195144D03*
Y1198491D03*
Y1201837D03*
Y1205184D03*
Y1208530D03*
Y1211877D03*
Y1215223D03*
Y1218570D03*
Y1221916D03*
Y1225263D03*
Y1228609D03*
Y1231955D03*
Y1235302D03*
Y1238648D03*
Y1241995D03*
Y1245341D03*
Y1248688D03*
Y1252034D03*
Y1255381D03*
Y1258727D03*
Y1262074D03*
Y1265420D03*
X641391Y766798D03*
Y770144D03*
Y773491D03*
Y776837D03*
Y780184D03*
Y783530D03*
Y786877D03*
Y790223D03*
Y793570D03*
Y796916D03*
Y800263D03*
Y803609D03*
Y806955D03*
Y810302D03*
Y813648D03*
Y816995D03*
Y820341D03*
Y823688D03*
Y827034D03*
Y830381D03*
Y833727D03*
Y837074D03*
Y840420D03*
Y843766D03*
Y847113D03*
Y850459D03*
Y853806D03*
Y857152D03*
Y860499D03*
Y863845D03*
Y867192D03*
Y870538D03*
Y873885D03*
Y877231D03*
Y880577D03*
Y883924D03*
Y887270D03*
Y890617D03*
Y893963D03*
Y897310D03*
Y900656D03*
Y904003D03*
Y907349D03*
Y910696D03*
Y914042D03*
Y917389D03*
Y920735D03*
Y924081D03*
Y927428D03*
Y930774D03*
Y934121D03*
Y937467D03*
Y940814D03*
Y944160D03*
Y947507D03*
Y950853D03*
Y954200D03*
Y957546D03*
Y960892D03*
Y964239D03*
Y967585D03*
Y970932D03*
Y974278D03*
Y977625D03*
Y980971D03*
Y984318D03*
Y987664D03*
Y991011D03*
Y994357D03*
Y1017782D03*
Y1021129D03*
Y1024475D03*
Y1027822D03*
Y1031168D03*
Y1034515D03*
Y1037861D03*
Y1041207D03*
Y1044554D03*
Y1047900D03*
Y1051247D03*
Y1054593D03*
Y1057940D03*
Y1061286D03*
Y1064633D03*
Y1067979D03*
Y1071326D03*
Y1074672D03*
Y1078018D03*
Y1081365D03*
Y1084711D03*
Y1088058D03*
Y1091404D03*
Y1094751D03*
Y1098097D03*
Y1101444D03*
Y1104790D03*
Y1108137D03*
Y1111483D03*
Y1114829D03*
Y1118176D03*
Y1121522D03*
Y1124869D03*
Y1128215D03*
Y1131562D03*
Y1134908D03*
Y1138255D03*
Y1141601D03*
Y1144948D03*
Y1148294D03*
Y1151641D03*
Y1154987D03*
Y1158333D03*
Y1161680D03*
Y1165026D03*
Y1168373D03*
Y1171719D03*
Y1175066D03*
Y1178412D03*
Y1181759D03*
Y1185105D03*
Y1188452D03*
Y1191798D03*
Y1195144D03*
Y1198491D03*
Y1201837D03*
Y1205184D03*
Y1208530D03*
Y1211877D03*
Y1215223D03*
Y1218570D03*
Y1221916D03*
Y1225263D03*
Y1228609D03*
Y1231955D03*
Y1235302D03*
Y1238648D03*
Y1241995D03*
Y1245341D03*
Y1248688D03*
Y1252034D03*
Y1255381D03*
Y1258727D03*
Y1262074D03*
Y1265420D03*
X654949Y766798D03*
Y770144D03*
Y773491D03*
Y776837D03*
Y780184D03*
Y783530D03*
Y786877D03*
Y790223D03*
Y793570D03*
Y796916D03*
Y800263D03*
Y803609D03*
Y806955D03*
Y810302D03*
Y813648D03*
Y816995D03*
Y820341D03*
Y823688D03*
Y827034D03*
Y830381D03*
Y833727D03*
Y837074D03*
Y840420D03*
Y843766D03*
Y847113D03*
Y850459D03*
Y853806D03*
Y857152D03*
Y860499D03*
Y863845D03*
Y867192D03*
Y870538D03*
Y873885D03*
Y877231D03*
Y880577D03*
Y883924D03*
Y887270D03*
Y890617D03*
Y893963D03*
Y897310D03*
Y900656D03*
Y904003D03*
Y907349D03*
Y910696D03*
Y914042D03*
Y917389D03*
Y920735D03*
Y924081D03*
Y927428D03*
Y930774D03*
Y934121D03*
Y937467D03*
Y940814D03*
Y944160D03*
Y947507D03*
Y950853D03*
Y954200D03*
Y957546D03*
Y960892D03*
Y964239D03*
Y967585D03*
Y970932D03*
Y974278D03*
Y977625D03*
Y980971D03*
Y984318D03*
Y987664D03*
Y991011D03*
Y994357D03*
Y1017782D03*
Y1021129D03*
Y1024475D03*
Y1027822D03*
Y1031168D03*
Y1034515D03*
Y1037861D03*
Y1041207D03*
Y1044554D03*
Y1047900D03*
Y1051247D03*
Y1054593D03*
Y1057940D03*
Y1061286D03*
Y1064633D03*
Y1067979D03*
Y1071326D03*
Y1074672D03*
Y1078018D03*
Y1081365D03*
Y1084711D03*
Y1088058D03*
Y1091404D03*
Y1094751D03*
Y1098097D03*
Y1101444D03*
Y1104790D03*
Y1108137D03*
Y1111483D03*
Y1114829D03*
Y1118176D03*
Y1121522D03*
Y1124869D03*
Y1128215D03*
Y1131562D03*
Y1134908D03*
Y1138255D03*
Y1141601D03*
Y1144948D03*
Y1148294D03*
Y1151641D03*
Y1154987D03*
Y1158333D03*
Y1161680D03*
Y1165026D03*
Y1168373D03*
Y1171719D03*
Y1175066D03*
Y1178412D03*
Y1181759D03*
Y1185105D03*
Y1188452D03*
Y1191798D03*
Y1195144D03*
Y1198491D03*
Y1201837D03*
Y1205184D03*
Y1208530D03*
Y1211877D03*
Y1215223D03*
Y1218570D03*
Y1221916D03*
Y1225263D03*
Y1228609D03*
Y1231955D03*
Y1235302D03*
Y1238648D03*
Y1241995D03*
Y1245341D03*
Y1248688D03*
Y1252034D03*
Y1255381D03*
Y1258727D03*
Y1262074D03*
Y1265420D03*
X671091Y766798D03*
Y770144D03*
Y773491D03*
Y776837D03*
Y780184D03*
Y783530D03*
Y786877D03*
Y790223D03*
Y793570D03*
Y796916D03*
Y800263D03*
Y803609D03*
Y806955D03*
Y810302D03*
Y813648D03*
Y816995D03*
Y820341D03*
Y823688D03*
Y827034D03*
Y830381D03*
Y833727D03*
Y837074D03*
Y840420D03*
Y843766D03*
Y847113D03*
Y850459D03*
Y853806D03*
Y857152D03*
Y860499D03*
Y863845D03*
Y867192D03*
Y870538D03*
Y873885D03*
Y877231D03*
Y880577D03*
Y883924D03*
Y887270D03*
Y890617D03*
Y893963D03*
Y897310D03*
Y900656D03*
Y904003D03*
Y907349D03*
Y910696D03*
Y914042D03*
Y917389D03*
Y920735D03*
Y924081D03*
Y927428D03*
Y930774D03*
Y934121D03*
Y937467D03*
Y940814D03*
Y944160D03*
Y947507D03*
Y950853D03*
Y954200D03*
Y957546D03*
Y960892D03*
Y964239D03*
Y967585D03*
Y970932D03*
Y974278D03*
Y977625D03*
Y980971D03*
Y984318D03*
Y987664D03*
Y991011D03*
Y994357D03*
Y1017782D03*
Y1021129D03*
Y1024475D03*
Y1027822D03*
Y1031168D03*
Y1034515D03*
Y1037861D03*
Y1041207D03*
Y1044554D03*
Y1047900D03*
Y1051247D03*
Y1054593D03*
Y1057940D03*
Y1061286D03*
Y1064633D03*
Y1067979D03*
Y1071326D03*
Y1074672D03*
Y1078018D03*
Y1081365D03*
Y1084711D03*
Y1088058D03*
Y1091404D03*
Y1094751D03*
Y1098097D03*
Y1101444D03*
Y1104790D03*
Y1108137D03*
Y1111483D03*
Y1114829D03*
Y1118176D03*
Y1121522D03*
Y1124869D03*
Y1128215D03*
Y1131562D03*
Y1134908D03*
Y1138255D03*
Y1141601D03*
Y1144948D03*
Y1148294D03*
Y1151641D03*
Y1154987D03*
Y1158333D03*
Y1161680D03*
Y1165026D03*
Y1168373D03*
Y1171719D03*
Y1175066D03*
Y1178412D03*
Y1181759D03*
Y1185105D03*
Y1188452D03*
Y1191798D03*
Y1195144D03*
Y1198491D03*
Y1201837D03*
Y1205184D03*
Y1208530D03*
Y1211877D03*
Y1215223D03*
Y1218570D03*
Y1221916D03*
Y1225263D03*
Y1228609D03*
Y1231955D03*
Y1235302D03*
Y1238648D03*
Y1241995D03*
Y1245341D03*
Y1248688D03*
Y1252034D03*
Y1255381D03*
Y1258727D03*
Y1262074D03*
Y1265420D03*
X684649Y766798D03*
Y770144D03*
Y773491D03*
Y776837D03*
Y780184D03*
Y783530D03*
Y786877D03*
Y790223D03*
Y793570D03*
Y796916D03*
Y800263D03*
Y803609D03*
Y806955D03*
Y810302D03*
Y813648D03*
Y816995D03*
Y820341D03*
Y823688D03*
Y827034D03*
Y830381D03*
Y833727D03*
Y837074D03*
Y840420D03*
Y843766D03*
Y847113D03*
Y850459D03*
Y853806D03*
Y857152D03*
Y860499D03*
Y863845D03*
Y867192D03*
Y870538D03*
Y873885D03*
Y877231D03*
Y880577D03*
Y883924D03*
Y887270D03*
Y890617D03*
Y893963D03*
Y897310D03*
Y900656D03*
Y904003D03*
Y907349D03*
Y910696D03*
Y914042D03*
Y917389D03*
Y920735D03*
Y924081D03*
Y927428D03*
Y930774D03*
Y934121D03*
Y937467D03*
Y940814D03*
Y944160D03*
Y947507D03*
Y950853D03*
Y954200D03*
Y957546D03*
Y960892D03*
Y964239D03*
Y967585D03*
Y970932D03*
Y974278D03*
Y977625D03*
Y980971D03*
Y984318D03*
Y987664D03*
Y991011D03*
Y994357D03*
Y1017782D03*
Y1021129D03*
Y1024475D03*
Y1027822D03*
Y1031168D03*
Y1034515D03*
Y1037861D03*
Y1041207D03*
Y1044554D03*
Y1047900D03*
Y1051247D03*
Y1054593D03*
Y1057940D03*
Y1061286D03*
Y1064633D03*
Y1067979D03*
Y1071326D03*
Y1074672D03*
Y1078018D03*
Y1081365D03*
Y1084711D03*
Y1088058D03*
Y1091404D03*
Y1094751D03*
Y1098097D03*
Y1101444D03*
Y1104790D03*
Y1108137D03*
Y1111483D03*
Y1114829D03*
Y1118176D03*
Y1121522D03*
Y1124869D03*
Y1128215D03*
Y1131562D03*
Y1134908D03*
Y1138255D03*
Y1141601D03*
Y1144948D03*
Y1148294D03*
Y1151641D03*
Y1154987D03*
Y1158333D03*
Y1161680D03*
Y1165026D03*
Y1168373D03*
Y1171719D03*
Y1175066D03*
Y1178412D03*
Y1181759D03*
Y1185105D03*
Y1188452D03*
Y1191798D03*
Y1195144D03*
Y1198491D03*
Y1201837D03*
Y1205184D03*
Y1208530D03*
Y1211877D03*
Y1215223D03*
Y1218570D03*
Y1221916D03*
Y1225263D03*
Y1228609D03*
Y1231955D03*
Y1235302D03*
Y1238648D03*
Y1241995D03*
Y1245341D03*
Y1248688D03*
Y1252034D03*
Y1255381D03*
Y1258727D03*
Y1262074D03*
Y1265420D03*
X714349Y766798D03*
Y770144D03*
X700791Y766798D03*
Y770144D03*
X714349Y773491D03*
Y776837D03*
Y780184D03*
Y783530D03*
Y786877D03*
X700791Y773491D03*
Y776837D03*
Y780184D03*
Y783530D03*
Y786877D03*
X714349Y790223D03*
Y793570D03*
Y796916D03*
Y800263D03*
Y803609D03*
X700791Y790223D03*
Y793570D03*
Y796916D03*
Y800263D03*
Y803609D03*
X714349Y806955D03*
Y810302D03*
Y813648D03*
Y816995D03*
Y820341D03*
X700791Y806955D03*
Y810302D03*
Y813648D03*
Y816995D03*
Y820341D03*
X714349Y823688D03*
Y827034D03*
Y830381D03*
Y833727D03*
X700791Y823688D03*
Y827034D03*
Y830381D03*
Y833727D03*
X714349Y837074D03*
Y840420D03*
Y843766D03*
Y847113D03*
Y850459D03*
X700791Y837074D03*
Y840420D03*
Y843766D03*
Y847113D03*
Y850459D03*
X714349Y853806D03*
Y857152D03*
Y860499D03*
Y863845D03*
Y867192D03*
X700791Y853806D03*
Y857152D03*
Y860499D03*
Y863845D03*
Y867192D03*
X714349Y870538D03*
Y873885D03*
Y877231D03*
Y880577D03*
Y883924D03*
X700791Y870538D03*
Y873885D03*
Y877231D03*
Y880577D03*
Y883924D03*
X714349Y887270D03*
Y890617D03*
Y893963D03*
Y897310D03*
Y900656D03*
X700791Y887270D03*
Y890617D03*
Y893963D03*
Y897310D03*
Y900656D03*
X714349Y904003D03*
Y907349D03*
Y910696D03*
Y914042D03*
Y917389D03*
X700791Y904003D03*
Y907349D03*
Y910696D03*
Y914042D03*
Y917389D03*
X714349Y920735D03*
Y924081D03*
Y927428D03*
Y930774D03*
Y934121D03*
X700791Y920735D03*
Y924081D03*
Y927428D03*
Y930774D03*
Y934121D03*
X714349Y937467D03*
Y940814D03*
Y944160D03*
Y947507D03*
X700791Y937467D03*
Y940814D03*
Y944160D03*
Y947507D03*
X714349Y950853D03*
Y954200D03*
Y957546D03*
Y960892D03*
Y964239D03*
X700791Y950853D03*
Y954200D03*
Y957546D03*
Y960892D03*
Y964239D03*
X714349Y967585D03*
Y970932D03*
Y974278D03*
Y977625D03*
Y980971D03*
X700791Y967585D03*
Y970932D03*
Y974278D03*
Y977625D03*
Y980971D03*
X714349Y984318D03*
Y987664D03*
Y991011D03*
Y994357D03*
X700791Y984318D03*
Y987664D03*
Y991011D03*
Y994357D03*
X714349Y1017782D03*
Y1021129D03*
Y1024475D03*
Y1027822D03*
Y1031168D03*
X700791Y1017782D03*
Y1021129D03*
Y1024475D03*
Y1027822D03*
Y1031168D03*
X714349Y1034515D03*
Y1037861D03*
Y1041207D03*
Y1044554D03*
Y1047900D03*
X700791Y1034515D03*
Y1037861D03*
Y1041207D03*
Y1044554D03*
Y1047900D03*
X714349Y1051247D03*
Y1054593D03*
Y1057940D03*
Y1061286D03*
X700791Y1051247D03*
Y1054593D03*
Y1057940D03*
Y1061286D03*
X714349Y1064633D03*
Y1067979D03*
Y1071326D03*
Y1074672D03*
Y1078018D03*
X700791Y1064633D03*
Y1067979D03*
Y1071326D03*
Y1074672D03*
Y1078018D03*
X714349Y1081365D03*
Y1084711D03*
Y1088058D03*
Y1091404D03*
Y1094751D03*
X700791Y1081365D03*
Y1084711D03*
Y1088058D03*
Y1091404D03*
Y1094751D03*
X714349Y1098097D03*
Y1101444D03*
Y1104790D03*
Y1108137D03*
Y1111483D03*
X700791Y1098097D03*
Y1101444D03*
Y1104790D03*
Y1108137D03*
Y1111483D03*
X714349Y1114829D03*
Y1118176D03*
Y1121522D03*
Y1124869D03*
Y1128215D03*
X700791Y1114829D03*
Y1118176D03*
Y1121522D03*
Y1124869D03*
Y1128215D03*
X714349Y1131562D03*
Y1134908D03*
Y1138255D03*
Y1141601D03*
Y1144948D03*
X700791Y1131562D03*
Y1134908D03*
Y1138255D03*
Y1141601D03*
Y1144948D03*
X714349Y1148294D03*
Y1151641D03*
Y1154987D03*
Y1158333D03*
Y1161680D03*
X700791Y1148294D03*
Y1151641D03*
Y1154987D03*
Y1158333D03*
Y1161680D03*
X714349Y1165026D03*
Y1168373D03*
Y1171719D03*
Y1175066D03*
X700791Y1165026D03*
Y1168373D03*
Y1171719D03*
Y1175066D03*
X714349Y1178412D03*
Y1181759D03*
Y1185105D03*
Y1188452D03*
Y1191798D03*
X700791Y1178412D03*
Y1181759D03*
Y1185105D03*
Y1188452D03*
Y1191798D03*
X714349Y1195144D03*
Y1198491D03*
Y1201837D03*
Y1205184D03*
Y1208530D03*
X700791Y1195144D03*
Y1198491D03*
Y1201837D03*
Y1205184D03*
Y1208530D03*
X714349Y1211877D03*
Y1215223D03*
Y1218570D03*
Y1221916D03*
Y1225263D03*
X700791Y1211877D03*
Y1215223D03*
Y1218570D03*
Y1221916D03*
Y1225263D03*
X714349Y1228609D03*
Y1231955D03*
Y1235302D03*
Y1238648D03*
Y1241995D03*
X700791Y1228609D03*
Y1231955D03*
Y1235302D03*
Y1238648D03*
Y1241995D03*
X714349Y1245341D03*
Y1248688D03*
Y1252034D03*
Y1255381D03*
Y1258727D03*
X700791Y1245341D03*
Y1248688D03*
Y1252034D03*
Y1255381D03*
Y1258727D03*
X714349Y1262074D03*
Y1265420D03*
X700791Y1262074D03*
Y1265420D03*
X730491Y766798D03*
Y770144D03*
Y773491D03*
Y776837D03*
Y780184D03*
Y783530D03*
Y786877D03*
Y790223D03*
Y793570D03*
Y796916D03*
Y800263D03*
Y803609D03*
Y806955D03*
Y810302D03*
Y813648D03*
Y816995D03*
Y820341D03*
Y823688D03*
Y827034D03*
Y830381D03*
Y833727D03*
Y837074D03*
Y840420D03*
Y843766D03*
Y847113D03*
Y850459D03*
Y853806D03*
Y857152D03*
Y860499D03*
Y863845D03*
Y867192D03*
Y870538D03*
Y873885D03*
Y877231D03*
Y880577D03*
Y883924D03*
Y887270D03*
Y890617D03*
Y893963D03*
Y897310D03*
Y900656D03*
Y904003D03*
Y907349D03*
Y910696D03*
Y914042D03*
Y917389D03*
Y920735D03*
Y924081D03*
Y927428D03*
Y930774D03*
Y934121D03*
Y937467D03*
Y940814D03*
Y944160D03*
Y947507D03*
Y950853D03*
Y954200D03*
Y957546D03*
Y960892D03*
Y964239D03*
Y967585D03*
Y970932D03*
Y974278D03*
Y977625D03*
Y980971D03*
Y984318D03*
Y987664D03*
Y991011D03*
Y994357D03*
Y1017782D03*
Y1021129D03*
Y1024475D03*
Y1027822D03*
Y1031168D03*
Y1034515D03*
Y1037861D03*
Y1041207D03*
Y1044554D03*
Y1047900D03*
Y1051247D03*
Y1054593D03*
Y1057940D03*
Y1061286D03*
Y1064633D03*
Y1067979D03*
Y1071326D03*
Y1074672D03*
Y1078018D03*
Y1081365D03*
Y1084711D03*
Y1088058D03*
Y1091404D03*
Y1094751D03*
Y1098097D03*
Y1101444D03*
Y1104790D03*
Y1108137D03*
Y1111483D03*
Y1114829D03*
Y1118176D03*
Y1121522D03*
Y1124869D03*
Y1128215D03*
Y1131562D03*
Y1134908D03*
Y1138255D03*
Y1141601D03*
Y1144948D03*
Y1148294D03*
Y1151641D03*
Y1154987D03*
Y1158333D03*
Y1161680D03*
Y1165026D03*
Y1168373D03*
Y1171719D03*
Y1175066D03*
Y1178412D03*
Y1181759D03*
Y1185105D03*
Y1188452D03*
Y1191798D03*
Y1195144D03*
Y1198491D03*
Y1201837D03*
Y1205184D03*
Y1208530D03*
Y1211877D03*
Y1215223D03*
Y1218570D03*
Y1221916D03*
Y1225263D03*
Y1228609D03*
Y1231955D03*
Y1235302D03*
Y1238648D03*
Y1241995D03*
Y1245341D03*
Y1248688D03*
Y1252034D03*
Y1255381D03*
Y1258727D03*
Y1262074D03*
Y1265420D03*
X744049Y766798D03*
Y770144D03*
Y773491D03*
Y776837D03*
Y780184D03*
Y783530D03*
Y786877D03*
Y790223D03*
Y793570D03*
Y796916D03*
Y800263D03*
Y803609D03*
Y806955D03*
Y810302D03*
Y813648D03*
Y816995D03*
Y820341D03*
Y823688D03*
Y827034D03*
Y830381D03*
Y833727D03*
Y837074D03*
Y840420D03*
Y843766D03*
Y847113D03*
Y850459D03*
Y853806D03*
Y857152D03*
Y860499D03*
Y863845D03*
Y867192D03*
Y870538D03*
Y873885D03*
Y877231D03*
Y880577D03*
Y883924D03*
Y887270D03*
Y890617D03*
Y893963D03*
Y897310D03*
Y900656D03*
Y904003D03*
Y907349D03*
Y910696D03*
Y914042D03*
Y917389D03*
Y920735D03*
Y924081D03*
Y927428D03*
Y930774D03*
Y934121D03*
Y937467D03*
Y940814D03*
Y944160D03*
Y947507D03*
Y950853D03*
Y954200D03*
Y957546D03*
Y960892D03*
Y964239D03*
Y967585D03*
Y970932D03*
Y974278D03*
Y977625D03*
Y980971D03*
Y984318D03*
Y987664D03*
Y991011D03*
Y994357D03*
Y1017782D03*
Y1021129D03*
Y1024475D03*
Y1027822D03*
Y1031168D03*
Y1034515D03*
Y1037861D03*
Y1041207D03*
Y1044554D03*
Y1047900D03*
Y1051247D03*
Y1054593D03*
Y1057940D03*
Y1061286D03*
Y1064633D03*
Y1067979D03*
Y1071326D03*
Y1074672D03*
Y1078018D03*
Y1081365D03*
Y1084711D03*
Y1088058D03*
Y1091404D03*
Y1094751D03*
Y1098097D03*
Y1101444D03*
Y1104790D03*
Y1108137D03*
Y1111483D03*
Y1114829D03*
Y1118176D03*
Y1121522D03*
Y1124869D03*
Y1128215D03*
Y1131562D03*
Y1134908D03*
Y1138255D03*
Y1141601D03*
Y1144948D03*
Y1148294D03*
Y1151641D03*
Y1154987D03*
Y1158333D03*
Y1161680D03*
Y1165026D03*
Y1168373D03*
Y1171719D03*
Y1175066D03*
Y1178412D03*
Y1181759D03*
Y1185105D03*
Y1188452D03*
Y1191798D03*
Y1195144D03*
Y1198491D03*
Y1201837D03*
Y1205184D03*
Y1208530D03*
Y1211877D03*
Y1215223D03*
Y1218570D03*
Y1221916D03*
Y1225263D03*
Y1228609D03*
Y1231955D03*
Y1235302D03*
Y1238648D03*
Y1241995D03*
Y1245341D03*
Y1248688D03*
Y1252034D03*
Y1255381D03*
Y1258727D03*
Y1262074D03*
Y1265420D03*
X760191Y766798D03*
Y770144D03*
Y773491D03*
Y776837D03*
Y780184D03*
Y783530D03*
Y786877D03*
Y790223D03*
Y793570D03*
Y796916D03*
Y800263D03*
Y803609D03*
Y806955D03*
Y810302D03*
Y813648D03*
Y816995D03*
Y820341D03*
Y823688D03*
Y827034D03*
Y830381D03*
Y833727D03*
Y837074D03*
Y840420D03*
Y843766D03*
Y847113D03*
Y850459D03*
Y853806D03*
Y857152D03*
Y860499D03*
Y863845D03*
Y867192D03*
Y870538D03*
Y873885D03*
Y877231D03*
Y880577D03*
Y883924D03*
Y887270D03*
Y890617D03*
Y893963D03*
Y897310D03*
Y900656D03*
Y904003D03*
Y907349D03*
Y910696D03*
Y914042D03*
Y917389D03*
Y920735D03*
Y924081D03*
Y927428D03*
Y930774D03*
Y934121D03*
Y937467D03*
Y940814D03*
Y944160D03*
Y947507D03*
Y950853D03*
Y954200D03*
Y957546D03*
Y960892D03*
Y964239D03*
Y967585D03*
Y970932D03*
Y974278D03*
Y977625D03*
Y980971D03*
Y984318D03*
Y987664D03*
Y991011D03*
Y994357D03*
Y1017782D03*
Y1021129D03*
Y1024475D03*
Y1027822D03*
Y1031168D03*
Y1034515D03*
Y1037861D03*
Y1041207D03*
Y1044554D03*
Y1047900D03*
Y1051247D03*
Y1054593D03*
Y1057940D03*
Y1061286D03*
Y1064633D03*
Y1067979D03*
Y1071326D03*
Y1074672D03*
Y1078018D03*
Y1081365D03*
Y1084711D03*
Y1088058D03*
Y1091404D03*
Y1094751D03*
Y1098097D03*
Y1101444D03*
Y1104790D03*
Y1108137D03*
Y1111483D03*
Y1114829D03*
Y1118176D03*
Y1121522D03*
Y1124869D03*
Y1128215D03*
Y1131562D03*
Y1134908D03*
Y1138255D03*
Y1141601D03*
Y1144948D03*
Y1148294D03*
Y1151641D03*
Y1154987D03*
Y1158333D03*
Y1161680D03*
Y1165026D03*
Y1168373D03*
Y1171719D03*
Y1175066D03*
Y1178412D03*
Y1181759D03*
Y1185105D03*
Y1188452D03*
Y1191798D03*
Y1195144D03*
Y1198491D03*
Y1201837D03*
Y1205184D03*
Y1208530D03*
Y1211877D03*
Y1215223D03*
Y1218570D03*
Y1221916D03*
Y1225263D03*
Y1228609D03*
Y1231955D03*
Y1235302D03*
Y1238648D03*
Y1241995D03*
Y1245341D03*
Y1248688D03*
Y1252034D03*
Y1255381D03*
Y1258727D03*
Y1262074D03*
Y1265420D03*
X773749Y766798D03*
Y770144D03*
Y773491D03*
Y776837D03*
Y780184D03*
Y783530D03*
Y786877D03*
Y790223D03*
Y793570D03*
Y796916D03*
Y800263D03*
Y803609D03*
Y806955D03*
Y810302D03*
Y813648D03*
Y816995D03*
Y820341D03*
Y823688D03*
Y827034D03*
Y830381D03*
Y833727D03*
Y837074D03*
Y840420D03*
Y843766D03*
Y847113D03*
Y850459D03*
Y853806D03*
Y857152D03*
Y860499D03*
Y863845D03*
Y867192D03*
Y870538D03*
Y873885D03*
Y877231D03*
Y880577D03*
Y883924D03*
Y887270D03*
Y890617D03*
Y893963D03*
Y897310D03*
Y900656D03*
Y904003D03*
Y907349D03*
Y910696D03*
Y914042D03*
Y917389D03*
Y920735D03*
Y924081D03*
Y927428D03*
Y930774D03*
Y934121D03*
Y937467D03*
Y940814D03*
Y944160D03*
Y947507D03*
Y950853D03*
Y954200D03*
Y957546D03*
Y960892D03*
Y964239D03*
Y967585D03*
Y970932D03*
Y974278D03*
Y977625D03*
Y980971D03*
Y984318D03*
Y987664D03*
Y991011D03*
Y994357D03*
Y1017782D03*
Y1021129D03*
Y1024475D03*
Y1027822D03*
Y1031168D03*
Y1034515D03*
Y1037861D03*
Y1041207D03*
Y1044554D03*
Y1047900D03*
Y1051247D03*
Y1054593D03*
Y1057940D03*
Y1061286D03*
Y1064633D03*
Y1067979D03*
Y1071326D03*
Y1074672D03*
Y1078018D03*
Y1081365D03*
Y1084711D03*
Y1088058D03*
Y1091404D03*
Y1094751D03*
Y1098097D03*
Y1101444D03*
Y1104790D03*
Y1108137D03*
Y1111483D03*
Y1114829D03*
Y1118176D03*
Y1121522D03*
Y1124869D03*
Y1128215D03*
Y1131562D03*
Y1134908D03*
Y1138255D03*
Y1141601D03*
Y1144948D03*
Y1148294D03*
Y1151641D03*
Y1154987D03*
Y1158333D03*
Y1161680D03*
Y1165026D03*
Y1168373D03*
Y1171719D03*
Y1175066D03*
Y1178412D03*
Y1181759D03*
Y1185105D03*
Y1188452D03*
Y1191798D03*
Y1195144D03*
Y1198491D03*
Y1201837D03*
Y1205184D03*
Y1208530D03*
Y1211877D03*
Y1215223D03*
Y1218570D03*
Y1221916D03*
Y1225263D03*
Y1228609D03*
Y1231955D03*
Y1235302D03*
Y1238648D03*
Y1241995D03*
Y1245341D03*
Y1248688D03*
Y1252034D03*
Y1255381D03*
Y1258727D03*
Y1262074D03*
Y1265420D03*
X789891Y766798D03*
Y770144D03*
Y773491D03*
Y776837D03*
Y780184D03*
Y783530D03*
Y786877D03*
Y790223D03*
Y793570D03*
Y796916D03*
Y800263D03*
Y803609D03*
Y806955D03*
Y810302D03*
Y813648D03*
Y816995D03*
Y820341D03*
Y823688D03*
Y827034D03*
Y830381D03*
Y833727D03*
Y837074D03*
Y840420D03*
Y843766D03*
Y847113D03*
Y850459D03*
Y853806D03*
Y857152D03*
Y860499D03*
Y863845D03*
Y867192D03*
Y870538D03*
Y873885D03*
Y877231D03*
Y880577D03*
Y883924D03*
Y887270D03*
Y890617D03*
Y893963D03*
Y897310D03*
Y900656D03*
Y904003D03*
Y907349D03*
Y910696D03*
Y914042D03*
Y917389D03*
Y920735D03*
Y924081D03*
Y927428D03*
Y930774D03*
Y934121D03*
Y937467D03*
Y940814D03*
Y944160D03*
Y947507D03*
Y950853D03*
Y954200D03*
Y957546D03*
Y960892D03*
Y964239D03*
Y967585D03*
Y970932D03*
Y974278D03*
Y977625D03*
Y980971D03*
Y984318D03*
Y987664D03*
Y991011D03*
Y994357D03*
Y1017782D03*
Y1021129D03*
Y1024475D03*
Y1027822D03*
Y1031168D03*
Y1034515D03*
Y1037861D03*
Y1041207D03*
Y1044554D03*
Y1047900D03*
Y1051247D03*
Y1054593D03*
Y1057940D03*
Y1061286D03*
Y1064633D03*
Y1067979D03*
Y1071326D03*
Y1074672D03*
Y1078018D03*
Y1081365D03*
Y1084711D03*
Y1088058D03*
Y1091404D03*
Y1094751D03*
Y1098097D03*
Y1101444D03*
Y1104790D03*
Y1108137D03*
Y1111483D03*
Y1114829D03*
Y1118176D03*
Y1121522D03*
Y1124869D03*
Y1128215D03*
Y1131562D03*
Y1134908D03*
Y1138255D03*
Y1141601D03*
Y1144948D03*
Y1148294D03*
Y1151641D03*
Y1154987D03*
Y1158333D03*
Y1161680D03*
Y1165026D03*
Y1168373D03*
Y1171719D03*
Y1175066D03*
Y1178412D03*
Y1181759D03*
Y1185105D03*
Y1188452D03*
Y1191798D03*
Y1195144D03*
Y1198491D03*
Y1201837D03*
Y1205184D03*
Y1208530D03*
Y1211877D03*
Y1215223D03*
Y1218570D03*
Y1221916D03*
Y1225263D03*
Y1228609D03*
Y1231955D03*
Y1235302D03*
Y1238648D03*
Y1241995D03*
Y1245341D03*
Y1248688D03*
Y1252034D03*
Y1255381D03*
Y1258727D03*
Y1262074D03*
Y1265420D03*
X803449Y766798D03*
Y770144D03*
Y773491D03*
Y776837D03*
Y780184D03*
Y783530D03*
Y786877D03*
Y790223D03*
Y793570D03*
Y796916D03*
Y800263D03*
Y803609D03*
Y806955D03*
Y810302D03*
Y813648D03*
Y816995D03*
Y820341D03*
Y823688D03*
Y827034D03*
Y830381D03*
Y833727D03*
Y837074D03*
Y840420D03*
Y843766D03*
Y847113D03*
Y850459D03*
Y853806D03*
Y857152D03*
Y860499D03*
Y863845D03*
Y867192D03*
Y870538D03*
Y873885D03*
Y877231D03*
Y880577D03*
Y883924D03*
Y887270D03*
Y890617D03*
Y893963D03*
Y897310D03*
Y900656D03*
Y904003D03*
Y907349D03*
Y910696D03*
Y914042D03*
Y917389D03*
Y920735D03*
Y924081D03*
Y927428D03*
Y930774D03*
Y934121D03*
Y937467D03*
Y940814D03*
Y944160D03*
Y947507D03*
Y950853D03*
Y954200D03*
Y957546D03*
Y960892D03*
Y964239D03*
Y967585D03*
Y970932D03*
Y974278D03*
Y977625D03*
Y980971D03*
Y984318D03*
Y987664D03*
Y991011D03*
Y994357D03*
Y1017782D03*
Y1021129D03*
Y1024475D03*
Y1027822D03*
Y1031168D03*
Y1034515D03*
Y1037861D03*
Y1041207D03*
Y1044554D03*
Y1047900D03*
Y1051247D03*
Y1054593D03*
Y1057940D03*
Y1061286D03*
Y1064633D03*
Y1067979D03*
Y1071326D03*
Y1074672D03*
Y1078018D03*
Y1081365D03*
Y1084711D03*
Y1088058D03*
Y1091404D03*
Y1094751D03*
Y1098097D03*
Y1101444D03*
Y1104790D03*
Y1108137D03*
Y1111483D03*
Y1114829D03*
Y1118176D03*
Y1121522D03*
Y1124869D03*
Y1128215D03*
Y1131562D03*
Y1134908D03*
Y1138255D03*
Y1141601D03*
Y1144948D03*
Y1148294D03*
Y1151641D03*
Y1154987D03*
Y1158333D03*
Y1161680D03*
Y1165026D03*
Y1168373D03*
Y1171719D03*
Y1175066D03*
Y1178412D03*
Y1181759D03*
Y1185105D03*
Y1188452D03*
Y1191798D03*
Y1195144D03*
Y1198491D03*
Y1201837D03*
Y1205184D03*
Y1208530D03*
Y1211877D03*
Y1215223D03*
Y1218570D03*
Y1221916D03*
Y1225263D03*
Y1228609D03*
Y1231955D03*
Y1235302D03*
Y1238648D03*
Y1241995D03*
Y1245341D03*
Y1248688D03*
Y1252034D03*
Y1255381D03*
Y1258727D03*
Y1262074D03*
Y1265420D03*
X819591Y766798D03*
Y770144D03*
Y773491D03*
Y776837D03*
Y780184D03*
Y783530D03*
Y786877D03*
Y790223D03*
Y793570D03*
Y796916D03*
Y800263D03*
Y803609D03*
Y806955D03*
Y810302D03*
Y813648D03*
Y816995D03*
Y820341D03*
Y823688D03*
Y827034D03*
Y830381D03*
Y833727D03*
Y837074D03*
Y840420D03*
Y843766D03*
Y847113D03*
Y850459D03*
Y853806D03*
Y857152D03*
Y860499D03*
Y863845D03*
Y867192D03*
Y870538D03*
Y873885D03*
Y877231D03*
Y880577D03*
Y883924D03*
Y887270D03*
Y890617D03*
Y893963D03*
Y897310D03*
Y900656D03*
Y904003D03*
Y907349D03*
Y910696D03*
Y914042D03*
Y917389D03*
Y920735D03*
Y924081D03*
Y927428D03*
Y930774D03*
Y934121D03*
Y937467D03*
Y940814D03*
Y944160D03*
Y947507D03*
Y950853D03*
Y954200D03*
Y957546D03*
Y960892D03*
Y964239D03*
Y967585D03*
Y970932D03*
Y974278D03*
Y977625D03*
Y980971D03*
Y984318D03*
Y987664D03*
Y991011D03*
Y994357D03*
Y1017782D03*
Y1021129D03*
Y1024475D03*
Y1027822D03*
Y1031168D03*
Y1034515D03*
Y1037861D03*
Y1041207D03*
Y1044554D03*
Y1047900D03*
Y1051247D03*
Y1054593D03*
Y1057940D03*
Y1061286D03*
Y1064633D03*
Y1067979D03*
Y1071326D03*
Y1074672D03*
Y1078018D03*
Y1081365D03*
Y1084711D03*
Y1088058D03*
Y1091404D03*
Y1094751D03*
Y1098097D03*
Y1101444D03*
Y1104790D03*
Y1108137D03*
Y1111483D03*
Y1114829D03*
Y1118176D03*
Y1121522D03*
Y1124869D03*
Y1128215D03*
Y1131562D03*
Y1134908D03*
Y1138255D03*
Y1141601D03*
Y1144948D03*
Y1148294D03*
Y1151641D03*
Y1154987D03*
Y1158333D03*
Y1161680D03*
Y1165026D03*
Y1168373D03*
Y1171719D03*
Y1175066D03*
Y1178412D03*
Y1181759D03*
Y1185105D03*
Y1188452D03*
Y1191798D03*
Y1195144D03*
Y1198491D03*
Y1201837D03*
Y1205184D03*
Y1208530D03*
Y1211877D03*
Y1215223D03*
Y1218570D03*
Y1221916D03*
Y1225263D03*
Y1228609D03*
Y1231955D03*
Y1235302D03*
Y1238648D03*
Y1241995D03*
Y1245341D03*
Y1248688D03*
Y1252034D03*
Y1255381D03*
Y1258727D03*
Y1262074D03*
Y1265420D03*
X833149Y766798D03*
Y770144D03*
Y773491D03*
Y776837D03*
Y780184D03*
Y783530D03*
Y786877D03*
Y790223D03*
Y793570D03*
Y796916D03*
Y800263D03*
Y803609D03*
Y806955D03*
Y810302D03*
Y813648D03*
Y816995D03*
Y820341D03*
Y823688D03*
Y827034D03*
Y830381D03*
Y833727D03*
Y837074D03*
Y840420D03*
Y843766D03*
Y847113D03*
Y850459D03*
Y853806D03*
Y857152D03*
Y860499D03*
Y863845D03*
Y867192D03*
Y870538D03*
Y873885D03*
Y877231D03*
Y880577D03*
Y883924D03*
Y887270D03*
Y890617D03*
Y893963D03*
Y897310D03*
Y900656D03*
Y904003D03*
Y907349D03*
Y910696D03*
Y914042D03*
Y917389D03*
Y920735D03*
Y924081D03*
Y927428D03*
Y930774D03*
Y934121D03*
Y937467D03*
Y940814D03*
Y944160D03*
Y947507D03*
Y950853D03*
Y954200D03*
Y957546D03*
Y960892D03*
Y964239D03*
Y967585D03*
Y970932D03*
Y974278D03*
Y977625D03*
Y980971D03*
Y984318D03*
Y987664D03*
Y991011D03*
Y994357D03*
Y1017782D03*
Y1021129D03*
Y1024475D03*
Y1027822D03*
Y1031168D03*
Y1034515D03*
Y1037861D03*
Y1041207D03*
Y1044554D03*
Y1047900D03*
Y1051247D03*
Y1054593D03*
Y1057940D03*
Y1061286D03*
Y1064633D03*
Y1067979D03*
Y1071326D03*
Y1074672D03*
Y1078018D03*
Y1081365D03*
Y1084711D03*
Y1088058D03*
Y1091404D03*
Y1094751D03*
Y1098097D03*
Y1101444D03*
Y1104790D03*
Y1108137D03*
Y1111483D03*
Y1114829D03*
Y1118176D03*
Y1121522D03*
Y1124869D03*
Y1128215D03*
Y1131562D03*
Y1134908D03*
Y1138255D03*
Y1141601D03*
Y1144948D03*
Y1148294D03*
Y1151641D03*
Y1154987D03*
Y1158333D03*
Y1161680D03*
Y1165026D03*
Y1168373D03*
Y1171719D03*
Y1175066D03*
Y1178412D03*
Y1181759D03*
Y1185105D03*
Y1188452D03*
Y1191798D03*
Y1195144D03*
Y1198491D03*
Y1201837D03*
Y1205184D03*
Y1208530D03*
Y1211877D03*
Y1215223D03*
Y1218570D03*
Y1221916D03*
Y1225263D03*
Y1228609D03*
Y1231955D03*
Y1235302D03*
Y1238648D03*
Y1241995D03*
Y1245341D03*
Y1248688D03*
Y1252034D03*
Y1255381D03*
Y1258727D03*
Y1262074D03*
Y1265420D03*
X849291Y766798D03*
Y770144D03*
Y773491D03*
Y776837D03*
Y780184D03*
Y783530D03*
Y786877D03*
Y790223D03*
Y793570D03*
Y796916D03*
Y800263D03*
Y803609D03*
Y806955D03*
Y810302D03*
Y813648D03*
Y816995D03*
Y820341D03*
Y823688D03*
Y827034D03*
Y830381D03*
Y833727D03*
Y837074D03*
Y840420D03*
Y843766D03*
Y847113D03*
Y850459D03*
Y853806D03*
Y857152D03*
Y860499D03*
Y863845D03*
Y867192D03*
Y870538D03*
Y873885D03*
Y877231D03*
Y880577D03*
Y883924D03*
Y887270D03*
Y890617D03*
Y893963D03*
Y897310D03*
Y900656D03*
Y904003D03*
Y907349D03*
Y910696D03*
Y914042D03*
Y917389D03*
Y920735D03*
Y924081D03*
Y927428D03*
Y930774D03*
Y934121D03*
Y937467D03*
Y940814D03*
Y944160D03*
Y947507D03*
Y950853D03*
Y954200D03*
Y957546D03*
Y960892D03*
Y964239D03*
Y967585D03*
Y970932D03*
Y974278D03*
Y977625D03*
Y980971D03*
Y984318D03*
Y987664D03*
Y991011D03*
Y994357D03*
Y1017782D03*
Y1021129D03*
Y1024475D03*
Y1027822D03*
Y1031168D03*
Y1034515D03*
Y1037861D03*
Y1041207D03*
Y1044554D03*
Y1047900D03*
Y1051247D03*
Y1054593D03*
Y1057940D03*
Y1061286D03*
Y1064633D03*
Y1067979D03*
Y1071326D03*
Y1074672D03*
Y1078018D03*
Y1081365D03*
Y1084711D03*
Y1088058D03*
Y1091404D03*
Y1094751D03*
Y1098097D03*
Y1101444D03*
Y1104790D03*
Y1108137D03*
Y1111483D03*
Y1114829D03*
Y1118176D03*
Y1121522D03*
Y1124869D03*
Y1128215D03*
Y1131562D03*
Y1134908D03*
Y1138255D03*
Y1141601D03*
Y1144948D03*
Y1148294D03*
Y1151641D03*
Y1154987D03*
Y1158333D03*
Y1161680D03*
Y1165026D03*
Y1168373D03*
Y1171719D03*
Y1175066D03*
Y1178412D03*
Y1181759D03*
Y1185105D03*
Y1188452D03*
Y1191798D03*
Y1195144D03*
Y1198491D03*
Y1201837D03*
Y1205184D03*
Y1208530D03*
Y1211877D03*
Y1215223D03*
Y1218570D03*
Y1221916D03*
Y1225263D03*
Y1228609D03*
Y1231955D03*
Y1235302D03*
Y1238648D03*
Y1241995D03*
Y1245341D03*
Y1248688D03*
Y1252034D03*
Y1255381D03*
Y1258727D03*
Y1262074D03*
Y1265420D03*
X1008191Y766798D03*
Y770144D03*
Y773491D03*
Y776837D03*
Y780184D03*
Y783530D03*
Y786877D03*
Y790223D03*
Y793570D03*
Y796916D03*
Y800263D03*
Y803609D03*
Y806955D03*
Y810302D03*
Y813648D03*
Y816995D03*
Y820341D03*
Y823688D03*
Y827034D03*
Y830381D03*
Y833727D03*
Y837074D03*
Y840420D03*
Y843766D03*
Y847113D03*
Y850459D03*
Y853806D03*
Y857152D03*
Y860499D03*
Y863845D03*
Y867192D03*
Y870538D03*
Y873885D03*
Y877231D03*
Y880577D03*
Y883924D03*
Y887270D03*
Y890617D03*
Y893963D03*
Y897310D03*
Y900656D03*
Y904003D03*
Y907349D03*
Y910696D03*
Y914042D03*
Y917389D03*
Y920735D03*
Y924081D03*
Y927428D03*
Y930774D03*
Y934121D03*
Y937467D03*
Y940814D03*
Y944160D03*
Y947507D03*
Y950853D03*
Y954200D03*
Y957546D03*
Y960892D03*
Y964239D03*
Y967585D03*
Y970932D03*
Y974278D03*
Y977625D03*
Y980971D03*
Y984318D03*
Y987664D03*
Y991011D03*
Y994357D03*
Y1017782D03*
Y1021129D03*
Y1024475D03*
Y1027822D03*
Y1031168D03*
Y1034515D03*
Y1037861D03*
Y1041207D03*
Y1044554D03*
Y1047900D03*
Y1051247D03*
Y1054593D03*
Y1057940D03*
Y1061286D03*
Y1064633D03*
Y1067979D03*
Y1071326D03*
Y1074672D03*
Y1078018D03*
Y1081365D03*
Y1084711D03*
Y1088058D03*
Y1091404D03*
Y1094751D03*
Y1098097D03*
Y1101444D03*
Y1104790D03*
Y1108137D03*
Y1111483D03*
Y1114829D03*
Y1118176D03*
Y1121522D03*
Y1124869D03*
Y1128215D03*
Y1131562D03*
Y1134908D03*
Y1138255D03*
Y1141601D03*
Y1144948D03*
Y1148294D03*
Y1151641D03*
Y1154987D03*
Y1158333D03*
Y1161680D03*
Y1165026D03*
Y1168373D03*
Y1171719D03*
Y1175066D03*
Y1178412D03*
Y1181759D03*
Y1185105D03*
Y1188452D03*
Y1191798D03*
Y1195144D03*
Y1198491D03*
Y1201837D03*
Y1205184D03*
Y1208530D03*
Y1211877D03*
Y1215223D03*
Y1218570D03*
Y1221916D03*
Y1225263D03*
Y1228609D03*
Y1231955D03*
Y1235302D03*
Y1238648D03*
Y1241995D03*
Y1245341D03*
Y1248688D03*
Y1252034D03*
Y1255381D03*
Y1258727D03*
Y1262074D03*
Y1265420D03*
X1037891Y766798D03*
Y770144D03*
X1024333Y766798D03*
Y770144D03*
X1037891Y773491D03*
Y776837D03*
Y780184D03*
Y783530D03*
Y786877D03*
X1024333Y773491D03*
Y776837D03*
Y780184D03*
Y783530D03*
Y786877D03*
X1037891Y790223D03*
Y793570D03*
Y796916D03*
Y800263D03*
Y803609D03*
X1024333Y790223D03*
Y793570D03*
Y796916D03*
Y800263D03*
Y803609D03*
X1037891Y806955D03*
Y810302D03*
Y813648D03*
Y816995D03*
Y820341D03*
X1024333Y806955D03*
Y810302D03*
Y813648D03*
Y816995D03*
Y820341D03*
X1037891Y823688D03*
Y827034D03*
Y830381D03*
Y833727D03*
X1024333Y823688D03*
Y827034D03*
Y830381D03*
Y833727D03*
X1037891Y837074D03*
Y840420D03*
Y843766D03*
Y847113D03*
Y850459D03*
X1024333Y837074D03*
Y840420D03*
Y843766D03*
Y847113D03*
Y850459D03*
X1037891Y853806D03*
Y857152D03*
Y860499D03*
Y863845D03*
Y867192D03*
X1024333Y853806D03*
Y857152D03*
Y860499D03*
Y863845D03*
Y867192D03*
X1037891Y870538D03*
Y873885D03*
Y877231D03*
Y880577D03*
Y883924D03*
X1024333Y870538D03*
Y873885D03*
Y877231D03*
Y880577D03*
Y883924D03*
X1037891Y887270D03*
Y890617D03*
Y893963D03*
Y897310D03*
Y900656D03*
X1024333Y887270D03*
Y890617D03*
Y893963D03*
Y897310D03*
Y900656D03*
X1037891Y904003D03*
Y907349D03*
Y910696D03*
Y914042D03*
Y917389D03*
X1024333Y904003D03*
Y907349D03*
Y910696D03*
Y914042D03*
Y917389D03*
X1037891Y920735D03*
Y924081D03*
Y927428D03*
Y930774D03*
Y934121D03*
X1024333Y920735D03*
Y924081D03*
Y927428D03*
Y930774D03*
Y934121D03*
X1037891Y937467D03*
Y940814D03*
Y944160D03*
Y947507D03*
X1024333Y937467D03*
Y940814D03*
Y944160D03*
Y947507D03*
X1037891Y950853D03*
Y954200D03*
Y957546D03*
Y960892D03*
Y964239D03*
X1024333Y950853D03*
Y954200D03*
Y957546D03*
Y960892D03*
Y964239D03*
X1037891Y967585D03*
Y970932D03*
Y974278D03*
Y977625D03*
Y980971D03*
X1024333Y967585D03*
Y970932D03*
Y974278D03*
Y977625D03*
Y980971D03*
X1037891Y984318D03*
Y987664D03*
Y991011D03*
Y994357D03*
X1024333Y984318D03*
Y987664D03*
Y991011D03*
Y994357D03*
X1037891Y1017782D03*
Y1021129D03*
Y1024475D03*
Y1027822D03*
Y1031168D03*
X1024333Y1017782D03*
Y1021129D03*
Y1024475D03*
Y1027822D03*
Y1031168D03*
X1037891Y1034515D03*
Y1037861D03*
Y1041207D03*
Y1044554D03*
Y1047900D03*
X1024333Y1034515D03*
Y1037861D03*
Y1041207D03*
Y1044554D03*
Y1047900D03*
X1037891Y1051247D03*
Y1054593D03*
Y1057940D03*
Y1061286D03*
X1024333Y1051247D03*
Y1054593D03*
Y1057940D03*
Y1061286D03*
X1037891Y1064633D03*
Y1067979D03*
Y1071326D03*
Y1074672D03*
Y1078018D03*
X1024333Y1064633D03*
Y1067979D03*
Y1071326D03*
Y1074672D03*
Y1078018D03*
X1037891Y1081365D03*
Y1084711D03*
Y1088058D03*
Y1091404D03*
Y1094751D03*
X1024333Y1081365D03*
Y1084711D03*
Y1088058D03*
Y1091404D03*
Y1094751D03*
X1037891Y1098097D03*
Y1101444D03*
Y1104790D03*
Y1108137D03*
Y1111483D03*
X1024333Y1098097D03*
Y1101444D03*
Y1104790D03*
Y1108137D03*
Y1111483D03*
X1037891Y1114829D03*
Y1118176D03*
Y1121522D03*
Y1124869D03*
Y1128215D03*
X1024333Y1114829D03*
Y1118176D03*
Y1121522D03*
Y1124869D03*
Y1128215D03*
X1037891Y1131562D03*
Y1134908D03*
Y1138255D03*
Y1141601D03*
Y1144948D03*
X1024333Y1131562D03*
Y1134908D03*
Y1138255D03*
Y1141601D03*
Y1144948D03*
X1037891Y1148294D03*
Y1151641D03*
Y1154987D03*
Y1158333D03*
Y1161680D03*
X1024333Y1148294D03*
Y1151641D03*
Y1154987D03*
Y1158333D03*
Y1161680D03*
X1037891Y1165026D03*
Y1168373D03*
Y1171719D03*
Y1175066D03*
X1024333Y1165026D03*
Y1168373D03*
Y1171719D03*
Y1175066D03*
X1037891Y1178412D03*
Y1181759D03*
Y1185105D03*
Y1188452D03*
Y1191798D03*
X1024333Y1178412D03*
Y1181759D03*
Y1185105D03*
Y1188452D03*
Y1191798D03*
X1037891Y1195144D03*
Y1198491D03*
Y1201837D03*
Y1205184D03*
Y1208530D03*
X1024333Y1195144D03*
Y1198491D03*
Y1201837D03*
Y1205184D03*
Y1208530D03*
X1037891Y1211877D03*
Y1215223D03*
Y1218570D03*
Y1221916D03*
Y1225263D03*
X1024333Y1211877D03*
Y1215223D03*
Y1218570D03*
Y1221916D03*
Y1225263D03*
X1037891Y1228609D03*
Y1231955D03*
Y1235302D03*
Y1238648D03*
Y1241995D03*
X1024333Y1228609D03*
Y1231955D03*
Y1235302D03*
Y1238648D03*
Y1241995D03*
X1037891Y1245341D03*
Y1248688D03*
Y1252034D03*
Y1255381D03*
Y1258727D03*
X1024333Y1245341D03*
Y1248688D03*
Y1252034D03*
Y1255381D03*
Y1258727D03*
X1037891Y1262074D03*
Y1265420D03*
X1024333Y1262074D03*
Y1265420D03*
X1054033Y766798D03*
Y770144D03*
Y773491D03*
Y776837D03*
Y780184D03*
Y783530D03*
Y786877D03*
Y790223D03*
Y793570D03*
Y796916D03*
Y800263D03*
Y803609D03*
Y806955D03*
Y810302D03*
Y813648D03*
Y816995D03*
Y820341D03*
Y823688D03*
Y827034D03*
Y830381D03*
Y833727D03*
Y837074D03*
Y840420D03*
Y843766D03*
Y847113D03*
Y850459D03*
Y853806D03*
Y857152D03*
Y860499D03*
Y863845D03*
Y867192D03*
Y870538D03*
Y873885D03*
Y877231D03*
Y880577D03*
Y883924D03*
Y887270D03*
Y890617D03*
Y893963D03*
Y897310D03*
Y900656D03*
Y904003D03*
Y907349D03*
Y910696D03*
Y914042D03*
Y917389D03*
Y920735D03*
Y924081D03*
Y927428D03*
Y930774D03*
Y934121D03*
Y937467D03*
Y940814D03*
Y944160D03*
Y947507D03*
Y950853D03*
Y954200D03*
Y957546D03*
Y960892D03*
Y964239D03*
Y967585D03*
Y970932D03*
Y974278D03*
Y977625D03*
Y980971D03*
Y984318D03*
Y987664D03*
Y991011D03*
Y994357D03*
Y1017782D03*
Y1021129D03*
Y1024475D03*
Y1027822D03*
Y1031168D03*
Y1034515D03*
Y1037861D03*
Y1041207D03*
Y1044554D03*
Y1047900D03*
Y1051247D03*
Y1054593D03*
Y1057940D03*
Y1061286D03*
Y1064633D03*
Y1067979D03*
Y1071326D03*
Y1074672D03*
Y1078018D03*
Y1081365D03*
Y1084711D03*
Y1088058D03*
Y1091404D03*
Y1094751D03*
Y1098097D03*
Y1101444D03*
Y1104790D03*
Y1108137D03*
Y1111483D03*
Y1114829D03*
Y1118176D03*
Y1121522D03*
Y1124869D03*
Y1128215D03*
Y1131562D03*
Y1134908D03*
Y1138255D03*
Y1141601D03*
Y1144948D03*
Y1148294D03*
Y1151641D03*
Y1154987D03*
Y1158333D03*
Y1161680D03*
Y1165026D03*
Y1168373D03*
Y1171719D03*
Y1175066D03*
Y1178412D03*
Y1181759D03*
Y1185105D03*
Y1188452D03*
Y1191798D03*
Y1195144D03*
Y1198491D03*
Y1201837D03*
Y1205184D03*
Y1208530D03*
Y1211877D03*
Y1215223D03*
Y1218570D03*
Y1221916D03*
Y1225263D03*
Y1228609D03*
Y1231955D03*
Y1235302D03*
Y1238648D03*
Y1241995D03*
Y1245341D03*
Y1248688D03*
Y1252034D03*
Y1255381D03*
Y1258727D03*
Y1262074D03*
Y1265420D03*
X1067591Y766798D03*
Y770144D03*
Y773491D03*
Y776837D03*
Y780184D03*
Y783530D03*
Y786877D03*
Y790223D03*
Y793570D03*
Y796916D03*
Y800263D03*
Y803609D03*
Y806955D03*
Y810302D03*
Y813648D03*
Y816995D03*
Y820341D03*
Y823688D03*
Y827034D03*
Y830381D03*
Y833727D03*
Y837074D03*
Y840420D03*
Y843766D03*
Y847113D03*
Y850459D03*
Y853806D03*
Y857152D03*
Y860499D03*
Y863845D03*
Y867192D03*
Y870538D03*
Y873885D03*
Y877231D03*
Y880577D03*
Y883924D03*
Y887270D03*
Y890617D03*
Y893963D03*
Y897310D03*
Y900656D03*
Y904003D03*
Y907349D03*
Y910696D03*
Y914042D03*
Y917389D03*
Y920735D03*
Y924081D03*
Y927428D03*
Y930774D03*
Y934121D03*
Y937467D03*
Y940814D03*
Y944160D03*
Y947507D03*
Y950853D03*
Y954200D03*
Y957546D03*
Y960892D03*
Y964239D03*
Y967585D03*
Y970932D03*
Y974278D03*
Y977625D03*
Y980971D03*
Y984318D03*
Y987664D03*
Y991011D03*
Y994357D03*
Y1017782D03*
Y1021129D03*
Y1024475D03*
Y1027822D03*
Y1031168D03*
Y1034515D03*
Y1037861D03*
Y1041207D03*
Y1044554D03*
Y1047900D03*
Y1051247D03*
Y1054593D03*
Y1057940D03*
Y1061286D03*
Y1064633D03*
Y1067979D03*
Y1071326D03*
Y1074672D03*
Y1078018D03*
Y1081365D03*
Y1084711D03*
Y1088058D03*
Y1091404D03*
Y1094751D03*
Y1098097D03*
Y1101444D03*
Y1104790D03*
Y1108137D03*
Y1111483D03*
Y1114829D03*
Y1118176D03*
Y1121522D03*
Y1124869D03*
Y1128215D03*
Y1131562D03*
Y1134908D03*
Y1138255D03*
Y1141601D03*
Y1144948D03*
Y1148294D03*
Y1151641D03*
Y1154987D03*
Y1158333D03*
Y1161680D03*
Y1165026D03*
Y1168373D03*
Y1171719D03*
Y1175066D03*
Y1178412D03*
Y1181759D03*
Y1185105D03*
Y1188452D03*
Y1191798D03*
Y1195144D03*
Y1198491D03*
Y1201837D03*
Y1205184D03*
Y1208530D03*
Y1211877D03*
Y1215223D03*
Y1218570D03*
Y1221916D03*
Y1225263D03*
Y1228609D03*
Y1231955D03*
Y1235302D03*
Y1238648D03*
Y1241995D03*
Y1245341D03*
Y1248688D03*
Y1252034D03*
Y1255381D03*
Y1258727D03*
Y1262074D03*
Y1265420D03*
X1083733Y766798D03*
Y770144D03*
Y773491D03*
Y776837D03*
Y780184D03*
Y783530D03*
Y786877D03*
Y790223D03*
Y793570D03*
Y796916D03*
Y800263D03*
Y803609D03*
Y806955D03*
Y810302D03*
Y813648D03*
Y816995D03*
Y820341D03*
Y823688D03*
Y827034D03*
Y830381D03*
Y833727D03*
Y837074D03*
Y840420D03*
Y843766D03*
Y847113D03*
Y850459D03*
Y853806D03*
Y857152D03*
Y860499D03*
Y863845D03*
Y867192D03*
Y870538D03*
Y873885D03*
Y877231D03*
Y880577D03*
Y883924D03*
Y887270D03*
Y890617D03*
Y893963D03*
Y897310D03*
Y900656D03*
Y904003D03*
Y907349D03*
Y910696D03*
Y914042D03*
Y917389D03*
Y920735D03*
Y924081D03*
Y927428D03*
Y930774D03*
Y934121D03*
Y937467D03*
Y940814D03*
Y944160D03*
Y947507D03*
Y950853D03*
Y954200D03*
Y957546D03*
Y960892D03*
Y964239D03*
Y967585D03*
Y970932D03*
Y974278D03*
Y977625D03*
Y980971D03*
Y984318D03*
Y987664D03*
Y991011D03*
Y994357D03*
Y1017782D03*
Y1021129D03*
Y1024475D03*
Y1027822D03*
Y1031168D03*
Y1034515D03*
Y1037861D03*
Y1041207D03*
Y1044554D03*
Y1047900D03*
Y1051247D03*
Y1054593D03*
Y1057940D03*
Y1061286D03*
Y1064633D03*
Y1067979D03*
Y1071326D03*
Y1074672D03*
Y1078018D03*
Y1081365D03*
Y1084711D03*
Y1088058D03*
Y1091404D03*
Y1094751D03*
Y1098097D03*
Y1101444D03*
Y1104790D03*
Y1108137D03*
Y1111483D03*
Y1114829D03*
Y1118176D03*
Y1121522D03*
Y1124869D03*
Y1128215D03*
Y1131562D03*
Y1134908D03*
Y1138255D03*
Y1141601D03*
Y1144948D03*
Y1148294D03*
Y1151641D03*
Y1154987D03*
Y1158333D03*
Y1161680D03*
Y1165026D03*
Y1168373D03*
Y1171719D03*
Y1175066D03*
Y1178412D03*
Y1181759D03*
Y1185105D03*
Y1188452D03*
Y1191798D03*
Y1195144D03*
Y1198491D03*
Y1201837D03*
Y1205184D03*
Y1208530D03*
Y1211877D03*
Y1215223D03*
Y1218570D03*
Y1221916D03*
Y1225263D03*
Y1228609D03*
Y1231955D03*
Y1235302D03*
Y1238648D03*
Y1241995D03*
Y1245341D03*
Y1248688D03*
Y1252034D03*
Y1255381D03*
Y1258727D03*
Y1262074D03*
Y1265420D03*
X1097291Y766798D03*
Y770144D03*
Y773491D03*
Y776837D03*
Y780184D03*
Y783530D03*
Y786877D03*
Y790223D03*
Y793570D03*
Y796916D03*
Y800263D03*
Y803609D03*
Y806955D03*
Y810302D03*
Y813648D03*
Y816995D03*
Y820341D03*
Y823688D03*
Y827034D03*
Y830381D03*
Y833727D03*
Y837074D03*
Y840420D03*
Y843766D03*
Y847113D03*
Y850459D03*
Y853806D03*
Y857152D03*
Y860499D03*
Y863845D03*
Y867192D03*
Y870538D03*
Y873885D03*
Y877231D03*
Y880577D03*
Y883924D03*
Y887270D03*
Y890617D03*
Y893963D03*
Y897310D03*
Y900656D03*
Y904003D03*
Y907349D03*
Y910696D03*
Y914042D03*
Y917389D03*
Y920735D03*
Y924081D03*
Y927428D03*
Y930774D03*
Y934121D03*
Y937467D03*
Y940814D03*
Y944160D03*
Y947507D03*
Y950853D03*
Y954200D03*
Y957546D03*
Y960892D03*
Y964239D03*
Y967585D03*
Y970932D03*
Y974278D03*
Y977625D03*
Y980971D03*
Y984318D03*
Y987664D03*
Y991011D03*
Y994357D03*
Y1017782D03*
Y1021129D03*
Y1024475D03*
Y1027822D03*
Y1031168D03*
Y1034515D03*
Y1037861D03*
Y1041207D03*
Y1044554D03*
Y1047900D03*
Y1051247D03*
Y1054593D03*
Y1057940D03*
Y1061286D03*
Y1064633D03*
Y1067979D03*
Y1071326D03*
Y1074672D03*
Y1078018D03*
Y1081365D03*
Y1084711D03*
Y1088058D03*
Y1091404D03*
Y1094751D03*
Y1098097D03*
Y1101444D03*
Y1104790D03*
Y1108137D03*
Y1111483D03*
Y1114829D03*
Y1118176D03*
Y1121522D03*
Y1124869D03*
Y1128215D03*
Y1131562D03*
Y1134908D03*
Y1138255D03*
Y1141601D03*
Y1144948D03*
Y1148294D03*
Y1151641D03*
Y1154987D03*
Y1158333D03*
Y1161680D03*
Y1165026D03*
Y1168373D03*
Y1171719D03*
Y1175066D03*
Y1178412D03*
Y1181759D03*
Y1185105D03*
Y1188452D03*
Y1191798D03*
Y1195144D03*
Y1198491D03*
Y1201837D03*
Y1205184D03*
Y1208530D03*
Y1211877D03*
Y1215223D03*
Y1218570D03*
Y1221916D03*
Y1225263D03*
Y1228609D03*
Y1231955D03*
Y1235302D03*
Y1238648D03*
Y1241995D03*
Y1245341D03*
Y1248688D03*
Y1252034D03*
Y1255381D03*
Y1258727D03*
Y1262074D03*
Y1265420D03*
X1113433Y766798D03*
Y770144D03*
Y773491D03*
Y776837D03*
Y780184D03*
Y783530D03*
Y786877D03*
Y790223D03*
Y793570D03*
Y796916D03*
Y800263D03*
Y803609D03*
Y806955D03*
Y810302D03*
Y813648D03*
Y816995D03*
Y820341D03*
Y823688D03*
Y827034D03*
Y830381D03*
Y833727D03*
Y837074D03*
Y840420D03*
Y843766D03*
Y847113D03*
Y850459D03*
Y853806D03*
Y857152D03*
Y860499D03*
Y863845D03*
Y867192D03*
Y870538D03*
Y873885D03*
Y877231D03*
Y880577D03*
Y883924D03*
Y887270D03*
Y890617D03*
Y893963D03*
Y897310D03*
Y900656D03*
Y904003D03*
Y907349D03*
Y910696D03*
Y914042D03*
Y917389D03*
Y920735D03*
Y924081D03*
Y927428D03*
Y930774D03*
Y934121D03*
Y937467D03*
Y940814D03*
Y944160D03*
Y947507D03*
Y950853D03*
Y954200D03*
Y957546D03*
Y960892D03*
Y964239D03*
Y967585D03*
Y970932D03*
Y974278D03*
Y977625D03*
Y980971D03*
Y984318D03*
Y987664D03*
Y991011D03*
Y994357D03*
Y1017782D03*
Y1021129D03*
Y1024475D03*
Y1027822D03*
Y1031168D03*
Y1034515D03*
Y1037861D03*
Y1041207D03*
Y1044554D03*
Y1047900D03*
Y1051247D03*
Y1054593D03*
Y1057940D03*
Y1061286D03*
Y1064633D03*
Y1067979D03*
Y1071326D03*
Y1074672D03*
Y1078018D03*
Y1081365D03*
Y1084711D03*
Y1088058D03*
Y1091404D03*
Y1094751D03*
Y1098097D03*
Y1101444D03*
Y1104790D03*
Y1108137D03*
Y1111483D03*
Y1114829D03*
Y1118176D03*
Y1121522D03*
Y1124869D03*
Y1128215D03*
Y1131562D03*
Y1134908D03*
Y1138255D03*
Y1141601D03*
Y1144948D03*
Y1148294D03*
Y1151641D03*
Y1154987D03*
Y1158333D03*
Y1161680D03*
Y1165026D03*
Y1168373D03*
Y1171719D03*
Y1175066D03*
Y1178412D03*
Y1181759D03*
Y1185105D03*
Y1188452D03*
Y1191798D03*
Y1195144D03*
Y1198491D03*
Y1201837D03*
Y1205184D03*
Y1208530D03*
Y1211877D03*
Y1215223D03*
Y1218570D03*
Y1221916D03*
Y1225263D03*
Y1228609D03*
Y1231955D03*
Y1235302D03*
Y1238648D03*
Y1241995D03*
Y1245341D03*
Y1248688D03*
Y1252034D03*
Y1255381D03*
Y1258727D03*
Y1262074D03*
Y1265420D03*
X1126991Y766798D03*
Y770144D03*
Y773491D03*
Y776837D03*
Y780184D03*
Y783530D03*
Y786877D03*
Y790223D03*
Y793570D03*
Y796916D03*
Y800263D03*
Y803609D03*
Y806955D03*
Y810302D03*
Y813648D03*
Y816995D03*
Y820341D03*
Y823688D03*
Y827034D03*
Y830381D03*
Y833727D03*
Y837074D03*
Y840420D03*
Y843766D03*
Y847113D03*
Y850459D03*
Y853806D03*
Y857152D03*
Y860499D03*
Y863845D03*
Y867192D03*
Y870538D03*
Y873885D03*
Y877231D03*
Y880577D03*
Y883924D03*
Y887270D03*
Y890617D03*
Y893963D03*
Y897310D03*
Y900656D03*
Y904003D03*
Y907349D03*
Y910696D03*
Y914042D03*
Y917389D03*
Y920735D03*
Y924081D03*
Y927428D03*
Y930774D03*
Y934121D03*
Y937467D03*
Y940814D03*
Y944160D03*
Y947507D03*
Y950853D03*
Y954200D03*
Y957546D03*
Y960892D03*
Y964239D03*
Y967585D03*
Y970932D03*
Y974278D03*
Y977625D03*
Y980971D03*
Y984318D03*
Y987664D03*
Y991011D03*
Y994357D03*
Y1017782D03*
Y1021129D03*
Y1024475D03*
Y1027822D03*
Y1031168D03*
Y1034515D03*
Y1037861D03*
Y1041207D03*
Y1044554D03*
Y1047900D03*
Y1051247D03*
Y1054593D03*
Y1057940D03*
Y1061286D03*
Y1064633D03*
Y1067979D03*
Y1071326D03*
Y1074672D03*
Y1078018D03*
Y1081365D03*
Y1084711D03*
Y1088058D03*
Y1091404D03*
Y1094751D03*
Y1098097D03*
Y1101444D03*
Y1104790D03*
Y1108137D03*
Y1111483D03*
Y1114829D03*
Y1118176D03*
Y1121522D03*
Y1124869D03*
Y1128215D03*
Y1131562D03*
Y1134908D03*
Y1138255D03*
Y1141601D03*
Y1144948D03*
Y1148294D03*
Y1151641D03*
Y1154987D03*
Y1158333D03*
Y1161680D03*
Y1165026D03*
Y1168373D03*
Y1171719D03*
Y1175066D03*
Y1178412D03*
Y1181759D03*
Y1185105D03*
Y1188452D03*
Y1191798D03*
Y1195144D03*
Y1198491D03*
Y1201837D03*
Y1205184D03*
Y1208530D03*
Y1211877D03*
Y1215223D03*
Y1218570D03*
Y1221916D03*
Y1225263D03*
Y1228609D03*
Y1231955D03*
Y1235302D03*
Y1238648D03*
Y1241995D03*
Y1245341D03*
Y1248688D03*
Y1252034D03*
Y1255381D03*
Y1258727D03*
Y1262074D03*
Y1265420D03*
X1143133Y766798D03*
Y770144D03*
Y773491D03*
Y776837D03*
Y780184D03*
Y783530D03*
Y786877D03*
Y790223D03*
Y793570D03*
Y796916D03*
Y800263D03*
Y803609D03*
Y806955D03*
Y810302D03*
Y813648D03*
Y816995D03*
Y820341D03*
Y823688D03*
Y827034D03*
Y830381D03*
Y833727D03*
Y837074D03*
Y840420D03*
Y843766D03*
Y847113D03*
Y850459D03*
Y853806D03*
Y857152D03*
Y860499D03*
Y863845D03*
Y867192D03*
Y870538D03*
Y873885D03*
Y877231D03*
Y880577D03*
Y883924D03*
Y887270D03*
Y890617D03*
Y893963D03*
Y897310D03*
Y900656D03*
Y904003D03*
Y907349D03*
Y910696D03*
Y914042D03*
Y917389D03*
Y920735D03*
Y924081D03*
Y927428D03*
Y930774D03*
Y934121D03*
Y937467D03*
Y940814D03*
Y944160D03*
Y947507D03*
Y950853D03*
Y954200D03*
Y957546D03*
Y960892D03*
Y964239D03*
Y967585D03*
Y970932D03*
Y974278D03*
Y977625D03*
Y980971D03*
Y984318D03*
Y987664D03*
Y991011D03*
Y994357D03*
Y1017782D03*
Y1021129D03*
Y1024475D03*
Y1027822D03*
Y1031168D03*
Y1034515D03*
Y1037861D03*
Y1041207D03*
Y1044554D03*
Y1047900D03*
Y1051247D03*
Y1054593D03*
Y1057940D03*
Y1061286D03*
Y1064633D03*
Y1067979D03*
Y1071326D03*
Y1074672D03*
Y1078018D03*
Y1081365D03*
Y1084711D03*
Y1088058D03*
Y1091404D03*
Y1094751D03*
Y1098097D03*
Y1101444D03*
Y1104790D03*
Y1108137D03*
Y1111483D03*
Y1114829D03*
Y1118176D03*
Y1121522D03*
Y1124869D03*
Y1128215D03*
Y1131562D03*
Y1134908D03*
Y1138255D03*
Y1141601D03*
Y1144948D03*
Y1148294D03*
Y1151641D03*
Y1154987D03*
Y1158333D03*
Y1161680D03*
Y1165026D03*
Y1168373D03*
Y1171719D03*
Y1175066D03*
Y1178412D03*
Y1181759D03*
Y1185105D03*
Y1188452D03*
Y1191798D03*
Y1195144D03*
Y1198491D03*
Y1201837D03*
Y1205184D03*
Y1208530D03*
Y1211877D03*
Y1215223D03*
Y1218570D03*
Y1221916D03*
Y1225263D03*
Y1228609D03*
Y1231955D03*
Y1235302D03*
Y1238648D03*
Y1241995D03*
Y1245341D03*
Y1248688D03*
Y1252034D03*
Y1255381D03*
Y1258727D03*
Y1262074D03*
Y1265420D03*
X1156691Y766798D03*
Y770144D03*
Y773491D03*
Y776837D03*
Y780184D03*
Y783530D03*
Y786877D03*
Y790223D03*
Y793570D03*
Y796916D03*
Y800263D03*
Y803609D03*
Y806955D03*
Y810302D03*
Y813648D03*
Y816995D03*
Y820341D03*
Y823688D03*
Y827034D03*
Y830381D03*
Y833727D03*
Y837074D03*
Y840420D03*
Y843766D03*
Y847113D03*
Y850459D03*
Y853806D03*
Y857152D03*
Y860499D03*
Y863845D03*
Y867192D03*
Y870538D03*
Y873885D03*
Y877231D03*
Y880577D03*
Y883924D03*
Y887270D03*
Y890617D03*
Y893963D03*
Y897310D03*
Y900656D03*
Y904003D03*
Y907349D03*
Y910696D03*
Y914042D03*
Y917389D03*
Y920735D03*
Y924081D03*
Y927428D03*
Y930774D03*
Y934121D03*
Y937467D03*
Y940814D03*
Y944160D03*
Y947507D03*
Y950853D03*
Y954200D03*
Y957546D03*
Y960892D03*
Y964239D03*
Y967585D03*
Y970932D03*
Y974278D03*
Y977625D03*
Y980971D03*
Y984318D03*
Y987664D03*
Y991011D03*
Y994357D03*
Y1017782D03*
Y1021129D03*
Y1024475D03*
Y1027822D03*
Y1031168D03*
Y1034515D03*
Y1037861D03*
Y1041207D03*
Y1044554D03*
Y1047900D03*
Y1051247D03*
Y1054593D03*
Y1057940D03*
Y1061286D03*
Y1064633D03*
Y1067979D03*
Y1071326D03*
Y1074672D03*
Y1078018D03*
Y1081365D03*
Y1084711D03*
Y1088058D03*
Y1091404D03*
Y1094751D03*
Y1098097D03*
Y1101444D03*
Y1104790D03*
Y1108137D03*
Y1111483D03*
Y1114829D03*
Y1118176D03*
Y1121522D03*
Y1124869D03*
Y1128215D03*
Y1131562D03*
Y1134908D03*
Y1138255D03*
Y1141601D03*
Y1144948D03*
Y1148294D03*
Y1151641D03*
Y1154987D03*
Y1158333D03*
Y1161680D03*
Y1165026D03*
Y1168373D03*
Y1171719D03*
Y1175066D03*
Y1178412D03*
Y1181759D03*
Y1185105D03*
Y1188452D03*
Y1191798D03*
Y1195144D03*
Y1198491D03*
Y1201837D03*
Y1205184D03*
Y1208530D03*
Y1211877D03*
Y1215223D03*
Y1218570D03*
Y1221916D03*
Y1225263D03*
Y1228609D03*
Y1231955D03*
Y1235302D03*
Y1238648D03*
Y1241995D03*
Y1245341D03*
Y1248688D03*
Y1252034D03*
Y1255381D03*
Y1258727D03*
Y1262074D03*
Y1265420D03*
X1186391Y766798D03*
Y770144D03*
X1172833Y766798D03*
Y770144D03*
X1186391Y773491D03*
Y776837D03*
Y780184D03*
Y783530D03*
Y786877D03*
X1172833Y773491D03*
Y776837D03*
Y780184D03*
Y783530D03*
Y786877D03*
X1186391Y790223D03*
Y793570D03*
Y796916D03*
Y800263D03*
Y803609D03*
X1172833Y790223D03*
Y793570D03*
Y796916D03*
Y800263D03*
Y803609D03*
X1186391Y806955D03*
Y810302D03*
Y813648D03*
Y816995D03*
Y820341D03*
X1172833Y806955D03*
Y810302D03*
Y813648D03*
Y816995D03*
Y820341D03*
X1186391Y823688D03*
Y827034D03*
Y830381D03*
Y833727D03*
X1172833Y823688D03*
Y827034D03*
Y830381D03*
Y833727D03*
X1186391Y837074D03*
Y840420D03*
Y843766D03*
Y847113D03*
Y850459D03*
X1172833Y837074D03*
Y840420D03*
Y843766D03*
Y847113D03*
Y850459D03*
X1186391Y853806D03*
Y857152D03*
Y860499D03*
Y863845D03*
Y867192D03*
X1172833Y853806D03*
Y857152D03*
Y860499D03*
Y863845D03*
Y867192D03*
X1186391Y870538D03*
Y873885D03*
Y877231D03*
Y880577D03*
Y883924D03*
X1172833Y870538D03*
Y873885D03*
Y877231D03*
Y880577D03*
Y883924D03*
X1186391Y887270D03*
Y890617D03*
Y893963D03*
Y897310D03*
Y900656D03*
X1172833Y887270D03*
Y890617D03*
Y893963D03*
Y897310D03*
Y900656D03*
X1186391Y904003D03*
Y907349D03*
Y910696D03*
Y914042D03*
Y917389D03*
X1172833Y904003D03*
Y907349D03*
Y910696D03*
Y914042D03*
Y917389D03*
X1186391Y920735D03*
Y924081D03*
Y927428D03*
Y930774D03*
Y934121D03*
X1172833Y920735D03*
Y924081D03*
Y927428D03*
Y930774D03*
Y934121D03*
X1186391Y937467D03*
Y940814D03*
Y944160D03*
Y947507D03*
X1172833Y937467D03*
Y940814D03*
Y944160D03*
Y947507D03*
X1186391Y950853D03*
Y954200D03*
Y957546D03*
Y960892D03*
Y964239D03*
X1172833Y950853D03*
Y954200D03*
Y957546D03*
Y960892D03*
Y964239D03*
X1186391Y967585D03*
Y970932D03*
Y974278D03*
Y977625D03*
Y980971D03*
X1172833Y967585D03*
Y970932D03*
Y974278D03*
Y977625D03*
Y980971D03*
X1186391Y984318D03*
Y987664D03*
Y991011D03*
Y994357D03*
X1172833Y984318D03*
Y987664D03*
Y991011D03*
Y994357D03*
X1186391Y1017782D03*
Y1021129D03*
Y1024475D03*
Y1027822D03*
Y1031168D03*
X1172833Y1017782D03*
Y1021129D03*
Y1024475D03*
Y1027822D03*
Y1031168D03*
X1186391Y1034515D03*
Y1037861D03*
Y1041207D03*
Y1044554D03*
Y1047900D03*
X1172833Y1034515D03*
Y1037861D03*
Y1041207D03*
Y1044554D03*
Y1047900D03*
X1186391Y1051247D03*
Y1054593D03*
Y1057940D03*
Y1061286D03*
X1172833Y1051247D03*
Y1054593D03*
Y1057940D03*
Y1061286D03*
X1186391Y1064633D03*
Y1067979D03*
Y1071326D03*
Y1074672D03*
Y1078018D03*
X1172833Y1064633D03*
Y1067979D03*
Y1071326D03*
Y1074672D03*
Y1078018D03*
X1186391Y1081365D03*
Y1084711D03*
Y1088058D03*
Y1091404D03*
Y1094751D03*
X1172833Y1081365D03*
Y1084711D03*
Y1088058D03*
Y1091404D03*
Y1094751D03*
X1186391Y1098097D03*
Y1101444D03*
Y1104790D03*
Y1108137D03*
Y1111483D03*
X1172833Y1098097D03*
Y1101444D03*
Y1104790D03*
Y1108137D03*
Y1111483D03*
X1186391Y1114829D03*
Y1118176D03*
Y1121522D03*
Y1124869D03*
Y1128215D03*
X1172833Y1114829D03*
Y1118176D03*
Y1121522D03*
Y1124869D03*
Y1128215D03*
X1186391Y1131562D03*
Y1134908D03*
Y1138255D03*
Y1141601D03*
Y1144948D03*
X1172833Y1131562D03*
Y1134908D03*
Y1138255D03*
Y1141601D03*
Y1144948D03*
X1186391Y1148294D03*
Y1151641D03*
Y1154987D03*
Y1158333D03*
Y1161680D03*
X1172833Y1148294D03*
Y1151641D03*
Y1154987D03*
Y1158333D03*
Y1161680D03*
X1186391Y1165026D03*
Y1168373D03*
Y1171719D03*
Y1175066D03*
X1172833Y1165026D03*
Y1168373D03*
Y1171719D03*
Y1175066D03*
X1186391Y1178412D03*
Y1181759D03*
Y1185105D03*
Y1188452D03*
Y1191798D03*
X1172833Y1178412D03*
Y1181759D03*
Y1185105D03*
Y1188452D03*
Y1191798D03*
X1186391Y1195144D03*
Y1198491D03*
Y1201837D03*
Y1205184D03*
Y1208530D03*
X1172833Y1195144D03*
Y1198491D03*
Y1201837D03*
Y1205184D03*
Y1208530D03*
X1186391Y1211877D03*
Y1215223D03*
Y1218570D03*
Y1221916D03*
Y1225263D03*
X1172833Y1211877D03*
Y1215223D03*
Y1218570D03*
Y1221916D03*
Y1225263D03*
X1186391Y1228609D03*
Y1231955D03*
Y1235302D03*
Y1238648D03*
Y1241995D03*
X1172833Y1228609D03*
Y1231955D03*
Y1235302D03*
Y1238648D03*
Y1241995D03*
X1186391Y1245341D03*
Y1248688D03*
Y1252034D03*
Y1255381D03*
Y1258727D03*
X1172833Y1245341D03*
Y1248688D03*
Y1252034D03*
Y1255381D03*
Y1258727D03*
X1186391Y1262074D03*
Y1265420D03*
X1172833Y1262074D03*
Y1265420D03*
X1202533Y766798D03*
Y770144D03*
Y773491D03*
Y776837D03*
Y780184D03*
Y783530D03*
Y786877D03*
Y790223D03*
Y793570D03*
Y796916D03*
Y800263D03*
Y803609D03*
Y806955D03*
Y810302D03*
Y813648D03*
Y816995D03*
Y820341D03*
Y823688D03*
Y827034D03*
Y830381D03*
Y833727D03*
Y837074D03*
Y840420D03*
Y843766D03*
Y847113D03*
Y850459D03*
Y853806D03*
Y857152D03*
Y860499D03*
Y863845D03*
Y867192D03*
Y870538D03*
Y873885D03*
Y877231D03*
Y880577D03*
Y883924D03*
Y887270D03*
Y890617D03*
Y893963D03*
Y897310D03*
Y900656D03*
Y904003D03*
Y907349D03*
Y910696D03*
Y914042D03*
Y917389D03*
Y920735D03*
Y924081D03*
Y927428D03*
Y930774D03*
Y934121D03*
Y937467D03*
Y940814D03*
Y944160D03*
Y947507D03*
Y950853D03*
Y954200D03*
Y957546D03*
Y960892D03*
Y964239D03*
Y967585D03*
Y970932D03*
Y974278D03*
Y977625D03*
Y980971D03*
Y984318D03*
Y987664D03*
Y991011D03*
Y994357D03*
Y1017782D03*
Y1021129D03*
Y1024475D03*
Y1027822D03*
Y1031168D03*
Y1034515D03*
Y1037861D03*
Y1041207D03*
Y1044554D03*
Y1047900D03*
Y1051247D03*
Y1054593D03*
Y1057940D03*
Y1061286D03*
Y1064633D03*
Y1067979D03*
Y1071326D03*
Y1074672D03*
Y1078018D03*
Y1081365D03*
Y1084711D03*
Y1088058D03*
Y1091404D03*
Y1094751D03*
Y1098097D03*
Y1101444D03*
Y1104790D03*
Y1108137D03*
Y1111483D03*
Y1114829D03*
Y1118176D03*
Y1121522D03*
Y1124869D03*
Y1128215D03*
Y1131562D03*
Y1134908D03*
Y1138255D03*
Y1141601D03*
Y1144948D03*
Y1148294D03*
Y1151641D03*
Y1154987D03*
Y1158333D03*
Y1161680D03*
Y1165026D03*
Y1168373D03*
Y1171719D03*
Y1175066D03*
Y1178412D03*
Y1181759D03*
Y1185105D03*
Y1188452D03*
Y1191798D03*
Y1195144D03*
Y1198491D03*
Y1201837D03*
Y1205184D03*
Y1208530D03*
Y1211877D03*
Y1215223D03*
Y1218570D03*
Y1221916D03*
Y1225263D03*
Y1228609D03*
Y1231955D03*
Y1235302D03*
Y1238648D03*
Y1241995D03*
Y1245341D03*
Y1248688D03*
Y1252034D03*
Y1255381D03*
Y1258727D03*
Y1262074D03*
Y1265420D03*
X1216091Y766798D03*
Y770144D03*
Y773491D03*
Y776837D03*
Y780184D03*
Y783530D03*
Y786877D03*
Y790223D03*
Y793570D03*
Y796916D03*
Y800263D03*
Y803609D03*
Y806955D03*
Y810302D03*
Y813648D03*
Y816995D03*
Y820341D03*
Y823688D03*
Y827034D03*
Y830381D03*
Y833727D03*
Y837074D03*
Y840420D03*
Y843766D03*
Y847113D03*
Y850459D03*
Y853806D03*
Y857152D03*
Y860499D03*
Y863845D03*
Y867192D03*
Y870538D03*
Y873885D03*
Y877231D03*
Y880577D03*
Y883924D03*
Y887270D03*
Y890617D03*
Y893963D03*
Y897310D03*
Y900656D03*
Y904003D03*
Y907349D03*
Y910696D03*
Y914042D03*
Y917389D03*
Y920735D03*
Y924081D03*
Y927428D03*
Y930774D03*
Y934121D03*
Y937467D03*
Y940814D03*
Y944160D03*
Y947507D03*
Y950853D03*
Y954200D03*
Y957546D03*
Y960892D03*
Y964239D03*
Y967585D03*
Y970932D03*
Y974278D03*
Y977625D03*
Y980971D03*
Y984318D03*
Y987664D03*
Y991011D03*
Y994357D03*
Y1017782D03*
Y1021129D03*
Y1024475D03*
Y1027822D03*
Y1031168D03*
Y1034515D03*
Y1037861D03*
Y1041207D03*
Y1044554D03*
Y1047900D03*
Y1051247D03*
Y1054593D03*
Y1057940D03*
Y1061286D03*
Y1064633D03*
Y1067979D03*
Y1071326D03*
Y1074672D03*
Y1078018D03*
Y1081365D03*
Y1084711D03*
Y1088058D03*
Y1091404D03*
Y1094751D03*
Y1098097D03*
Y1101444D03*
Y1104790D03*
Y1108137D03*
Y1111483D03*
Y1114829D03*
Y1118176D03*
Y1121522D03*
Y1124869D03*
Y1128215D03*
Y1131562D03*
Y1134908D03*
Y1138255D03*
Y1141601D03*
Y1144948D03*
Y1148294D03*
Y1151641D03*
Y1154987D03*
Y1158333D03*
Y1161680D03*
Y1165026D03*
Y1168373D03*
Y1171719D03*
Y1175066D03*
Y1178412D03*
Y1181759D03*
Y1185105D03*
Y1188452D03*
Y1191798D03*
Y1195144D03*
Y1198491D03*
Y1201837D03*
Y1205184D03*
Y1208530D03*
Y1211877D03*
Y1215223D03*
Y1218570D03*
Y1221916D03*
Y1225263D03*
Y1228609D03*
Y1231955D03*
Y1235302D03*
Y1238648D03*
Y1241995D03*
Y1245341D03*
Y1248688D03*
Y1252034D03*
Y1255381D03*
Y1258727D03*
Y1262074D03*
Y1265420D03*
X1232233Y766798D03*
Y770144D03*
Y773491D03*
Y776837D03*
Y780184D03*
Y783530D03*
Y786877D03*
Y790223D03*
Y793570D03*
Y796916D03*
Y800263D03*
Y803609D03*
Y806955D03*
Y810302D03*
Y813648D03*
Y816995D03*
Y820341D03*
Y823688D03*
Y827034D03*
Y830381D03*
Y833727D03*
Y837074D03*
Y840420D03*
Y843766D03*
Y847113D03*
Y850459D03*
Y853806D03*
Y857152D03*
Y860499D03*
Y863845D03*
Y867192D03*
Y870538D03*
Y873885D03*
Y877231D03*
Y880577D03*
Y883924D03*
Y887270D03*
Y890617D03*
Y893963D03*
Y897310D03*
Y900656D03*
Y904003D03*
Y907349D03*
Y910696D03*
Y914042D03*
Y917389D03*
Y920735D03*
Y924081D03*
Y927428D03*
Y930774D03*
Y934121D03*
Y937467D03*
Y940814D03*
Y944160D03*
Y947507D03*
Y950853D03*
Y954200D03*
Y957546D03*
Y960892D03*
Y964239D03*
Y967585D03*
Y970932D03*
Y974278D03*
Y977625D03*
Y980971D03*
Y984318D03*
Y987664D03*
Y991011D03*
Y994357D03*
Y1017782D03*
Y1021129D03*
Y1024475D03*
Y1027822D03*
Y1031168D03*
Y1034515D03*
Y1037861D03*
Y1041207D03*
Y1044554D03*
Y1047900D03*
Y1051247D03*
Y1054593D03*
Y1057940D03*
Y1061286D03*
Y1064633D03*
Y1067979D03*
Y1071326D03*
Y1074672D03*
Y1078018D03*
Y1081365D03*
Y1084711D03*
Y1088058D03*
Y1091404D03*
Y1094751D03*
Y1098097D03*
Y1101444D03*
Y1104790D03*
Y1108137D03*
Y1111483D03*
Y1114829D03*
Y1118176D03*
Y1121522D03*
Y1124869D03*
Y1128215D03*
Y1131562D03*
Y1134908D03*
Y1138255D03*
Y1141601D03*
Y1144948D03*
Y1148294D03*
Y1151641D03*
Y1154987D03*
Y1158333D03*
Y1161680D03*
Y1165026D03*
Y1168373D03*
Y1171719D03*
Y1175066D03*
Y1178412D03*
Y1181759D03*
Y1185105D03*
Y1188452D03*
Y1191798D03*
Y1195144D03*
Y1198491D03*
Y1201837D03*
Y1205184D03*
Y1208530D03*
Y1211877D03*
Y1215223D03*
Y1218570D03*
Y1221916D03*
Y1225263D03*
Y1228609D03*
Y1231955D03*
Y1235302D03*
Y1238648D03*
Y1241995D03*
Y1245341D03*
Y1248688D03*
Y1252034D03*
Y1255381D03*
Y1258727D03*
Y1262074D03*
Y1265420D03*
X1601391Y766798D03*
Y770144D03*
Y773491D03*
Y776837D03*
Y780184D03*
Y783530D03*
Y786877D03*
Y790223D03*
Y793570D03*
Y796916D03*
Y800263D03*
Y803609D03*
Y806955D03*
Y810302D03*
Y813648D03*
Y816995D03*
Y820341D03*
Y823688D03*
Y827034D03*
Y830381D03*
Y833727D03*
Y837074D03*
Y840420D03*
Y843766D03*
Y847113D03*
Y850459D03*
Y853806D03*
Y857152D03*
Y860499D03*
Y863845D03*
Y867192D03*
Y870538D03*
Y873885D03*
Y877231D03*
Y880577D03*
Y883924D03*
Y887270D03*
Y890617D03*
Y893963D03*
Y897310D03*
Y900656D03*
Y904003D03*
Y907349D03*
Y910696D03*
Y914042D03*
Y917389D03*
Y920735D03*
Y924081D03*
Y927428D03*
Y930774D03*
Y934121D03*
Y937467D03*
Y940814D03*
Y944160D03*
Y947507D03*
Y950853D03*
Y954200D03*
Y957546D03*
Y960892D03*
Y964239D03*
Y967585D03*
Y970932D03*
Y974278D03*
Y977625D03*
Y980971D03*
Y984318D03*
Y987664D03*
Y991011D03*
Y994357D03*
Y1017782D03*
Y1021129D03*
Y1024475D03*
Y1027822D03*
Y1031168D03*
Y1034515D03*
Y1037861D03*
Y1041207D03*
Y1044554D03*
Y1047900D03*
Y1051247D03*
Y1054593D03*
Y1057940D03*
Y1061286D03*
Y1064633D03*
Y1067979D03*
Y1071326D03*
Y1074672D03*
Y1078018D03*
Y1081365D03*
Y1084711D03*
Y1088058D03*
Y1091404D03*
Y1094751D03*
Y1098097D03*
Y1101444D03*
Y1104790D03*
Y1108137D03*
Y1111483D03*
Y1114829D03*
Y1118176D03*
Y1121522D03*
Y1124869D03*
Y1128215D03*
Y1131562D03*
Y1134908D03*
Y1138255D03*
Y1141601D03*
Y1144948D03*
Y1148294D03*
Y1151641D03*
Y1154987D03*
Y1158333D03*
Y1161680D03*
Y1165026D03*
Y1168373D03*
Y1171719D03*
Y1175066D03*
Y1178412D03*
Y1181759D03*
Y1185105D03*
Y1188452D03*
Y1191798D03*
Y1195144D03*
Y1198491D03*
Y1201837D03*
Y1205184D03*
Y1208530D03*
Y1211877D03*
Y1215223D03*
Y1218570D03*
Y1221916D03*
Y1225263D03*
Y1228609D03*
Y1231955D03*
Y1235302D03*
Y1238648D03*
Y1241995D03*
Y1245341D03*
Y1248688D03*
Y1252034D03*
Y1255381D03*
Y1258727D03*
Y1262074D03*
Y1265420D03*
X1617533Y766798D03*
Y770144D03*
Y773491D03*
Y776837D03*
Y780184D03*
Y783530D03*
Y786877D03*
Y790223D03*
Y793570D03*
Y796916D03*
Y800263D03*
Y803609D03*
Y806955D03*
Y810302D03*
Y813648D03*
Y816995D03*
Y820341D03*
Y823688D03*
Y827034D03*
Y830381D03*
Y833727D03*
Y837074D03*
Y840420D03*
Y843766D03*
Y847113D03*
Y850459D03*
Y853806D03*
Y857152D03*
Y860499D03*
Y863845D03*
Y867192D03*
Y870538D03*
Y873885D03*
Y877231D03*
Y880577D03*
Y883924D03*
Y887270D03*
Y890617D03*
Y893963D03*
Y897310D03*
Y900656D03*
Y904003D03*
Y907349D03*
Y910696D03*
Y914042D03*
Y917389D03*
Y920735D03*
Y924081D03*
Y927428D03*
Y930774D03*
Y934121D03*
Y937467D03*
Y940814D03*
Y944160D03*
Y947507D03*
Y950853D03*
Y954200D03*
Y957546D03*
Y960892D03*
Y964239D03*
Y967585D03*
Y970932D03*
Y974278D03*
Y977625D03*
Y980971D03*
Y984318D03*
Y987664D03*
Y991011D03*
Y994357D03*
Y1017782D03*
Y1021129D03*
Y1024475D03*
Y1027822D03*
Y1031168D03*
Y1034515D03*
Y1037861D03*
Y1041207D03*
Y1044554D03*
Y1047900D03*
Y1051247D03*
Y1054593D03*
Y1057940D03*
Y1061286D03*
Y1064633D03*
Y1067979D03*
Y1071326D03*
Y1074672D03*
Y1078018D03*
Y1081365D03*
Y1084711D03*
Y1088058D03*
Y1091404D03*
Y1094751D03*
Y1098097D03*
Y1101444D03*
Y1104790D03*
Y1108137D03*
Y1111483D03*
Y1114829D03*
Y1118176D03*
Y1121522D03*
Y1124869D03*
Y1128215D03*
Y1131562D03*
Y1134908D03*
Y1138255D03*
Y1141601D03*
Y1144948D03*
Y1148294D03*
Y1151641D03*
Y1154987D03*
Y1158333D03*
Y1161680D03*
Y1165026D03*
Y1168373D03*
Y1171719D03*
Y1175066D03*
Y1178412D03*
Y1181759D03*
Y1185105D03*
Y1188452D03*
Y1191798D03*
Y1195144D03*
Y1198491D03*
Y1201837D03*
Y1205184D03*
Y1208530D03*
Y1211877D03*
Y1215223D03*
Y1218570D03*
Y1221916D03*
Y1225263D03*
Y1228609D03*
Y1231955D03*
Y1235302D03*
Y1238648D03*
Y1241995D03*
Y1245341D03*
Y1248688D03*
Y1252034D03*
Y1255381D03*
Y1258727D03*
Y1262074D03*
Y1265420D03*
X1631091Y766798D03*
Y770144D03*
Y773491D03*
Y776837D03*
Y780184D03*
Y783530D03*
Y786877D03*
Y790223D03*
Y793570D03*
Y796916D03*
Y800263D03*
Y803609D03*
Y806955D03*
Y810302D03*
Y813648D03*
Y816995D03*
Y820341D03*
Y823688D03*
Y827034D03*
Y830381D03*
Y833727D03*
Y837074D03*
Y840420D03*
Y843766D03*
Y847113D03*
Y850459D03*
Y853806D03*
Y857152D03*
Y860499D03*
Y863845D03*
Y867192D03*
Y870538D03*
Y873885D03*
Y877231D03*
Y880577D03*
Y883924D03*
Y887270D03*
Y890617D03*
Y893963D03*
Y897310D03*
Y900656D03*
Y904003D03*
Y907349D03*
Y910696D03*
Y914042D03*
Y917389D03*
Y920735D03*
Y924081D03*
Y927428D03*
Y930774D03*
Y934121D03*
Y937467D03*
Y940814D03*
Y944160D03*
Y947507D03*
Y950853D03*
Y954200D03*
Y957546D03*
Y960892D03*
Y964239D03*
Y967585D03*
Y970932D03*
Y974278D03*
Y977625D03*
Y980971D03*
Y984318D03*
Y987664D03*
Y991011D03*
Y994357D03*
Y1017782D03*
Y1021129D03*
Y1024475D03*
Y1027822D03*
Y1031168D03*
Y1034515D03*
Y1037861D03*
Y1041207D03*
Y1044554D03*
Y1047900D03*
Y1051247D03*
Y1054593D03*
Y1057940D03*
Y1061286D03*
Y1064633D03*
Y1067979D03*
Y1071326D03*
Y1074672D03*
Y1078018D03*
Y1081365D03*
Y1084711D03*
Y1088058D03*
Y1091404D03*
Y1094751D03*
Y1098097D03*
Y1101444D03*
Y1104790D03*
Y1108137D03*
Y1111483D03*
Y1114829D03*
Y1118176D03*
Y1121522D03*
Y1124869D03*
Y1128215D03*
Y1131562D03*
Y1134908D03*
Y1138255D03*
Y1141601D03*
Y1144948D03*
Y1148294D03*
Y1151641D03*
Y1154987D03*
Y1158333D03*
Y1161680D03*
Y1165026D03*
Y1168373D03*
Y1171719D03*
Y1175066D03*
Y1178412D03*
Y1181759D03*
Y1185105D03*
Y1188452D03*
Y1191798D03*
Y1195144D03*
Y1198491D03*
Y1201837D03*
Y1205184D03*
Y1208530D03*
Y1211877D03*
Y1215223D03*
Y1218570D03*
Y1221916D03*
Y1225263D03*
Y1228609D03*
Y1231955D03*
Y1235302D03*
Y1238648D03*
Y1241995D03*
Y1245341D03*
Y1248688D03*
Y1252034D03*
Y1255381D03*
Y1258727D03*
Y1262074D03*
Y1265420D03*
X1647233Y766798D03*
Y770144D03*
Y773491D03*
Y776837D03*
Y780184D03*
Y783530D03*
Y786877D03*
Y790223D03*
Y793570D03*
Y796916D03*
Y800263D03*
Y803609D03*
Y806955D03*
Y810302D03*
Y813648D03*
Y816995D03*
Y820341D03*
Y823688D03*
Y827034D03*
Y830381D03*
Y833727D03*
Y837074D03*
Y840420D03*
Y843766D03*
Y847113D03*
Y850459D03*
Y853806D03*
Y857152D03*
Y860499D03*
Y863845D03*
Y867192D03*
Y870538D03*
Y873885D03*
Y877231D03*
Y880577D03*
Y883924D03*
Y887270D03*
Y890617D03*
Y893963D03*
Y897310D03*
Y900656D03*
Y904003D03*
Y907349D03*
Y910696D03*
Y914042D03*
Y917389D03*
Y920735D03*
Y924081D03*
Y927428D03*
Y930774D03*
Y934121D03*
Y937467D03*
Y940814D03*
Y944160D03*
Y947507D03*
Y950853D03*
Y954200D03*
Y957546D03*
Y960892D03*
Y964239D03*
Y967585D03*
Y970932D03*
Y974278D03*
Y977625D03*
Y980971D03*
Y984318D03*
Y987664D03*
Y991011D03*
Y994357D03*
Y1017782D03*
Y1021129D03*
Y1024475D03*
Y1027822D03*
Y1031168D03*
Y1034515D03*
Y1037861D03*
Y1041207D03*
Y1044554D03*
Y1047900D03*
Y1051247D03*
Y1054593D03*
Y1057940D03*
Y1061286D03*
Y1064633D03*
Y1067979D03*
Y1071326D03*
Y1074672D03*
Y1078018D03*
Y1081365D03*
Y1084711D03*
Y1088058D03*
Y1091404D03*
Y1094751D03*
Y1098097D03*
Y1101444D03*
Y1104790D03*
Y1108137D03*
Y1111483D03*
Y1114829D03*
Y1118176D03*
Y1121522D03*
Y1124869D03*
Y1128215D03*
Y1131562D03*
Y1134908D03*
Y1138255D03*
Y1141601D03*
Y1144948D03*
Y1148294D03*
Y1151641D03*
Y1154987D03*
Y1158333D03*
Y1161680D03*
Y1165026D03*
Y1168373D03*
Y1171719D03*
Y1175066D03*
Y1178412D03*
Y1181759D03*
Y1185105D03*
Y1188452D03*
Y1191798D03*
Y1195144D03*
Y1198491D03*
Y1201837D03*
Y1205184D03*
Y1208530D03*
Y1211877D03*
Y1215223D03*
Y1218570D03*
Y1221916D03*
Y1225263D03*
Y1228609D03*
Y1231955D03*
Y1235302D03*
Y1238648D03*
Y1241995D03*
Y1245341D03*
Y1248688D03*
Y1252034D03*
Y1255381D03*
Y1258727D03*
Y1262074D03*
Y1265420D03*
X1660791Y766798D03*
Y770144D03*
Y773491D03*
Y776837D03*
Y780184D03*
Y783530D03*
Y786877D03*
Y790223D03*
Y793570D03*
Y796916D03*
Y800263D03*
Y803609D03*
Y806955D03*
Y810302D03*
Y813648D03*
Y816995D03*
Y820341D03*
Y823688D03*
Y827034D03*
Y830381D03*
Y833727D03*
Y837074D03*
Y840420D03*
Y843766D03*
Y847113D03*
Y850459D03*
Y853806D03*
Y857152D03*
Y860499D03*
Y863845D03*
Y867192D03*
Y870538D03*
Y873885D03*
Y877231D03*
Y880577D03*
Y883924D03*
Y887270D03*
Y890617D03*
Y893963D03*
Y897310D03*
Y900656D03*
Y904003D03*
Y907349D03*
Y910696D03*
Y914042D03*
Y917389D03*
Y920735D03*
Y924081D03*
Y927428D03*
Y930774D03*
Y934121D03*
Y937467D03*
Y940814D03*
Y944160D03*
Y947507D03*
Y950853D03*
Y954200D03*
Y957546D03*
Y960892D03*
Y964239D03*
Y967585D03*
Y970932D03*
Y974278D03*
Y977625D03*
Y980971D03*
Y984318D03*
Y987664D03*
Y991011D03*
Y994357D03*
Y1017782D03*
Y1021129D03*
Y1024475D03*
Y1027822D03*
Y1031168D03*
Y1034515D03*
Y1037861D03*
Y1041207D03*
Y1044554D03*
Y1047900D03*
Y1051247D03*
Y1054593D03*
Y1057940D03*
Y1061286D03*
Y1064633D03*
Y1067979D03*
Y1071326D03*
Y1074672D03*
Y1078018D03*
Y1081365D03*
Y1084711D03*
Y1088058D03*
Y1091404D03*
Y1094751D03*
Y1098097D03*
Y1101444D03*
Y1104790D03*
Y1108137D03*
Y1111483D03*
Y1114829D03*
Y1118176D03*
Y1121522D03*
Y1124869D03*
Y1128215D03*
Y1131562D03*
Y1134908D03*
Y1138255D03*
Y1141601D03*
Y1144948D03*
Y1148294D03*
Y1151641D03*
Y1154987D03*
Y1158333D03*
Y1161680D03*
Y1165026D03*
Y1168373D03*
Y1171719D03*
Y1175066D03*
Y1178412D03*
Y1181759D03*
Y1185105D03*
Y1188452D03*
Y1191798D03*
Y1195144D03*
Y1198491D03*
Y1201837D03*
Y1205184D03*
Y1208530D03*
Y1211877D03*
Y1215223D03*
Y1218570D03*
Y1221916D03*
Y1225263D03*
Y1228609D03*
Y1231955D03*
Y1235302D03*
Y1238648D03*
Y1241995D03*
Y1245341D03*
Y1248688D03*
Y1252034D03*
Y1255381D03*
Y1258727D03*
Y1262074D03*
Y1265420D03*
X1690491Y766798D03*
Y770144D03*
X1676933Y766798D03*
Y770144D03*
X1690491Y773491D03*
Y776837D03*
Y780184D03*
Y783530D03*
Y786877D03*
X1676933Y773491D03*
Y776837D03*
Y780184D03*
Y783530D03*
Y786877D03*
X1690491Y790223D03*
Y793570D03*
Y796916D03*
Y800263D03*
Y803609D03*
X1676933Y790223D03*
Y793570D03*
Y796916D03*
Y800263D03*
Y803609D03*
X1690491Y806955D03*
Y810302D03*
Y813648D03*
Y816995D03*
Y820341D03*
X1676933Y806955D03*
Y810302D03*
Y813648D03*
Y816995D03*
Y820341D03*
X1690491Y823688D03*
Y827034D03*
Y830381D03*
Y833727D03*
X1676933Y823688D03*
Y827034D03*
Y830381D03*
Y833727D03*
X1690491Y837074D03*
Y840420D03*
Y843766D03*
Y847113D03*
Y850459D03*
X1676933Y837074D03*
Y840420D03*
Y843766D03*
Y847113D03*
Y850459D03*
X1690491Y853806D03*
Y857152D03*
Y860499D03*
Y863845D03*
Y867192D03*
X1676933Y853806D03*
Y857152D03*
Y860499D03*
Y863845D03*
Y867192D03*
X1690491Y870538D03*
Y873885D03*
Y877231D03*
Y880577D03*
Y883924D03*
X1676933Y870538D03*
Y873885D03*
Y877231D03*
Y880577D03*
Y883924D03*
X1690491Y887270D03*
Y890617D03*
Y893963D03*
Y897310D03*
Y900656D03*
X1676933Y887270D03*
Y890617D03*
Y893963D03*
Y897310D03*
Y900656D03*
X1690491Y904003D03*
Y907349D03*
Y910696D03*
Y914042D03*
Y917389D03*
X1676933Y904003D03*
Y907349D03*
Y910696D03*
Y914042D03*
Y917389D03*
X1690491Y920735D03*
Y924081D03*
Y927428D03*
Y930774D03*
Y934121D03*
X1676933Y920735D03*
Y924081D03*
Y927428D03*
Y930774D03*
Y934121D03*
X1690491Y937467D03*
Y940814D03*
Y944160D03*
Y947507D03*
X1676933Y937467D03*
Y940814D03*
Y944160D03*
Y947507D03*
X1690491Y950853D03*
Y954200D03*
Y957546D03*
Y960892D03*
Y964239D03*
X1676933Y950853D03*
Y954200D03*
Y957546D03*
Y960892D03*
Y964239D03*
X1690491Y967585D03*
Y970932D03*
Y974278D03*
Y977625D03*
Y980971D03*
X1676933Y967585D03*
Y970932D03*
Y974278D03*
Y977625D03*
Y980971D03*
X1690491Y984318D03*
Y987664D03*
Y991011D03*
Y994357D03*
X1676933Y984318D03*
Y987664D03*
Y991011D03*
Y994357D03*
X1690491Y1017782D03*
Y1021129D03*
Y1024475D03*
Y1027822D03*
Y1031168D03*
X1676933Y1017782D03*
Y1021129D03*
Y1024475D03*
Y1027822D03*
Y1031168D03*
X1690491Y1034515D03*
Y1037861D03*
Y1041207D03*
Y1044554D03*
Y1047900D03*
X1676933Y1034515D03*
Y1037861D03*
Y1041207D03*
Y1044554D03*
Y1047900D03*
X1690491Y1051247D03*
Y1054593D03*
Y1057940D03*
Y1061286D03*
X1676933Y1051247D03*
Y1054593D03*
Y1057940D03*
Y1061286D03*
X1690491Y1064633D03*
Y1067979D03*
Y1071326D03*
Y1074672D03*
Y1078018D03*
X1676933Y1064633D03*
Y1067979D03*
Y1071326D03*
Y1074672D03*
Y1078018D03*
X1690491Y1081365D03*
Y1084711D03*
Y1088058D03*
Y1091404D03*
Y1094751D03*
X1676933Y1081365D03*
Y1084711D03*
Y1088058D03*
Y1091404D03*
Y1094751D03*
X1690491Y1098097D03*
Y1101444D03*
Y1104790D03*
Y1108137D03*
Y1111483D03*
X1676933Y1098097D03*
Y1101444D03*
Y1104790D03*
Y1108137D03*
Y1111483D03*
X1690491Y1114829D03*
Y1118176D03*
Y1121522D03*
Y1124869D03*
Y1128215D03*
X1676933Y1114829D03*
Y1118176D03*
Y1121522D03*
Y1124869D03*
Y1128215D03*
X1690491Y1131562D03*
Y1134908D03*
Y1138255D03*
Y1141601D03*
Y1144948D03*
X1676933Y1131562D03*
Y1134908D03*
Y1138255D03*
Y1141601D03*
Y1144948D03*
X1690491Y1148294D03*
Y1151641D03*
Y1154987D03*
Y1158333D03*
Y1161680D03*
X1676933Y1148294D03*
Y1151641D03*
Y1154987D03*
Y1158333D03*
Y1161680D03*
X1690491Y1165026D03*
Y1168373D03*
Y1171719D03*
Y1175066D03*
X1676933Y1165026D03*
Y1168373D03*
Y1171719D03*
Y1175066D03*
X1690491Y1178412D03*
Y1181759D03*
Y1185105D03*
Y1188452D03*
Y1191798D03*
X1676933Y1178412D03*
Y1181759D03*
Y1185105D03*
Y1188452D03*
Y1191798D03*
X1690491Y1195144D03*
Y1198491D03*
Y1201837D03*
Y1205184D03*
Y1208530D03*
X1676933Y1195144D03*
Y1198491D03*
Y1201837D03*
Y1205184D03*
Y1208530D03*
X1690491Y1211877D03*
Y1215223D03*
Y1218570D03*
Y1221916D03*
Y1225263D03*
X1676933Y1211877D03*
Y1215223D03*
Y1218570D03*
Y1221916D03*
Y1225263D03*
X1690491Y1228609D03*
Y1231955D03*
Y1235302D03*
Y1238648D03*
Y1241995D03*
X1676933Y1228609D03*
Y1231955D03*
Y1235302D03*
Y1238648D03*
Y1241995D03*
X1690491Y1245341D03*
Y1248688D03*
Y1252034D03*
Y1255381D03*
Y1258727D03*
X1676933Y1245341D03*
Y1248688D03*
Y1252034D03*
Y1255381D03*
Y1258727D03*
X1690491Y1262074D03*
Y1265420D03*
X1676933Y1262074D03*
Y1265420D03*
X1706633Y766798D03*
Y770144D03*
Y773491D03*
Y776837D03*
Y780184D03*
Y783530D03*
Y786877D03*
Y790223D03*
Y793570D03*
Y796916D03*
Y800263D03*
Y803609D03*
Y806955D03*
Y810302D03*
Y813648D03*
Y816995D03*
Y820341D03*
Y823688D03*
Y827034D03*
Y830381D03*
Y833727D03*
Y837074D03*
Y840420D03*
Y843766D03*
Y847113D03*
Y850459D03*
Y853806D03*
Y857152D03*
Y860499D03*
Y863845D03*
Y867192D03*
Y870538D03*
Y873885D03*
Y877231D03*
Y880577D03*
Y883924D03*
Y887270D03*
Y890617D03*
Y893963D03*
Y897310D03*
Y900656D03*
Y904003D03*
Y907349D03*
Y910696D03*
Y914042D03*
Y917389D03*
Y920735D03*
Y924081D03*
Y927428D03*
Y930774D03*
Y934121D03*
Y937467D03*
Y940814D03*
Y944160D03*
Y947507D03*
Y950853D03*
Y954200D03*
Y957546D03*
Y960892D03*
Y964239D03*
Y967585D03*
Y970932D03*
Y974278D03*
Y977625D03*
Y980971D03*
Y984318D03*
Y987664D03*
Y991011D03*
Y994357D03*
Y1017782D03*
Y1021129D03*
Y1024475D03*
Y1027822D03*
Y1031168D03*
Y1034515D03*
Y1037861D03*
Y1041207D03*
Y1044554D03*
Y1047900D03*
Y1051247D03*
Y1054593D03*
Y1057940D03*
Y1061286D03*
Y1064633D03*
Y1067979D03*
Y1071326D03*
Y1074672D03*
Y1078018D03*
Y1081365D03*
Y1084711D03*
Y1088058D03*
Y1091404D03*
Y1094751D03*
Y1098097D03*
Y1101444D03*
Y1104790D03*
Y1108137D03*
Y1111483D03*
Y1114829D03*
Y1118176D03*
Y1121522D03*
Y1124869D03*
Y1128215D03*
Y1131562D03*
Y1134908D03*
Y1138255D03*
Y1141601D03*
Y1144948D03*
Y1148294D03*
Y1151641D03*
Y1154987D03*
Y1158333D03*
Y1161680D03*
Y1165026D03*
Y1168373D03*
Y1171719D03*
Y1175066D03*
Y1178412D03*
Y1181759D03*
Y1185105D03*
Y1188452D03*
Y1191798D03*
Y1195144D03*
Y1198491D03*
Y1201837D03*
Y1205184D03*
Y1208530D03*
Y1211877D03*
Y1215223D03*
Y1218570D03*
Y1221916D03*
Y1225263D03*
Y1228609D03*
Y1231955D03*
Y1235302D03*
Y1238648D03*
Y1241995D03*
Y1245341D03*
Y1248688D03*
Y1252034D03*
Y1255381D03*
Y1258727D03*
Y1262074D03*
Y1265420D03*
X1720191Y766798D03*
Y770144D03*
Y773491D03*
Y776837D03*
Y780184D03*
Y783530D03*
Y786877D03*
Y790223D03*
Y793570D03*
Y796916D03*
Y800263D03*
Y803609D03*
Y806955D03*
Y810302D03*
Y813648D03*
Y816995D03*
Y820341D03*
Y823688D03*
Y827034D03*
Y830381D03*
Y833727D03*
Y837074D03*
Y840420D03*
Y843766D03*
Y847113D03*
Y850459D03*
Y853806D03*
Y857152D03*
Y860499D03*
Y863845D03*
Y867192D03*
Y870538D03*
Y873885D03*
Y877231D03*
Y880577D03*
Y883924D03*
Y887270D03*
Y890617D03*
Y893963D03*
Y897310D03*
Y900656D03*
Y904003D03*
Y907349D03*
Y910696D03*
Y914042D03*
Y917389D03*
Y920735D03*
Y924081D03*
Y927428D03*
Y930774D03*
Y934121D03*
Y937467D03*
Y940814D03*
Y944160D03*
Y947507D03*
Y950853D03*
Y954200D03*
Y957546D03*
Y960892D03*
Y964239D03*
Y967585D03*
Y970932D03*
Y974278D03*
Y977625D03*
Y980971D03*
Y984318D03*
Y987664D03*
Y991011D03*
Y994357D03*
Y1017782D03*
Y1021129D03*
Y1024475D03*
Y1027822D03*
Y1031168D03*
Y1034515D03*
Y1037861D03*
Y1041207D03*
Y1044554D03*
Y1047900D03*
Y1051247D03*
Y1054593D03*
Y1057940D03*
Y1061286D03*
Y1064633D03*
Y1067979D03*
Y1071326D03*
Y1074672D03*
Y1078018D03*
Y1081365D03*
Y1084711D03*
Y1088058D03*
Y1091404D03*
Y1094751D03*
Y1098097D03*
Y1101444D03*
Y1104790D03*
Y1108137D03*
Y1111483D03*
Y1114829D03*
Y1118176D03*
Y1121522D03*
Y1124869D03*
Y1128215D03*
Y1131562D03*
Y1134908D03*
Y1138255D03*
Y1141601D03*
Y1144948D03*
Y1148294D03*
Y1151641D03*
Y1154987D03*
Y1158333D03*
Y1161680D03*
Y1165026D03*
Y1168373D03*
Y1171719D03*
Y1175066D03*
Y1178412D03*
Y1181759D03*
Y1185105D03*
Y1188452D03*
Y1191798D03*
Y1195144D03*
Y1198491D03*
Y1201837D03*
Y1205184D03*
Y1208530D03*
Y1211877D03*
Y1215223D03*
Y1218570D03*
Y1221916D03*
Y1225263D03*
Y1228609D03*
Y1231955D03*
Y1235302D03*
Y1238648D03*
Y1241995D03*
Y1245341D03*
Y1248688D03*
Y1252034D03*
Y1255381D03*
Y1258727D03*
Y1262074D03*
Y1265420D03*
X1736333Y766798D03*
Y770144D03*
Y773491D03*
Y776837D03*
Y780184D03*
Y783530D03*
Y786877D03*
Y790223D03*
Y793570D03*
Y796916D03*
Y800263D03*
Y803609D03*
Y806955D03*
Y810302D03*
Y813648D03*
Y816995D03*
Y820341D03*
Y823688D03*
Y827034D03*
Y830381D03*
Y833727D03*
Y837074D03*
Y840420D03*
Y843766D03*
Y847113D03*
Y850459D03*
Y853806D03*
Y857152D03*
Y860499D03*
Y863845D03*
Y867192D03*
Y870538D03*
Y873885D03*
Y877231D03*
Y880577D03*
Y883924D03*
Y887270D03*
Y890617D03*
Y893963D03*
Y897310D03*
Y900656D03*
Y904003D03*
Y907349D03*
Y910696D03*
Y914042D03*
Y917389D03*
Y920735D03*
Y924081D03*
Y927428D03*
Y930774D03*
Y934121D03*
Y937467D03*
Y940814D03*
Y944160D03*
Y947507D03*
Y950853D03*
Y954200D03*
Y957546D03*
Y960892D03*
Y964239D03*
Y967585D03*
Y970932D03*
Y974278D03*
Y977625D03*
Y980971D03*
Y984318D03*
Y987664D03*
Y991011D03*
Y994357D03*
Y1017782D03*
Y1021129D03*
Y1024475D03*
Y1027822D03*
Y1031168D03*
Y1034515D03*
Y1037861D03*
Y1041207D03*
Y1044554D03*
Y1047900D03*
Y1051247D03*
Y1054593D03*
Y1057940D03*
Y1061286D03*
Y1064633D03*
Y1067979D03*
Y1071326D03*
Y1074672D03*
Y1078018D03*
Y1081365D03*
Y1084711D03*
Y1088058D03*
Y1091404D03*
Y1094751D03*
Y1098097D03*
Y1101444D03*
Y1104790D03*
Y1108137D03*
Y1111483D03*
Y1114829D03*
Y1118176D03*
Y1121522D03*
Y1124869D03*
Y1128215D03*
Y1131562D03*
Y1134908D03*
Y1138255D03*
Y1141601D03*
Y1144948D03*
Y1148294D03*
Y1151641D03*
Y1154987D03*
Y1158333D03*
Y1161680D03*
Y1165026D03*
Y1168373D03*
Y1171719D03*
Y1175066D03*
Y1178412D03*
Y1181759D03*
Y1185105D03*
Y1188452D03*
Y1191798D03*
Y1195144D03*
Y1198491D03*
Y1201837D03*
Y1205184D03*
Y1208530D03*
Y1211877D03*
Y1215223D03*
Y1218570D03*
Y1221916D03*
Y1225263D03*
Y1228609D03*
Y1231955D03*
Y1235302D03*
Y1238648D03*
Y1241995D03*
Y1245341D03*
Y1248688D03*
Y1252034D03*
Y1255381D03*
Y1258727D03*
Y1262074D03*
Y1265420D03*
X1749891Y766798D03*
Y770144D03*
Y773491D03*
Y776837D03*
Y780184D03*
Y783530D03*
Y786877D03*
Y790223D03*
Y793570D03*
Y796916D03*
Y800263D03*
Y803609D03*
Y806955D03*
Y810302D03*
Y813648D03*
Y816995D03*
Y820341D03*
Y823688D03*
Y827034D03*
Y830381D03*
Y833727D03*
Y837074D03*
Y840420D03*
Y843766D03*
Y847113D03*
Y850459D03*
Y853806D03*
Y857152D03*
Y860499D03*
Y863845D03*
Y867192D03*
Y870538D03*
Y873885D03*
Y877231D03*
Y880577D03*
Y883924D03*
Y887270D03*
Y890617D03*
Y893963D03*
Y897310D03*
Y900656D03*
Y904003D03*
Y907349D03*
Y910696D03*
Y914042D03*
Y917389D03*
Y920735D03*
Y924081D03*
Y927428D03*
Y930774D03*
Y934121D03*
Y937467D03*
Y940814D03*
Y944160D03*
Y947507D03*
Y950853D03*
Y954200D03*
Y957546D03*
Y960892D03*
Y964239D03*
Y967585D03*
Y970932D03*
Y974278D03*
Y977625D03*
Y980971D03*
Y984318D03*
Y987664D03*
Y991011D03*
Y994357D03*
Y1017782D03*
Y1021129D03*
Y1024475D03*
Y1027822D03*
Y1031168D03*
Y1034515D03*
Y1037861D03*
Y1041207D03*
Y1044554D03*
Y1047900D03*
Y1051247D03*
Y1054593D03*
Y1057940D03*
Y1061286D03*
Y1064633D03*
Y1067979D03*
Y1071326D03*
Y1074672D03*
Y1078018D03*
Y1081365D03*
Y1084711D03*
Y1088058D03*
Y1091404D03*
Y1094751D03*
Y1098097D03*
Y1101444D03*
Y1104790D03*
Y1108137D03*
Y1111483D03*
Y1114829D03*
Y1118176D03*
Y1121522D03*
Y1124869D03*
Y1128215D03*
Y1131562D03*
Y1134908D03*
Y1138255D03*
Y1141601D03*
Y1144948D03*
Y1148294D03*
Y1151641D03*
Y1154987D03*
Y1158333D03*
Y1161680D03*
Y1165026D03*
Y1168373D03*
Y1171719D03*
Y1175066D03*
Y1178412D03*
Y1181759D03*
Y1185105D03*
Y1188452D03*
Y1191798D03*
Y1195144D03*
Y1198491D03*
Y1201837D03*
Y1205184D03*
Y1208530D03*
Y1211877D03*
Y1215223D03*
Y1218570D03*
Y1221916D03*
Y1225263D03*
Y1228609D03*
Y1231955D03*
Y1235302D03*
Y1238648D03*
Y1241995D03*
Y1245341D03*
Y1248688D03*
Y1252034D03*
Y1255381D03*
Y1258727D03*
Y1262074D03*
Y1265420D03*
X1766033Y766798D03*
Y770144D03*
Y773491D03*
Y776837D03*
Y780184D03*
Y783530D03*
Y786877D03*
Y790223D03*
Y793570D03*
Y796916D03*
Y800263D03*
Y803609D03*
Y806955D03*
Y810302D03*
Y813648D03*
Y816995D03*
Y820341D03*
Y823688D03*
Y827034D03*
Y830381D03*
Y833727D03*
Y837074D03*
Y840420D03*
Y843766D03*
Y847113D03*
Y850459D03*
Y853806D03*
Y857152D03*
Y860499D03*
Y863845D03*
Y867192D03*
Y870538D03*
Y873885D03*
Y877231D03*
Y880577D03*
Y883924D03*
Y887270D03*
Y890617D03*
Y893963D03*
Y897310D03*
Y900656D03*
Y904003D03*
Y907349D03*
Y910696D03*
Y914042D03*
Y917389D03*
Y920735D03*
Y924081D03*
Y927428D03*
Y930774D03*
Y934121D03*
Y937467D03*
Y940814D03*
Y944160D03*
Y947507D03*
Y950853D03*
Y954200D03*
Y957546D03*
Y960892D03*
Y964239D03*
Y967585D03*
Y970932D03*
Y974278D03*
Y977625D03*
Y980971D03*
Y984318D03*
Y987664D03*
Y991011D03*
Y994357D03*
Y1017782D03*
Y1021129D03*
Y1024475D03*
Y1027822D03*
Y1031168D03*
Y1034515D03*
Y1037861D03*
Y1041207D03*
Y1044554D03*
Y1047900D03*
Y1051247D03*
Y1054593D03*
Y1057940D03*
Y1061286D03*
Y1064633D03*
Y1067979D03*
Y1071326D03*
Y1074672D03*
Y1078018D03*
Y1081365D03*
Y1084711D03*
Y1088058D03*
Y1091404D03*
Y1094751D03*
Y1098097D03*
Y1101444D03*
Y1104790D03*
Y1108137D03*
Y1111483D03*
Y1114829D03*
Y1118176D03*
Y1121522D03*
Y1124869D03*
Y1128215D03*
Y1131562D03*
Y1134908D03*
Y1138255D03*
Y1141601D03*
Y1144948D03*
Y1148294D03*
Y1151641D03*
Y1154987D03*
Y1158333D03*
Y1161680D03*
Y1165026D03*
Y1168373D03*
Y1171719D03*
Y1175066D03*
Y1178412D03*
Y1181759D03*
Y1185105D03*
Y1188452D03*
Y1191798D03*
Y1195144D03*
Y1198491D03*
Y1201837D03*
Y1205184D03*
Y1208530D03*
Y1211877D03*
Y1215223D03*
Y1218570D03*
Y1221916D03*
Y1225263D03*
Y1228609D03*
Y1231955D03*
Y1235302D03*
Y1238648D03*
Y1241995D03*
Y1245341D03*
Y1248688D03*
Y1252034D03*
Y1255381D03*
Y1258727D03*
Y1262074D03*
Y1265420D03*
X1779591Y766798D03*
Y770144D03*
Y773491D03*
Y776837D03*
Y780184D03*
Y783530D03*
Y786877D03*
Y790223D03*
Y793570D03*
Y796916D03*
Y800263D03*
Y803609D03*
Y806955D03*
Y810302D03*
Y813648D03*
Y816995D03*
Y820341D03*
Y823688D03*
Y827034D03*
Y830381D03*
Y833727D03*
Y837074D03*
Y840420D03*
Y843766D03*
Y847113D03*
Y850459D03*
Y853806D03*
Y857152D03*
Y860499D03*
Y863845D03*
Y867192D03*
Y870538D03*
Y873885D03*
Y877231D03*
Y880577D03*
Y883924D03*
Y887270D03*
Y890617D03*
Y893963D03*
Y897310D03*
Y900656D03*
Y904003D03*
Y907349D03*
Y910696D03*
Y914042D03*
Y917389D03*
Y920735D03*
Y924081D03*
Y927428D03*
Y930774D03*
Y934121D03*
Y937467D03*
Y940814D03*
Y944160D03*
Y947507D03*
Y950853D03*
Y954200D03*
Y957546D03*
Y960892D03*
Y964239D03*
Y967585D03*
Y970932D03*
Y974278D03*
Y977625D03*
Y980971D03*
Y984318D03*
Y987664D03*
Y991011D03*
Y994357D03*
Y1017782D03*
Y1021129D03*
Y1024475D03*
Y1027822D03*
Y1031168D03*
Y1034515D03*
Y1037861D03*
Y1041207D03*
Y1044554D03*
Y1047900D03*
Y1051247D03*
Y1054593D03*
Y1057940D03*
Y1061286D03*
Y1064633D03*
Y1067979D03*
Y1071326D03*
Y1074672D03*
Y1078018D03*
Y1081365D03*
Y1084711D03*
Y1088058D03*
Y1091404D03*
Y1094751D03*
Y1098097D03*
Y1101444D03*
Y1104790D03*
Y1108137D03*
Y1111483D03*
Y1114829D03*
Y1118176D03*
Y1121522D03*
Y1124869D03*
Y1128215D03*
Y1131562D03*
Y1134908D03*
Y1138255D03*
Y1141601D03*
Y1144948D03*
Y1148294D03*
Y1151641D03*
Y1154987D03*
Y1158333D03*
Y1161680D03*
Y1165026D03*
Y1168373D03*
Y1171719D03*
Y1175066D03*
Y1178412D03*
Y1181759D03*
Y1185105D03*
Y1188452D03*
Y1191798D03*
Y1195144D03*
Y1198491D03*
Y1201837D03*
Y1205184D03*
Y1208530D03*
Y1211877D03*
Y1215223D03*
Y1218570D03*
Y1221916D03*
Y1225263D03*
Y1228609D03*
Y1231955D03*
Y1235302D03*
Y1238648D03*
Y1241995D03*
Y1245341D03*
Y1248688D03*
Y1252034D03*
Y1255381D03*
Y1258727D03*
Y1262074D03*
Y1265420D03*
X1795733Y766798D03*
Y770144D03*
Y773491D03*
Y776837D03*
Y780184D03*
Y783530D03*
Y786877D03*
Y790223D03*
Y793570D03*
Y796916D03*
Y800263D03*
Y803609D03*
Y806955D03*
Y810302D03*
Y813648D03*
Y816995D03*
Y820341D03*
Y823688D03*
Y827034D03*
Y830381D03*
Y833727D03*
Y837074D03*
Y840420D03*
Y843766D03*
Y847113D03*
Y850459D03*
Y853806D03*
Y857152D03*
Y860499D03*
Y863845D03*
Y867192D03*
Y870538D03*
Y873885D03*
Y877231D03*
Y880577D03*
Y883924D03*
Y887270D03*
Y890617D03*
Y893963D03*
Y897310D03*
Y900656D03*
Y904003D03*
Y907349D03*
Y910696D03*
Y914042D03*
Y917389D03*
Y920735D03*
Y924081D03*
Y927428D03*
Y930774D03*
Y934121D03*
Y937467D03*
Y940814D03*
Y944160D03*
Y947507D03*
Y950853D03*
Y954200D03*
Y957546D03*
Y960892D03*
Y964239D03*
Y967585D03*
Y970932D03*
Y974278D03*
Y977625D03*
Y980971D03*
Y984318D03*
Y987664D03*
Y991011D03*
Y994357D03*
Y1017782D03*
Y1021129D03*
Y1024475D03*
Y1027822D03*
Y1031168D03*
Y1034515D03*
Y1037861D03*
Y1041207D03*
Y1044554D03*
Y1047900D03*
Y1051247D03*
Y1054593D03*
Y1057940D03*
Y1061286D03*
Y1064633D03*
Y1067979D03*
Y1071326D03*
Y1074672D03*
Y1078018D03*
Y1081365D03*
Y1084711D03*
Y1088058D03*
Y1091404D03*
Y1094751D03*
Y1098097D03*
Y1101444D03*
Y1104790D03*
Y1108137D03*
Y1111483D03*
Y1114829D03*
Y1118176D03*
Y1121522D03*
Y1124869D03*
Y1128215D03*
Y1131562D03*
Y1134908D03*
Y1138255D03*
Y1141601D03*
Y1144948D03*
Y1148294D03*
Y1151641D03*
Y1154987D03*
Y1158333D03*
Y1161680D03*
Y1165026D03*
Y1168373D03*
Y1171719D03*
Y1175066D03*
Y1178412D03*
Y1181759D03*
Y1185105D03*
Y1188452D03*
Y1191798D03*
Y1195144D03*
Y1198491D03*
Y1201837D03*
Y1205184D03*
Y1208530D03*
Y1211877D03*
Y1215223D03*
Y1218570D03*
Y1221916D03*
Y1225263D03*
Y1228609D03*
Y1231955D03*
Y1235302D03*
Y1238648D03*
Y1241995D03*
Y1245341D03*
Y1248688D03*
Y1252034D03*
Y1255381D03*
Y1258727D03*
Y1262074D03*
Y1265420D03*
X1809291Y766798D03*
Y770144D03*
Y773491D03*
Y776837D03*
Y780184D03*
Y783530D03*
Y786877D03*
Y790223D03*
Y793570D03*
Y796916D03*
Y800263D03*
Y803609D03*
Y806955D03*
Y810302D03*
Y813648D03*
Y816995D03*
Y820341D03*
Y823688D03*
Y827034D03*
Y830381D03*
Y833727D03*
Y837074D03*
Y840420D03*
Y843766D03*
Y847113D03*
Y850459D03*
Y853806D03*
Y857152D03*
Y860499D03*
Y863845D03*
Y867192D03*
Y870538D03*
Y873885D03*
Y877231D03*
Y880577D03*
Y883924D03*
Y887270D03*
Y890617D03*
Y893963D03*
Y897310D03*
Y900656D03*
Y904003D03*
Y907349D03*
Y910696D03*
Y914042D03*
Y917389D03*
Y920735D03*
Y924081D03*
Y927428D03*
Y930774D03*
Y934121D03*
Y937467D03*
Y940814D03*
Y944160D03*
Y947507D03*
Y950853D03*
Y954200D03*
Y957546D03*
Y960892D03*
Y964239D03*
Y967585D03*
Y970932D03*
Y974278D03*
Y977625D03*
Y980971D03*
Y984318D03*
Y987664D03*
Y991011D03*
Y994357D03*
Y1017782D03*
Y1021129D03*
Y1024475D03*
Y1027822D03*
Y1031168D03*
Y1034515D03*
Y1037861D03*
Y1041207D03*
Y1044554D03*
Y1047900D03*
Y1051247D03*
Y1054593D03*
Y1057940D03*
Y1061286D03*
Y1064633D03*
Y1067979D03*
Y1071326D03*
Y1074672D03*
Y1078018D03*
Y1081365D03*
Y1084711D03*
Y1088058D03*
Y1091404D03*
Y1094751D03*
Y1098097D03*
Y1101444D03*
Y1104790D03*
Y1108137D03*
Y1111483D03*
Y1114829D03*
Y1118176D03*
Y1121522D03*
Y1124869D03*
Y1128215D03*
Y1131562D03*
Y1134908D03*
Y1138255D03*
Y1141601D03*
Y1144948D03*
Y1148294D03*
Y1151641D03*
Y1154987D03*
Y1158333D03*
Y1161680D03*
Y1165026D03*
Y1168373D03*
Y1171719D03*
Y1175066D03*
Y1178412D03*
Y1181759D03*
Y1185105D03*
Y1188452D03*
Y1191798D03*
Y1195144D03*
Y1198491D03*
Y1201837D03*
Y1205184D03*
Y1208530D03*
Y1211877D03*
Y1215223D03*
Y1218570D03*
Y1221916D03*
Y1225263D03*
Y1228609D03*
Y1231955D03*
Y1235302D03*
Y1238648D03*
Y1241995D03*
Y1245341D03*
Y1248688D03*
Y1252034D03*
Y1255381D03*
Y1258727D03*
Y1262074D03*
Y1265420D03*
X1825433Y766798D03*
Y770144D03*
Y773491D03*
Y776837D03*
Y780184D03*
Y783530D03*
Y786877D03*
Y790223D03*
Y793570D03*
Y796916D03*
Y800263D03*
Y803609D03*
Y806955D03*
Y810302D03*
Y813648D03*
Y816995D03*
Y820341D03*
Y823688D03*
Y827034D03*
Y830381D03*
Y833727D03*
Y837074D03*
Y840420D03*
Y843766D03*
Y847113D03*
Y850459D03*
Y853806D03*
Y857152D03*
Y860499D03*
Y863845D03*
Y867192D03*
Y870538D03*
Y873885D03*
Y877231D03*
Y880577D03*
Y883924D03*
Y887270D03*
Y890617D03*
Y893963D03*
Y897310D03*
Y900656D03*
Y904003D03*
Y907349D03*
Y910696D03*
Y914042D03*
Y917389D03*
Y920735D03*
Y924081D03*
Y927428D03*
Y930774D03*
Y934121D03*
Y937467D03*
Y940814D03*
Y944160D03*
Y947507D03*
Y950853D03*
Y954200D03*
Y957546D03*
Y960892D03*
Y964239D03*
Y967585D03*
Y970932D03*
Y974278D03*
Y977625D03*
Y980971D03*
Y984318D03*
Y987664D03*
Y991011D03*
Y994357D03*
Y1017782D03*
Y1021129D03*
Y1024475D03*
Y1027822D03*
Y1031168D03*
Y1034515D03*
Y1037861D03*
Y1041207D03*
Y1044554D03*
Y1047900D03*
Y1051247D03*
Y1054593D03*
Y1057940D03*
Y1061286D03*
Y1064633D03*
Y1067979D03*
Y1071326D03*
Y1074672D03*
Y1078018D03*
Y1081365D03*
Y1084711D03*
Y1088058D03*
Y1091404D03*
Y1094751D03*
Y1098097D03*
Y1101444D03*
Y1104790D03*
Y1108137D03*
Y1111483D03*
Y1114829D03*
Y1118176D03*
Y1121522D03*
Y1124869D03*
Y1128215D03*
Y1131562D03*
Y1134908D03*
Y1138255D03*
Y1141601D03*
Y1144948D03*
Y1148294D03*
Y1151641D03*
Y1154987D03*
Y1158333D03*
Y1161680D03*
Y1165026D03*
Y1168373D03*
Y1171719D03*
Y1175066D03*
Y1178412D03*
Y1181759D03*
Y1185105D03*
Y1188452D03*
Y1191798D03*
Y1195144D03*
Y1198491D03*
Y1201837D03*
Y1205184D03*
Y1208530D03*
Y1211877D03*
Y1215223D03*
Y1218570D03*
Y1221916D03*
Y1225263D03*
Y1228609D03*
Y1231955D03*
Y1235302D03*
Y1238648D03*
Y1241995D03*
Y1245341D03*
Y1248688D03*
Y1252034D03*
Y1255381D03*
Y1258727D03*
Y1262074D03*
Y1265420D03*
G54D72*
X108909Y648926D03*
X126225Y510368D03*
X1676004Y537065D03*
X1702760Y484207D03*
G54D156*
X441990Y1627592D03*
G54D36*
X65933Y32756D03*
X68295D03*
X70657D03*
X73020D03*
X75382D03*
X77744D03*
X65933Y44370D03*
X68295D03*
X70657D03*
X73020D03*
X75382D03*
X77744D03*
X80106Y32756D03*
X82468D03*
X84831D03*
X87193D03*
X89555D03*
X91917D03*
X94279D03*
X80106Y44370D03*
X82468D03*
X84831D03*
X87193D03*
X89555D03*
X91917D03*
X94279D03*
X96642Y32756D03*
X99004D03*
X101366D03*
X103728D03*
X106090D03*
X108453D03*
X110815D03*
X96642Y44370D03*
X99004D03*
X101366D03*
X103728D03*
X106090D03*
X108453D03*
X110815D03*
X113177Y32756D03*
X115539D03*
X117902D03*
X120264D03*
X122626D03*
X124988D03*
X127350D03*
X113177Y44370D03*
X115539D03*
X117902D03*
X120264D03*
X122626D03*
X124988D03*
X127350D03*
X129713Y32756D03*
Y44370D03*
X149043Y32756D03*
X151405D03*
X153768D03*
X156130D03*
X158492D03*
X149043Y44370D03*
X151405D03*
X153768D03*
X156130D03*
X158492D03*
X160854Y32756D03*
X163216D03*
X165579D03*
X167941D03*
X170303D03*
X172665D03*
X175028D03*
X160854Y44370D03*
X163216D03*
X165579D03*
X167941D03*
X170303D03*
X172665D03*
X175028D03*
X177390Y32756D03*
X179752D03*
X177390Y44370D03*
X179752D03*
X195539Y32756D03*
X197902D03*
X200264D03*
X202626D03*
X204988D03*
X207350D03*
X195539Y44370D03*
X197902D03*
X200264D03*
X202626D03*
X204988D03*
X207350D03*
X209713Y32756D03*
X212075D03*
X214437D03*
X216799D03*
X219161D03*
X221524D03*
X223886D03*
X209713Y44370D03*
X212075D03*
X214437D03*
X216799D03*
X219161D03*
X221524D03*
X223886D03*
X226248Y32756D03*
X228610D03*
X230972D03*
X233335D03*
X235697D03*
X238059D03*
X240421D03*
X226248Y44370D03*
X228610D03*
X230972D03*
X233335D03*
X235697D03*
X238059D03*
X240421D03*
X242783Y32756D03*
X245146D03*
X247508D03*
X249870D03*
X252232D03*
X254594D03*
X256957D03*
X242783Y44370D03*
X245146D03*
X247508D03*
X249870D03*
X252232D03*
X254594D03*
X256957D03*
X259319Y32756D03*
Y44370D03*
X276622Y32756D03*
X278984D03*
X281346D03*
X283709D03*
X286071D03*
X288433D03*
X276622Y44370D03*
X278984D03*
X281346D03*
X283709D03*
X286071D03*
X288433D03*
X290795Y32756D03*
X293157D03*
X295520D03*
X297882D03*
X300244D03*
X302606D03*
X304968D03*
X290795Y44370D03*
X293157D03*
X295520D03*
X297882D03*
X300244D03*
X302606D03*
X304968D03*
X307331Y32756D03*
Y44370D03*
X510815Y53544D03*
X513177D03*
X515539D03*
X510815Y65158D03*
X513177D03*
X515539D03*
X517902Y53544D03*
X520264D03*
X522626D03*
X524988D03*
X527350D03*
X529713D03*
X532075D03*
X517902Y65158D03*
X520264D03*
X522626D03*
X524988D03*
X527350D03*
X529713D03*
X532075D03*
X534437Y53544D03*
X536799D03*
X539161D03*
X541524D03*
X543886D03*
X546248D03*
X548610D03*
X534437Y65158D03*
X536799D03*
X539161D03*
X541524D03*
X543886D03*
X546248D03*
X548610D03*
X550972Y53544D03*
X553335D03*
X555697D03*
X558059D03*
X560421D03*
X562784D03*
X565146D03*
X550972Y65158D03*
X553335D03*
X555697D03*
X558059D03*
X560421D03*
X562784D03*
X565146D03*
X567508Y53544D03*
X569870D03*
X572232D03*
X574595D03*
X567508Y65158D03*
X569870D03*
X572232D03*
X574595D03*
X593925Y53544D03*
X596287D03*
X598650D03*
X593925Y65158D03*
X596287D03*
X598650D03*
X601012Y53544D03*
X603374D03*
X605736D03*
X608098D03*
X610461D03*
X612823D03*
X615185D03*
X601012Y65158D03*
X603374D03*
X605736D03*
X608098D03*
X610461D03*
X612823D03*
X615185D03*
X617547Y53544D03*
X619910D03*
X622272D03*
X624634D03*
X617547Y65158D03*
X619910D03*
X622272D03*
X624634D03*
X640421Y53544D03*
X642784D03*
X645146D03*
X647508D03*
X640421Y65158D03*
X642784D03*
X645146D03*
X647508D03*
X649870Y53544D03*
X652232D03*
X654595D03*
X656957D03*
X659319D03*
X661681D03*
X664043D03*
X649870Y65158D03*
X652232D03*
X654595D03*
X656957D03*
X659319D03*
X661681D03*
X664043D03*
X666406Y53544D03*
X668768D03*
X671130D03*
X673492D03*
X675854D03*
X678217D03*
X666406Y65158D03*
X668768D03*
X671130D03*
X673492D03*
X675854D03*
X678217D03*
X680579Y53544D03*
X682941D03*
X685303D03*
X687665D03*
X690028D03*
X692390D03*
X694752D03*
X680579Y65158D03*
X682941D03*
X685303D03*
X687665D03*
X690028D03*
X692390D03*
X694752D03*
X697114Y53544D03*
X699476D03*
X701839D03*
X704201D03*
X697114Y65158D03*
X699476D03*
X701839D03*
X704201D03*
X721504Y53544D03*
X723866D03*
X726228D03*
X728591D03*
X721504Y65158D03*
X723866D03*
X726228D03*
X728591D03*
X730953Y53544D03*
X733315D03*
X735677D03*
X738039D03*
X740402D03*
X742764D03*
X745126D03*
X730953Y65158D03*
X733315D03*
X735677D03*
X738039D03*
X740402D03*
X742764D03*
X745126D03*
X747488Y53544D03*
X749850D03*
X752213D03*
X747488Y65158D03*
X749850D03*
X752213D03*
X1540342Y32756D03*
Y44370D03*
X1542704Y32756D03*
X1545066D03*
X1547429D03*
X1549791D03*
X1552153D03*
X1554515D03*
X1556877D03*
X1542704Y44370D03*
X1545066D03*
X1547429D03*
X1549791D03*
X1552153D03*
X1554515D03*
X1556877D03*
X1559240Y32756D03*
X1561602D03*
X1563964D03*
X1566326D03*
X1568688D03*
X1571051D03*
X1573413D03*
X1559240Y44370D03*
X1561602D03*
X1563964D03*
X1566326D03*
X1568688D03*
X1571051D03*
X1573413D03*
X1575775Y32756D03*
X1578137D03*
X1580499D03*
X1582862D03*
X1585224D03*
X1587586D03*
X1589948D03*
X1575775Y44370D03*
X1578137D03*
X1580499D03*
X1582862D03*
X1585224D03*
X1587586D03*
X1589948D03*
X1592311Y32756D03*
X1594673D03*
X1597035D03*
X1599397D03*
X1601759D03*
X1604122D03*
X1592311Y44370D03*
X1594673D03*
X1597035D03*
X1599397D03*
X1601759D03*
X1604122D03*
X1623452Y32756D03*
Y44370D03*
X1625814Y32756D03*
X1628177D03*
X1630539D03*
X1632901D03*
X1635263D03*
X1637625D03*
X1639988D03*
X1625814Y44370D03*
X1628177D03*
X1630539D03*
X1632901D03*
X1635263D03*
X1637625D03*
X1639988D03*
X1642350Y32756D03*
X1644712D03*
X1647074D03*
X1649437D03*
X1651799D03*
X1654161D03*
X1642350Y44370D03*
X1644712D03*
X1647074D03*
X1649437D03*
X1651799D03*
X1654161D03*
X1669948Y32756D03*
X1672311D03*
X1669948Y44370D03*
X1672311D03*
X1674673Y32756D03*
X1677035D03*
X1679397D03*
X1681759D03*
X1684122D03*
X1686484D03*
X1688846D03*
X1674673Y44370D03*
X1677035D03*
X1679397D03*
X1681759D03*
X1684122D03*
X1686484D03*
X1688846D03*
X1691208Y32756D03*
X1693570D03*
X1695933D03*
X1698295D03*
X1700657D03*
X1703019D03*
X1691208Y44370D03*
X1693570D03*
X1695933D03*
X1698295D03*
X1700657D03*
X1703019D03*
X1705381Y32756D03*
X1707744D03*
X1710106D03*
X1712468D03*
X1714830D03*
X1717192D03*
X1719555D03*
X1705381Y44370D03*
X1707744D03*
X1710106D03*
X1712468D03*
X1714830D03*
X1717192D03*
X1719555D03*
X1721917Y32756D03*
X1724279D03*
X1726641D03*
X1729003D03*
X1731366D03*
X1733728D03*
X1721917Y44370D03*
X1724279D03*
X1726641D03*
X1729003D03*
X1731366D03*
X1733728D03*
X1751031Y32756D03*
X1753393D03*
X1751031Y44370D03*
X1753393D03*
X1755755Y32756D03*
X1758118D03*
X1760480D03*
X1762842D03*
X1765204D03*
X1767566D03*
X1769929D03*
X1755755Y44370D03*
X1758118D03*
X1760480D03*
X1762842D03*
X1765204D03*
X1767566D03*
X1769929D03*
X1772291Y32756D03*
X1774653D03*
X1777015D03*
X1779377D03*
X1781740D03*
X1772291Y44370D03*
X1774653D03*
X1777015D03*
X1779377D03*
X1781740D03*
G54D228*
X1025215Y282445D03*
X1035451Y280083D03*
Y282445D03*
X1797432Y1517261D03*
Y1514899D03*
X1807668D03*
G54D129*
X322500Y1391830D03*
X537477Y1395413D03*
X1133779Y1653543D03*
X1298642Y1391830D03*
X1513618Y1395413D03*
G54D54*
X84430Y1311831D03*
Y1333091D03*
X1093936Y1593314D03*
Y1614574D03*
X1769097Y1310081D03*
Y1331341D03*
G54D174*
X542554Y465696D03*
Y468255D03*
Y470814D03*
Y473373D03*
Y475932D03*
Y478492D03*
Y481051D03*
Y483610D03*
Y486169D03*
Y488728D03*
X565586Y478492D03*
Y475932D03*
Y473373D03*
Y470814D03*
Y468255D03*
Y465696D03*
Y488728D03*
Y486169D03*
Y483610D03*
Y481051D03*
X1790546Y441108D03*
Y443667D03*
Y446226D03*
Y448785D03*
Y451344D03*
Y453904D03*
Y456463D03*
Y459022D03*
Y461581D03*
Y464140D03*
X1813578Y443667D03*
Y441108D03*
Y461581D03*
Y459022D03*
Y456463D03*
Y453904D03*
Y451344D03*
Y448785D03*
Y446226D03*
Y464140D03*
G54D18*
X25981Y387783D03*
Y394475D03*
X31099D03*
Y387783D03*
X593299Y152575D03*
Y145883D03*
X588181D03*
Y152575D03*
G54D147*
X417052Y234167D03*
X409178D03*
X417052Y239285D03*
Y236726D03*
X409178D03*
Y239285D03*
X531523Y129243D03*
Y131802D03*
Y134361D03*
Y147243D03*
Y149802D03*
Y152361D03*
X530978Y162167D03*
Y164726D03*
Y167285D03*
X539397Y134361D03*
Y131802D03*
Y129243D03*
Y152361D03*
Y149802D03*
Y147243D03*
X538852Y167285D03*
Y164726D03*
Y162167D03*
X579247Y133101D03*
Y130542D03*
Y127983D03*
X571373D03*
Y130542D03*
Y133101D03*
X577147Y147291D03*
Y144732D03*
Y142173D03*
X569273D03*
Y144732D03*
Y147291D03*
G54D237*
X1109429Y364235D03*
Y369235D03*
Y374235D03*
Y379235D03*
X1129901Y364235D03*
Y379235D03*
Y374235D03*
Y369235D03*
G54D138*
X370890Y1627042D03*
X368331D03*
Y1634522D03*
X370890D03*
X373449Y1627042D03*
Y1634522D03*
X380668Y1664844D03*
X378109D03*
X375550D03*
Y1672324D03*
X378109D03*
X380668D03*
X448079Y1552197D03*
X445520D03*
X442961D03*
Y1559677D03*
X445520D03*
X448079D03*
X462079Y1562197D03*
X459520D03*
X456961D03*
Y1569677D03*
X459520D03*
X462079D03*
X459779Y1599255D03*
X457220D03*
X454661D03*
Y1606735D03*
X457220D03*
X459779D03*
X600351Y472248D03*
X602910D03*
X605469D03*
Y464768D03*
X602910D03*
X600351D03*
X656877Y504277D03*
X654318D03*
X651759D03*
Y511757D03*
X654318D03*
X656877D03*
X1150704Y222677D03*
Y230157D03*
X1158382Y197407D03*
X1155823D03*
X1153264D03*
Y204887D03*
X1155823D03*
X1158382D03*
X1155822Y222677D03*
X1153263D03*
Y230157D03*
X1155822D03*
X1163789Y1665575D03*
X1161230D03*
X1158671D03*
Y1673055D03*
X1161230D03*
X1163789D03*
X1183230Y1665575D03*
X1180671D03*
X1174789D03*
X1172230D03*
X1169671D03*
X1180671Y1673055D03*
X1183230D03*
X1169671D03*
X1172230D03*
X1174789D03*
X1196459Y1665885D03*
X1193900D03*
X1191341D03*
X1185789Y1665575D03*
X1191341Y1673365D03*
X1193900D03*
X1196459D03*
X1185789Y1673055D03*
X1196199Y1711365D03*
X1193640D03*
X1191081D03*
Y1718845D03*
X1193640D03*
X1196199D03*
X1215210Y1711675D03*
X1212651D03*
X1206969Y1711410D03*
X1204410D03*
X1201851D03*
X1212651Y1719155D03*
X1215210D03*
X1201851Y1718890D03*
X1204410D03*
X1206969D03*
X1217769Y1711675D03*
Y1719155D03*
G54D192*
X761223Y271354D03*
Y273322D03*
Y275290D03*
X769097D03*
Y273322D03*
Y271354D03*
X1509488Y297812D03*
Y301748D03*
G54D264*
X1543444Y195866D03*
Y197834D03*
Y199803D03*
Y201771D03*
Y203740D03*
Y205708D03*
Y207677D03*
Y209645D03*
Y211614D03*
Y213582D03*
Y215551D03*
Y217519D03*
Y219488D03*
Y221456D03*
Y223425D03*
Y225393D03*
Y227362D03*
Y229330D03*
Y231299D03*
Y233267D03*
Y235236D03*
Y237204D03*
Y239173D03*
Y241141D03*
Y243110D03*
Y245078D03*
Y247047D03*
Y249015D03*
Y250984D03*
Y252952D03*
X1566004Y195866D03*
Y197834D03*
Y199803D03*
Y201771D03*
Y203740D03*
Y205708D03*
Y207677D03*
Y209645D03*
Y211614D03*
Y213582D03*
Y215551D03*
Y217519D03*
Y219488D03*
Y221456D03*
Y223425D03*
Y225393D03*
Y227362D03*
Y229330D03*
Y231299D03*
Y233267D03*
Y235236D03*
Y237204D03*
Y239173D03*
Y241141D03*
Y243110D03*
Y245078D03*
Y247047D03*
Y249015D03*
Y250984D03*
Y252952D03*
G54D165*
X500453Y1410179D03*
X1476594D03*
G54D282*
X1756127Y296368D03*
X1774731D03*
G54D255*
X1287521Y133603D03*
G54D81*
X159474Y1328627D03*
X183847Y1328652D03*
X208247D03*
X275289Y583576D03*
Y607735D03*
Y631889D03*
Y656043D03*
X270252Y676260D03*
Y700414D03*
X387897Y1242785D03*
X412297D03*
X436619D03*
X461019D03*
X485419D03*
X673093Y1328652D03*
X697466Y1328677D03*
X721866D03*
X1100800Y259362D03*
X1100700Y283662D03*
X1131100Y1364962D03*
X1155500D03*
X1179900D03*
X1364038Y1242785D03*
X1388438D03*
X1412760D03*
X1437160D03*
X1461560D03*
X1577000Y599762D03*
Y624262D03*
Y648762D03*
Y673162D03*
Y697662D03*
Y722162D03*
X1634259Y1362248D03*
X1658632Y1362273D03*
X1683032D03*
G54D90*
X149843Y1540080D03*
Y1542048D03*
Y1544017D03*
Y1545985D03*
Y1547954D03*
Y1549922D03*
X164803D03*
Y1547954D03*
Y1545985D03*
Y1544017D03*
Y1542048D03*
Y1540080D03*
G54D183*
X694225Y144488D03*
Y225984D03*
G54D246*
X1276480Y118820D03*
X1269520Y125780D03*
G36*
G01X1718341Y223879D02*
X1727396D01*
Y221517D01*
X1731727D01*
Y226261D01*
X1735270D01*
Y223899D01*
X1732227D01*
Y221261D01*
X1735270D01*
Y218899D01*
X1732227D01*
Y216261D01*
X1735270D01*
Y213899D01*
X1732227D01*
Y211261D01*
X1735270D01*
Y208899D01*
X1731727D01*
Y213143D01*
X1727396D01*
Y211281D01*
X1725034D01*
Y214324D01*
X1724050D01*
Y211281D01*
X1721688D01*
Y214324D01*
X1720703D01*
Y211281D01*
X1718341D01*
Y214824D01*
X1727396D01*
Y213643D01*
X1731727D01*
Y217080D01*
X1727396D01*
Y215808D01*
X1725034D01*
Y218852D01*
X1724050D01*
Y215808D01*
X1721688D01*
Y218852D01*
X1720703D01*
Y215808D01*
X1718341D01*
Y219352D01*
X1727396D01*
Y217580D01*
X1731727D01*
Y221017D01*
X1727396D01*
Y220336D01*
X1725034D01*
Y223379D01*
X1724050D01*
Y220336D01*
X1721688D01*
Y223379D01*
X1720703D01*
Y220336D01*
X1718341D01*
Y223879D01*
G37*
G54D166*
X493760Y1406144D03*
X496122Y1416380D03*
X493760D03*
X1469901Y1406144D03*
X1472263Y1416380D03*
X1469901D03*
G54D91*
X170014Y230928D03*
X166274D03*
X241354Y278685D03*
X232494D03*
X228754D03*
X240624Y311334D03*
X231764D03*
X228024D03*
X245094Y278685D03*
X257694D03*
X253954D03*
X244364Y311334D03*
X256964D03*
X253224D03*
X270294Y278685D03*
X266554D03*
X269564Y311334D03*
X265824D03*
X282894Y278685D03*
X279154D03*
X282164Y311334D03*
X278424D03*
X295494Y278685D03*
X291754D03*
X304354D03*
X294764Y311334D03*
X291024D03*
X303624D03*
X320694Y278685D03*
X316954D03*
X308094D03*
X319964Y311334D03*
X316224D03*
X307364D03*
X333294Y278685D03*
X329554D03*
X332564Y311334D03*
X328824D03*
X345894Y278685D03*
X342154D03*
X354754D03*
X345164Y311334D03*
X341424D03*
X354024D03*
X358494Y278685D03*
X371094D03*
X367354D03*
X370364Y311334D03*
X366624D03*
X357764D03*
X383694Y278685D03*
X379954D03*
X382964Y311334D03*
X379224D03*
X396294Y278685D03*
X392554D03*
X395564Y311334D03*
X391824D03*
X408894Y278685D03*
X405154D03*
X417754D03*
X408164Y311334D03*
X404424D03*
X417024D03*
X435654Y278715D03*
X431914D03*
X421494Y278685D03*
X420764Y311334D03*
X433364D03*
X429624D03*
X445964D03*
X442224D03*
X863450Y437462D03*
X867190D03*
X1453670Y281190D03*
X1449930D03*
G54D37*
X75896Y442183D03*
X81696D03*
X180867Y416827D03*
X186667D03*
X251487Y92733D03*
X257287D03*
Y97633D03*
X251487D03*
X684643Y96858D03*
X690443D03*
Y101758D03*
X684643D03*
X1034669Y373577D03*
X1034569Y367944D03*
X1040469Y373577D03*
X1040369Y367944D03*
X1321537Y255966D03*
X1327337D03*
X1726608Y93857D03*
X1732408D03*
Y98757D03*
X1726608D03*
G54D193*
X765160Y270763D03*
G54D247*
X1281262Y125396D03*
X1277160Y129498D03*
G54D184*
X709692Y177187D03*
X711792D03*
X709692Y173587D03*
X711792D03*
X709692Y185587D03*
X711792D03*
X709692Y189187D03*
X711792D03*
X709692Y197087D03*
X711792D03*
X709692Y200687D03*
X711792D03*
X709692Y212521D03*
X711792D03*
X709692Y208921D03*
X711792D03*
X940496Y211897D03*
Y215497D03*
Y204775D03*
Y208375D03*
Y229635D03*
Y226035D03*
X942596Y211897D03*
Y215497D03*
Y204775D03*
Y208375D03*
Y229635D03*
Y226035D03*
X947196Y222548D03*
X949296D03*
X947196Y218948D03*
X949296D03*
X1375400Y249262D03*
X1373300D03*
X1375400Y245662D03*
X1373300D03*
X1379624Y238551D03*
Y242151D03*
X1374916Y263736D03*
X1372816D03*
X1374916Y260136D03*
X1372816D03*
X1375121Y272170D03*
X1373021D03*
X1375121Y268570D03*
X1373021D03*
X1381724Y238551D03*
Y242151D03*
X1385600Y257303D03*
X1383500D03*
X1385600Y253703D03*
X1383500D03*
G54D238*
X1135748Y1528720D03*
X1133780Y1545768D03*
X1139685Y1528720D03*
X1143622D03*
X1147559D03*
X1151497D03*
X1137717Y1545768D03*
X1141654D03*
X1145591D03*
X1149528D03*
X1155433Y1528720D03*
X1159371D03*
X1163308D03*
X1167245D03*
X1153465Y1545768D03*
X1157402D03*
X1161339D03*
X1165276D03*
X1171182Y1528720D03*
X1169213Y1545768D03*
X1173150D03*
G54D283*
X1766413Y298829D03*
X1768382D03*
X1760508D03*
X1762476D03*
X1764445D03*
X1770350D03*
G54D64*
X95132Y1541244D03*
G54D19*
X39484Y200862D03*
Y192862D03*
X39204Y216362D03*
X30704D03*
X39204Y208362D03*
Y232362D03*
Y224342D03*
X30704Y224362D03*
X39204Y240362D03*
X36164Y302472D03*
X62258Y1520094D03*
Y1536094D03*
Y1540094D03*
Y1560094D03*
X65790Y302926D03*
X68592Y421746D03*
X82624Y278798D03*
Y295798D03*
Y286262D03*
Y303262D03*
X84875Y376026D03*
X84858Y386502D03*
X80975Y424319D03*
Y420319D03*
X91285Y438519D03*
Y442519D03*
X80674Y648574D03*
Y644564D03*
X88624D03*
X80674Y652564D03*
X88624Y648564D03*
Y656564D03*
Y652564D03*
X89503Y685488D03*
X88492Y694209D03*
X89492Y690644D03*
X87122Y1589872D03*
X91729Y1683071D03*
X91704Y1694362D03*
X91714Y1686622D03*
X110999Y216596D03*
X107934Y517925D03*
X110079Y685490D03*
X98734Y718880D03*
X110258Y1524594D03*
Y1544594D03*
Y1548594D03*
Y1536594D03*
Y1540594D03*
Y1560594D03*
Y1564594D03*
X96172Y1581852D03*
Y1597867D03*
X96247Y1601867D03*
Y1615821D03*
Y1619821D03*
X96157Y1630362D03*
Y1642362D03*
X112059Y186362D03*
X113996Y282995D03*
Y278875D03*
Y274800D03*
Y300354D03*
Y306236D03*
X115798Y523785D03*
X127222Y647103D03*
X125658Y665515D03*
Y661515D03*
X125634Y669400D03*
X119217Y1535767D03*
X119319Y1541935D03*
X119390Y1548027D03*
X124704Y1678362D03*
Y1670362D03*
Y1674362D03*
X117704Y1696362D03*
X124704Y1692362D03*
Y1688362D03*
Y1708362D03*
Y1700362D03*
Y1704362D03*
X130466Y404571D03*
X128222Y656603D03*
Y652603D03*
X131665Y643603D03*
X130541Y1727182D03*
Y1731182D03*
X146880Y415062D03*
Y423383D03*
Y427383D03*
Y419383D03*
Y431383D03*
Y435383D03*
Y439383D03*
Y443383D03*
X146981Y498810D03*
Y502810D03*
X146946Y506533D03*
X146981Y522810D03*
X146529Y688207D03*
X145601Y1396275D03*
Y1392745D03*
X160042Y1412173D03*
X151204Y1708362D03*
Y1712362D03*
X158204Y1716362D03*
X161384Y409362D03*
X175380Y421383D03*
Y425383D03*
Y443383D03*
Y430883D03*
X168595Y1443390D03*
X183966Y393071D03*
Y385071D03*
Y389071D03*
Y405071D03*
X182966Y1535462D03*
X182852Y1544028D03*
X182932Y1548486D03*
X182955Y1539723D03*
X182923Y1552874D03*
Y1557874D03*
X185051Y1723592D03*
X204608Y420255D03*
Y414755D03*
Y425755D03*
Y436755D03*
Y431255D03*
Y442255D03*
Y447755D03*
Y453255D03*
Y458755D03*
Y462755D03*
Y468255D03*
X199585Y570901D03*
X200057Y588879D03*
X199585Y604901D03*
X200057Y622879D03*
X199585Y638901D03*
X200057Y656879D03*
X195035Y681291D03*
X194126Y693623D03*
X198185Y1412173D03*
X196352Y1719697D03*
X208102Y1718017D03*
X202109Y1733022D03*
X215038Y452735D03*
X218375Y567981D03*
X217276Y596107D03*
X218375Y601981D03*
X217276Y630107D03*
X218375Y635981D03*
X217276Y664107D03*
X214525Y673737D03*
X233504Y154126D03*
X245204Y71862D03*
X250281Y111743D03*
X272984Y136962D03*
X270034Y142892D03*
X270037Y159203D03*
Y155203D03*
X265704Y214022D03*
X269538Y422735D03*
X269520Y418579D03*
X269538Y426735D03*
X269570Y431039D03*
X269538Y443735D03*
X259754Y458617D03*
X276751Y99183D03*
X279884Y136962D03*
X280764Y210802D03*
X298401Y71513D03*
X298431Y75673D03*
X299537Y151703D03*
Y156203D03*
X292104Y637809D03*
X320041Y91803D03*
X309203Y595318D03*
X317699Y599926D03*
X315130Y1369807D03*
X325526Y69863D03*
X323289Y563176D03*
X342984Y161862D03*
X349717Y709995D03*
X346153Y1347521D03*
X366684Y130162D03*
X366584Y156202D03*
X356204Y221862D03*
X379204Y128452D03*
X379224Y124312D03*
X378281Y1334095D03*
X387834Y1627062D03*
X388644Y124322D03*
X388559Y128491D03*
X399080Y1330142D03*
X397809Y1413619D03*
X399402Y1432571D03*
Y1427569D03*
X402405Y1541810D03*
Y1556810D03*
X411343Y161162D03*
X412027Y1334095D03*
X418461Y1390306D03*
X411799Y1390325D03*
X406388Y1404207D03*
Y1400684D03*
X406315Y1397038D03*
X406383Y1407727D03*
X408202Y1427569D03*
Y1432571D03*
X414184Y1611300D03*
Y1607400D03*
X412916Y1680267D03*
X422821Y67465D03*
Y62665D03*
X426559Y117491D03*
X431948Y128515D03*
Y124015D03*
X420681Y149373D03*
Y157466D03*
Y161466D03*
Y153477D03*
X431204Y214862D03*
Y209862D03*
X426204Y225362D03*
X426904Y232562D03*
Y236562D03*
Y240562D03*
X430639Y1330042D03*
X432905Y1543810D03*
Y1555810D03*
X430029Y1579466D03*
X449805Y149864D03*
X439802Y498733D03*
Y504233D03*
Y509733D03*
Y515233D03*
Y520733D03*
Y526233D03*
Y542733D03*
X448312Y537483D03*
X439802Y547769D03*
Y552769D03*
X442537Y1334095D03*
X454477Y75985D03*
X459623Y115948D03*
X458805Y149864D03*
Y154864D03*
X463564Y1330533D03*
X454073Y1393959D03*
X453085Y1420625D03*
Y1409125D03*
Y1413125D03*
Y1417125D03*
Y1427632D03*
Y1424125D03*
X453074Y1431134D03*
X453064Y1611923D03*
X475237Y66575D03*
X475211Y61129D03*
X475167Y55935D03*
X484305Y158864D03*
X483204Y391362D03*
X474665Y1334095D03*
X480950Y1400385D03*
X479555Y1411144D03*
X469397Y1614682D03*
X469354Y1618626D03*
X475414Y1643242D03*
Y1659242D03*
Y1651242D03*
Y1667242D03*
X475344Y1673462D03*
Y1685462D03*
X492320Y305398D03*
X492294Y313582D03*
X496204Y391362D03*
X494102Y547947D03*
X495724Y1319592D03*
X488134Y1631038D03*
X506934Y86422D03*
X502564Y93582D03*
X509984Y209862D03*
X503984Y228362D03*
X505484Y237862D03*
X508484Y288862D03*
X508241Y315404D03*
X511204Y420862D03*
X507002Y507819D03*
Y511819D03*
Y519819D03*
Y515819D03*
Y523819D03*
Y527819D03*
Y539819D03*
X506793Y1347521D03*
X526204Y420862D03*
X525864Y478492D03*
X529884Y489112D03*
Y495112D03*
X528322Y1338837D03*
X539304Y103352D03*
X539374Y108062D03*
X550454Y149802D03*
X538434Y442376D03*
Y450330D03*
Y446396D03*
X538921Y1370319D03*
X555454Y131756D03*
X562204Y167112D03*
Y161362D03*
X562704Y184862D03*
X557548Y253202D03*
Y257202D03*
X573704Y167112D03*
X578418Y262632D03*
X569673Y305247D03*
X568024Y442656D03*
X568001Y451710D03*
X571899Y498546D03*
X581984Y514362D03*
X591304Y129642D03*
X598204Y174612D03*
X584934Y190092D03*
X584940Y198378D03*
Y210378D03*
Y202378D03*
Y206378D03*
X584704Y225362D03*
Y221362D03*
X599298Y257532D03*
X589548Y252202D03*
X588029Y296657D03*
Y311571D03*
Y304052D03*
X594289Y363354D03*
X591054Y488212D03*
X594484Y524862D03*
X604704Y164612D03*
X614440Y202878D03*
Y207378D03*
X602914Y458688D03*
X602704Y482362D03*
X603704Y514862D03*
X621291Y184022D03*
X630048Y249202D03*
Y260202D03*
X619704Y442862D03*
Y457862D03*
X641537Y88035D03*
X641497Y92085D03*
X648145Y134506D03*
X648128Y144982D03*
X640204Y230362D03*
X640629Y298297D03*
Y315587D03*
Y310962D03*
Y302247D03*
X635984Y392862D03*
X634704Y411362D03*
X634484Y406862D03*
X634704Y426362D03*
Y421362D03*
Y441862D03*
Y431362D03*
X634707Y436650D03*
X634704Y457862D03*
Y452862D03*
Y447862D03*
Y462862D03*
X634684Y482662D03*
X646709Y1653194D03*
X645209Y1695694D03*
X645204Y1718362D03*
Y1722362D03*
X649484Y93362D03*
X655094Y120412D03*
X649204Y161862D03*
Y166362D03*
Y171362D03*
X655729Y290371D03*
X648984Y392862D03*
X649484Y406862D03*
Y402362D03*
X649704Y416362D03*
Y441862D03*
Y431362D03*
Y452862D03*
Y457862D03*
Y447862D03*
Y467862D03*
Y462862D03*
X659220Y1392770D03*
Y1396300D03*
X673114Y391602D03*
X673661Y1412198D03*
X668556Y1642667D03*
X668577Y1655557D03*
X668502Y1651557D03*
X668604Y1672862D03*
Y1668862D03*
X671704Y1708362D03*
X666704Y1720362D03*
X671704Y1724362D03*
Y1716362D03*
Y1732362D03*
X683437Y115868D03*
X684884Y1442245D03*
X694631Y1632667D03*
X694706Y1644667D03*
X694716Y1648843D03*
X695104Y1658862D03*
X690104Y1670862D03*
X695104Y1666862D03*
Y1674862D03*
Y1682862D03*
X709907Y103308D03*
X713204Y161862D03*
Y157362D03*
X711804Y1412198D03*
X707626Y1563733D03*
X707596Y1583683D03*
X706564Y1607102D03*
Y1611022D03*
X707556Y1601963D03*
X721254Y1644550D03*
X721817Y1676500D03*
X733007Y95158D03*
X732977Y90998D03*
X760102Y89348D03*
X754617Y111288D03*
X748719Y142050D03*
X751184Y167537D03*
X751144Y276322D03*
X757596Y1579183D03*
Y1587183D03*
Y1592183D03*
X748139Y1674362D03*
X777773Y158026D03*
X777787Y153728D03*
X766726Y299279D03*
X766627Y311249D03*
X766154Y317432D03*
X763704Y393212D03*
Y418212D03*
Y423212D03*
Y428212D03*
X777824Y464862D03*
Y469862D03*
X762824Y464862D03*
Y469862D03*
Y488862D03*
Y483862D03*
Y479862D03*
X777824Y488862D03*
X762834Y497659D03*
X765004Y1388562D03*
Y1392762D03*
Y1406062D03*
X764904Y1410262D03*
X768636Y1594893D03*
X782644Y267822D03*
Y281822D03*
X780526Y299279D03*
X792904Y393462D03*
X778704Y413212D03*
Y408212D03*
Y403212D03*
Y398212D03*
X792904Y402500D03*
X778704Y418212D03*
Y423212D03*
X792824Y464862D03*
Y474862D03*
X791384Y483262D03*
X805946Y269800D03*
X808324Y469862D03*
Y474862D03*
X810136Y1577793D03*
Y1593793D03*
Y1601793D03*
Y1609793D03*
X824592Y274885D03*
Y279885D03*
X834445Y58632D03*
X831204Y166862D03*
Y176362D03*
X836119Y275045D03*
Y280045D03*
X830462Y389012D03*
Y397276D03*
X830484Y384400D03*
X830461Y413260D03*
X838484Y446800D03*
X827247Y494000D03*
X827254Y498082D03*
X841704Y495362D03*
X827254Y502082D03*
Y523082D03*
Y515082D03*
X851804Y162762D03*
X851394Y185812D03*
X859317Y273217D03*
X859287Y269057D03*
X852384Y476900D03*
X852136Y1577793D03*
Y1593793D03*
Y1601793D03*
Y1609793D03*
X874204Y166362D03*
X867970Y394620D03*
Y390620D03*
Y382415D03*
X868022Y406812D03*
Y418836D03*
X867804Y431462D03*
X860104Y503162D03*
Y499062D03*
X860254Y515582D03*
Y519582D03*
X882204Y176862D03*
Y171362D03*
X884199Y183169D03*
X884209Y187449D03*
X886412Y267407D03*
X880899Y289439D03*
X887806Y874405D03*
X888376Y920325D03*
X894136Y1577793D03*
Y1593793D03*
Y1601793D03*
Y1609793D03*
X936136Y1581393D03*
Y1585393D03*
Y1589393D03*
X958329Y484271D03*
X958304Y480262D03*
X958355Y540727D03*
X958356Y536806D03*
X961274Y997496D03*
X964463Y1551855D03*
X984608Y185347D03*
X984333Y276394D03*
X980778Y356910D03*
X989241Y363660D03*
X987829Y1551855D03*
X997396Y217233D03*
Y221233D03*
X996507Y363155D03*
X1018711Y195114D03*
X1018704Y199076D03*
X1016679Y203423D03*
Y210423D03*
Y214423D03*
Y218423D03*
Y222423D03*
X1011222Y363356D03*
X1021253Y517728D03*
Y512574D03*
X1011195Y1551855D03*
X1037317Y264130D03*
X1027317Y297264D03*
Y305313D03*
Y301313D03*
X1034561Y1551855D03*
X1044011Y291105D03*
X1045472Y502161D03*
X1057927Y1551855D03*
X1082173Y78553D03*
X1072689Y382141D03*
X1076648Y509645D03*
X1081293Y1551855D03*
X1079441Y1663950D03*
X1097703Y65262D03*
X1094594Y379251D03*
X1094474Y369061D03*
X1094534Y374131D03*
X1101514Y1679870D03*
Y1675970D03*
X1100034Y1672030D03*
X1107116Y55505D03*
X1118912Y1429074D03*
Y1432604D03*
X1104659Y1551855D03*
X1124587Y60545D03*
X1124487Y56545D03*
X1124587Y64545D03*
X1133353Y1448502D03*
X1122094Y1612320D03*
X1122064Y1608420D03*
X1151854Y211231D03*
X1140374Y377011D03*
X1145017Y1479313D03*
X1152454Y1618960D03*
X1153494Y373231D03*
X1159145Y1622340D03*
Y1626220D03*
Y1630090D03*
X1163909Y1642600D03*
X1159145Y1633880D03*
X1178729Y202174D03*
Y198174D03*
Y186174D03*
Y218174D03*
Y214174D03*
X1171496Y1448502D03*
X1175364Y1601100D03*
Y1609100D03*
Y1605100D03*
X1175244Y1612960D03*
X1182055D03*
X1174909Y1642600D03*
X1185555Y61311D03*
X1185455Y65811D03*
X1185475Y57111D03*
X1198284Y93200D03*
X1196460Y127804D03*
X1200459Y236592D03*
X1196479Y1642910D03*
X1185909Y1642600D03*
X1196319Y1688390D03*
X1207245Y57130D03*
X1210704Y189362D03*
X1213889Y1673963D03*
X1206565Y1677873D03*
X1213819Y1681773D03*
X1207089Y1688435D03*
X1231484Y94200D03*
Y98400D03*
X1220077Y140962D03*
X1231577Y168162D03*
X1220077Y185462D03*
X1231577Y172962D03*
X1217889Y1688700D03*
X1245366Y98785D03*
X1242044Y191279D03*
X1242077Y197462D03*
X1251077Y201562D03*
Y211762D03*
Y205362D03*
X1262077Y217462D03*
X1251077Y215762D03*
X1262077Y233462D03*
Y221462D03*
X1251077Y219662D03*
X1262077Y229462D03*
Y225462D03*
Y243562D03*
Y238662D03*
Y247562D03*
X1251162Y245442D03*
X1262277Y251562D03*
X1270238Y88572D03*
Y96768D03*
X1281775Y98828D03*
X1269577Y233462D03*
X1291391Y1370043D03*
X1305518Y64572D03*
X1308247Y81775D03*
X1299149Y81169D03*
X1328048Y261514D03*
X1322294Y1347521D03*
X1354422Y1334095D03*
X1371736Y81111D03*
X1375221Y1330142D03*
X1373110Y1417374D03*
X1373950Y1413019D03*
X1388168Y1334095D03*
X1394602Y1390306D03*
X1382529Y1400684D03*
Y1404207D03*
X1387160Y1390335D03*
X1382524Y1407727D03*
X1411867Y227948D03*
X1406780Y1330042D03*
X1409892Y1565037D03*
X1409832Y1576197D03*
X1409892Y1570037D03*
X1402384Y1586400D03*
Y1590200D03*
X1405484Y1626362D03*
Y1634362D03*
Y1638362D03*
X1418678Y1334095D03*
X1420317Y1516435D03*
X1420557Y1532255D03*
X1420317Y1521335D03*
X1420557Y1537155D03*
X1420707Y1548375D03*
Y1543475D03*
X1423754Y1603262D03*
X1427254Y1608442D03*
X1427194Y1616932D03*
X1413959Y1622200D03*
X1439705Y1330533D03*
X1430214Y1393959D03*
X1429226Y1417125D03*
Y1413125D03*
Y1409125D03*
Y1420625D03*
Y1427632D03*
Y1424125D03*
X1429254Y1431150D03*
X1443164Y1590382D03*
X1443884Y1606800D03*
Y1602600D03*
X1439284Y1632900D03*
Y1620300D03*
X1444217Y1665495D03*
X1444127Y1673955D03*
X1444131Y1669629D03*
X1447984Y211862D03*
Y215862D03*
X1450806Y1334095D03*
X1457091Y1400385D03*
X1455696Y1411144D03*
X1455392Y1560037D03*
Y1565037D03*
X1453114Y1586262D03*
X1457449Y1612800D03*
X1474367Y225448D03*
Y233448D03*
X1466867Y242448D03*
X1474569Y263378D03*
Y255378D03*
X1466569Y271378D03*
X1471865Y1319592D03*
X1484392Y281456D03*
X1491884Y421982D03*
X1487864Y431972D03*
X1482934Y1347521D03*
X1498893Y280027D03*
X1504463Y1338837D03*
X1519484Y116462D03*
X1518484Y136162D03*
X1520052Y243362D03*
Y235116D03*
Y258616D03*
Y254616D03*
X1511385Y288030D03*
X1519742Y284956D03*
X1515862Y1369919D03*
X1545436Y152873D03*
X1546221Y634165D03*
X1566063Y655416D03*
Y659416D03*
X1568940Y735691D03*
Y732165D03*
X1592062Y219526D03*
Y227526D03*
X1591823Y248008D03*
X1591843Y243890D03*
X1591803Y252126D03*
X1607264Y654542D03*
X1605444Y722582D03*
X1600400Y1420169D03*
Y1433669D03*
Y1438169D03*
Y1452071D03*
X1614304Y586762D03*
X1620386Y1426366D03*
Y1429896D03*
X1629517Y117627D03*
Y129627D03*
Y121627D03*
X1634827Y1445794D03*
X1649066Y652601D03*
Y686601D03*
Y720601D03*
X1646091Y1476695D03*
X1664787Y550382D03*
X1657713Y544622D03*
X1665844Y598522D03*
X1656892Y635791D03*
Y669791D03*
Y703791D03*
X1672970Y1445794D03*
X1671582Y1493362D03*
Y1501362D03*
Y1516862D03*
Y1533862D03*
Y1520862D03*
Y1545862D03*
X1671657Y1561557D03*
X1671582Y1557557D03*
X1671657Y1581321D03*
X1687415Y495290D03*
Y499290D03*
X1704778Y369773D03*
Y373773D03*
X1702868Y401485D03*
X1696760Y525507D03*
Y529507D03*
Y533507D03*
Y549507D03*
X1703904Y688130D03*
Y691730D03*
Y695330D03*
X1704944Y726552D03*
X1714701Y174970D03*
X1717674Y364962D03*
X1706511Y655141D03*
X1725402Y112867D03*
X1722913Y474859D03*
Y478869D03*
X1725639Y688211D03*
X1751872Y100307D03*
X1754204Y372452D03*
X1739185Y486837D03*
X1744419Y1451841D03*
X1763552Y76797D03*
X1763522Y72637D03*
X1766494Y164362D03*
X1760125Y433221D03*
X1763225Y461393D03*
X1763335Y465893D03*
X1760740Y692742D03*
X1757509Y1475951D03*
X1785162Y92927D03*
X1774859Y169903D03*
X1782912Y291876D03*
X1782927Y295643D03*
Y299243D03*
X1790647Y70987D03*
X1802749Y165565D03*
X1795255Y367866D03*
X1794553Y390252D03*
X1787783Y403932D03*
Y410432D03*
Y418932D03*
Y425432D03*
X1798511Y1527366D03*
X1806274Y156557D03*
X1813234Y179897D03*
X1819283Y407932D03*
Y403225D03*
X1818783Y421432D03*
Y427932D03*
X1818725Y472521D03*
X1809625Y1494318D03*
Y1498318D03*
X1818198Y1504241D03*
X1826535Y363731D03*
X1820216Y371329D03*
X1826535Y367701D03*
X1826153Y379552D03*
X1820053Y395552D03*
X1826153Y383952D03*
X1835425Y459121D03*
X1838819Y182712D03*
X1845939Y176722D03*
G54D46*
X87225Y704442D03*
X1700657Y708568D03*
G54D175*
X572690Y1323203D03*
Y1341313D03*
X1263605Y1322514D03*
Y1340624D03*
G54D73*
X109608Y707039D03*
X132638D03*
X1473922Y298220D03*
X1496952D03*
X1723150Y708355D03*
X1746180D03*
G54D28*
X57646Y12480D03*
X137272D03*
X186622D03*
X266858D03*
X315598D03*
X502528Y33268D03*
X582154D03*
X631504D03*
X711740D03*
X760480D03*
X1532055Y12480D03*
X1611681D03*
X1661031D03*
X1741267D03*
X1790007D03*
G54D139*
X384600Y1595100D03*
X411162Y1414126D03*
X710486Y77695D03*
X919488Y1660733D03*
X956800Y1663725D03*
X1132187Y1582738D03*
G54D148*
X418813Y1401470D03*
Y1424108D03*
X434561Y1401470D03*
X432986D03*
X431411D03*
X429836D03*
X428261D03*
X426687D03*
X425112D03*
X423537D03*
X421962D03*
X420387D03*
Y1424108D03*
X421962D03*
X423537D03*
X425112D03*
X426687D03*
X428261D03*
X429836D03*
X431411D03*
X432986D03*
X434561D03*
X436135Y1401470D03*
Y1424108D03*
X1394954Y1401470D03*
Y1424108D03*
X1410702Y1401470D03*
X1409127D03*
X1407552D03*
X1405977D03*
X1404402D03*
X1402828D03*
X1401253D03*
X1399678D03*
X1398103D03*
X1396528D03*
Y1424108D03*
X1398103D03*
X1399678D03*
X1401253D03*
X1402828D03*
X1404402D03*
X1405977D03*
X1407552D03*
X1409127D03*
X1410702D03*
X1412276Y1401470D03*
Y1424108D03*
G54D274*
X1713488Y1525698D03*
X1730810D03*
G54D157*
X467736Y302358D03*
Y309838D03*
X501136Y301658D03*
Y309138D03*
G54D256*
X1288347Y150750D03*
X1290927Y151438D03*
X1294866D03*
X1292896Y149804D03*
X1296835D03*
X1294866Y148170D03*
X1287401Y167116D03*
X1290669D03*
X1289035Y165146D03*
X1292303D03*
X1287401Y163177D03*
X1290669D03*
X1289035Y161207D03*
X1292303D03*
X1287401Y159238D03*
X1290669D03*
X1285767Y157268D03*
X1289035D03*
X1292303D03*
X1287401Y155299D03*
X1290669D03*
X1294866Y154706D03*
X1289035Y153329D03*
X1292896Y153072D03*
X1296835D03*
X1289035Y184841D03*
X1292303D03*
X1287401Y182871D03*
X1290669D03*
X1289035Y180902D03*
X1292303D03*
X1287401Y178932D03*
X1290669D03*
X1289035Y176963D03*
X1292303D03*
X1287401Y174993D03*
X1290669D03*
X1289035Y173024D03*
X1292303D03*
X1287401Y171055D03*
X1290669D03*
X1289035Y169085D03*
X1292303D03*
X1289035Y196657D03*
X1292303D03*
X1287401Y194688D03*
X1290669D03*
X1289035Y192718D03*
X1292303D03*
X1287401Y190749D03*
X1290669D03*
X1289035Y188780D03*
X1292303D03*
X1287401Y186810D03*
X1290669D03*
X1289035Y200596D03*
X1292303D03*
X1287401Y198627D03*
X1290669D03*
X1289035Y216352D03*
X1292303D03*
X1287401Y214382D03*
X1290669D03*
X1289035Y212413D03*
X1292303D03*
X1287401Y210443D03*
X1290669D03*
X1289035Y208474D03*
X1292303D03*
X1287401Y206505D03*
X1290669D03*
X1289035Y204535D03*
X1292303D03*
X1287401Y202566D03*
X1290669D03*
X1292896Y231694D03*
X1296835D03*
X1290927Y230060D03*
X1294866D03*
X1289035Y228169D03*
X1292896Y228426D03*
X1296835D03*
X1287401Y226199D03*
X1290669D03*
X1294866Y226792D03*
X1289035Y224230D03*
X1292303D03*
X1287401Y222260D03*
X1290669D03*
X1289035Y220291D03*
X1292303D03*
X1287401Y218321D03*
X1290669D03*
X1302744Y151438D03*
X1306683D03*
X1310621D03*
X1314560D03*
X1298805D03*
X1304713Y149804D03*
X1308652D03*
X1312591D03*
X1300774D03*
X1302744Y154706D03*
X1306683D03*
X1310621D03*
X1314560D03*
X1298805D03*
X1304713Y153072D03*
X1308652D03*
X1312591D03*
X1300774D03*
X1304713Y231694D03*
X1308652D03*
X1312591D03*
X1300774D03*
X1302744Y230060D03*
X1306683D03*
X1310621D03*
X1314560D03*
X1298805D03*
X1304713Y228426D03*
X1308652D03*
X1312591D03*
X1300774D03*
X1302744Y226792D03*
X1306683D03*
X1310621D03*
X1314560D03*
X1298805D03*
X1318499Y151438D03*
X1322438D03*
X1326377D03*
X1330316D03*
X1316530Y149804D03*
X1320469D03*
X1324408D03*
X1328346D03*
X1318499Y154706D03*
X1322438D03*
X1326377D03*
X1330316D03*
X1316530Y153072D03*
X1320469D03*
X1324408D03*
X1328346D03*
X1316530Y231694D03*
X1320469D03*
X1324408D03*
X1328346D03*
X1318499Y230060D03*
X1322438D03*
X1326377D03*
X1330316D03*
X1316530Y228426D03*
X1320469D03*
X1324408D03*
X1328346D03*
X1318499Y226792D03*
X1322438D03*
X1326377D03*
X1330316D03*
X1334255Y151438D03*
X1338194D03*
X1342133D03*
X1346071D03*
X1332285Y149804D03*
X1336224D03*
X1340163D03*
X1344102D03*
X1334255Y154706D03*
X1338194D03*
X1342133D03*
X1346071D03*
X1332285Y153072D03*
X1336224D03*
X1340163D03*
X1344102D03*
X1332285Y231694D03*
X1336224D03*
X1340163D03*
X1344102D03*
X1334255Y230060D03*
X1338194D03*
X1342133D03*
X1346071D03*
X1332285Y228426D03*
X1336224D03*
X1340163D03*
X1344102D03*
X1334255Y226792D03*
X1338194D03*
X1342133D03*
X1346071D03*
X1350010Y151438D03*
X1353949D03*
X1357888D03*
X1361827D03*
X1348041Y149804D03*
X1351980D03*
X1355919D03*
X1359858D03*
X1362085Y167116D03*
X1360451Y165146D03*
X1362085Y163177D03*
X1360451Y161207D03*
X1362085Y159238D03*
X1360451Y157268D03*
X1350010Y154706D03*
X1353949D03*
X1357888D03*
X1362085Y155299D03*
X1348041Y153072D03*
X1351980D03*
X1355919D03*
X1359858D03*
X1360451Y184841D03*
X1362085Y182871D03*
X1360451Y180902D03*
X1362085Y178932D03*
X1360451Y176963D03*
X1362085Y174993D03*
X1360451Y173024D03*
X1362085Y171055D03*
X1360451Y169085D03*
Y196657D03*
X1362085Y194688D03*
X1360451Y192718D03*
X1362085Y190749D03*
X1360451Y188780D03*
X1362085Y186810D03*
X1360451Y200596D03*
X1362085Y198627D03*
X1360451Y216352D03*
X1362085Y214382D03*
X1360451Y212413D03*
X1362085Y210443D03*
X1360451Y208474D03*
X1362085Y206505D03*
X1360451Y204535D03*
X1362085Y202566D03*
X1348041Y231694D03*
X1351980D03*
X1355919D03*
X1359858D03*
X1350010Y230060D03*
X1353949D03*
X1357888D03*
X1361827D03*
X1348041Y228426D03*
X1351980D03*
X1355919D03*
X1359858D03*
X1350010Y226792D03*
X1353949D03*
X1357888D03*
X1362085Y226199D03*
X1360451Y224230D03*
X1362085Y222260D03*
X1360451Y220291D03*
X1362085Y218321D03*
X1364407Y150750D03*
X1365353Y167116D03*
X1363719Y165146D03*
X1365353Y163177D03*
X1363719Y161207D03*
X1365353Y159238D03*
X1363719Y157268D03*
X1365353Y155299D03*
X1363719Y153329D03*
Y184841D03*
X1365353Y182871D03*
X1363719Y180902D03*
X1365353Y178932D03*
X1363719Y176963D03*
X1365353Y174993D03*
X1363719Y173024D03*
X1365353Y171055D03*
X1363719Y169085D03*
Y196657D03*
X1365353Y194688D03*
X1363719Y192718D03*
X1365353Y190749D03*
X1363719Y188780D03*
X1365353Y186810D03*
X1363719Y200596D03*
X1365353Y198627D03*
X1363719Y216352D03*
X1365353Y214382D03*
X1363719Y212413D03*
X1365353Y210443D03*
X1363719Y208474D03*
X1365353Y206505D03*
X1363719Y204535D03*
X1365353Y202566D03*
X1364407Y230748D03*
X1363719Y228169D03*
X1365353Y226199D03*
X1363719Y224230D03*
X1365353Y222260D03*
X1363719Y220291D03*
X1365353Y218321D03*
G54D82*
X163642Y1380504D03*
X201785D03*
X317625Y1338650D03*
X349753Y1315852D03*
X381881Y1302426D03*
X414009D03*
X446137D03*
X478265D03*
X510393Y1315852D03*
X542521Y1338650D03*
X677261Y1380529D03*
X715404D03*
X1136953Y1416833D03*
X1175096D03*
X1293886Y1338886D03*
X1325894Y1315852D03*
X1358022Y1302426D03*
X1390150D03*
X1422278D03*
X1454406D03*
X1486534Y1315852D03*
X1518662Y1338650D03*
X1638427Y1414125D03*
X1676570D03*
G54D55*
X84430Y1334666D03*
X1093936Y1616149D03*
X1769097Y1332916D03*
G54D265*
X1554724Y192657D03*
Y256161D03*
G54D229*
X1029250Y275752D03*
G54D194*
X765160Y275881D03*
G54D248*
X1268043Y132212D03*
G54D92*
X180336Y593159D03*
Y578789D03*
X1831062Y251934D03*
Y237564D03*
G54D65*
X95132Y1539669D03*
Y1538094D03*
Y1536519D03*
G54D185*
X724465Y1581092D03*
Y1589950D03*
G54D176*
X599552Y288661D03*
Y291220D03*
Y293779D03*
Y296338D03*
Y298897D03*
Y301457D03*
Y304016D03*
Y306575D03*
Y309134D03*
Y311693D03*
X621992Y298897D03*
Y296338D03*
Y293779D03*
Y291220D03*
Y288661D03*
Y311693D03*
Y309134D03*
Y306575D03*
Y304016D03*
Y301457D03*
G54D74*
X106818Y1586793D03*
Y1589352D03*
Y1591911D03*
Y1598572D03*
Y1617262D03*
Y1601131D03*
Y1603690D03*
Y1619821D03*
Y1622380D03*
Y1635303D03*
Y1637862D03*
Y1640421D03*
X114298Y1591911D03*
Y1589352D03*
Y1586793D03*
Y1598572D03*
Y1617262D03*
Y1603690D03*
Y1601131D03*
Y1622380D03*
Y1619821D03*
Y1640421D03*
Y1637862D03*
Y1635303D03*
X242215Y144320D03*
Y146879D03*
Y149438D03*
X249695D03*
Y146879D03*
Y144320D03*
X249735Y160162D03*
Y157603D03*
Y155044D03*
X242255D03*
Y157603D03*
Y160162D03*
X333174Y363143D03*
Y375364D03*
Y377923D03*
Y380482D03*
Y365702D03*
Y368261D03*
X340654Y363143D03*
Y380482D03*
Y377923D03*
Y375364D03*
Y368261D03*
Y365702D03*
X366679Y389478D03*
Y392037D03*
Y394596D03*
X374159D03*
Y392037D03*
Y389478D03*
X395960Y323761D03*
Y321202D03*
Y318643D03*
X388480D03*
Y321202D03*
Y323761D03*
X401175Y363081D03*
X393695D03*
X401081Y378439D03*
Y375880D03*
X393601D03*
Y378439D03*
X401175Y368199D03*
Y365640D03*
X393695D03*
Y368199D03*
X401070Y393992D03*
Y391433D03*
Y388874D03*
X393590D03*
Y391433D03*
Y393992D03*
X401081Y380998D03*
X393601D03*
X401129Y406863D03*
Y404304D03*
Y401745D03*
X393649D03*
Y404304D03*
Y406863D03*
X418960Y1606441D03*
Y1609000D03*
Y1611559D03*
X429249Y363644D03*
X421769D03*
X429003Y379201D03*
Y376642D03*
X421523D03*
Y379201D03*
X429249Y368762D03*
Y366203D03*
X421769D03*
Y368762D03*
X429003Y381760D03*
X421523D03*
X428839Y394722D03*
Y392163D03*
Y389604D03*
X421359D03*
Y392163D03*
Y394722D03*
X428962Y407847D03*
Y405288D03*
Y402729D03*
X421482D03*
Y405288D03*
Y407847D03*
X426440Y1611559D03*
Y1609000D03*
Y1606441D03*
X531980Y178803D03*
Y181362D03*
Y183921D03*
X539460D03*
Y181362D03*
Y178803D03*
X586760Y514303D03*
Y516862D03*
Y519421D03*
X594240D03*
Y516862D03*
Y514303D03*
X673612Y1634844D03*
Y1637403D03*
Y1639962D03*
X679148Y1652262D03*
Y1654821D03*
Y1657380D03*
X681092Y1639962D03*
Y1637403D03*
Y1634844D03*
X686628Y1657380D03*
Y1654821D03*
Y1652262D03*
X761245Y167518D03*
Y170077D03*
Y172636D03*
X768725Y167518D03*
Y172636D03*
Y170077D03*
X819684Y264580D03*
Y267139D03*
Y269698D03*
X827164Y264580D03*
Y269698D03*
Y267139D03*
X1134512Y1620851D03*
Y1623410D03*
Y1625969D03*
X1141992D03*
Y1623410D03*
Y1620851D03*
X1408260Y1583441D03*
Y1586000D03*
Y1588559D03*
X1415740Y1583441D03*
Y1588559D03*
Y1586000D03*
X1419270Y1623391D03*
Y1625950D03*
Y1628509D03*
X1426750D03*
Y1625950D03*
Y1623391D03*
X1423240Y1639921D03*
Y1637362D03*
Y1634803D03*
X1415760D03*
Y1637362D03*
Y1639921D03*
X1440273Y1518976D03*
X1432793D03*
X1440513Y1534796D03*
X1433033D03*
X1440273Y1524094D03*
Y1521535D03*
X1432793D03*
Y1524094D03*
X1440663Y1551134D03*
Y1548575D03*
Y1546016D03*
X1433183D03*
Y1548575D03*
Y1551134D03*
X1440513Y1539914D03*
Y1537355D03*
X1433033D03*
Y1539914D03*
X1457540Y1607559D03*
Y1605000D03*
Y1602441D03*
X1450060D03*
Y1605000D03*
Y1607559D03*
X1682008Y1498303D03*
Y1500862D03*
Y1503421D03*
Y1517803D03*
Y1520362D03*
Y1522921D03*
Y1538803D03*
Y1541362D03*
Y1543921D03*
Y1558262D03*
Y1560821D03*
Y1563380D03*
Y1578762D03*
Y1581321D03*
Y1583880D03*
X1689488Y1503421D03*
Y1500862D03*
Y1498303D03*
Y1517803D03*
Y1522921D03*
Y1520362D03*
Y1543921D03*
Y1541362D03*
Y1538803D03*
Y1563380D03*
Y1560821D03*
Y1558262D03*
Y1583880D03*
Y1581321D03*
Y1578762D03*
X1813335Y158868D03*
Y161427D03*
Y163986D03*
X1831277Y151402D03*
X1820815Y163986D03*
Y161427D03*
Y158868D03*
X1831277Y153961D03*
Y156520D03*
X1838757Y151402D03*
Y156520D03*
Y153961D03*
G54D29*
X61057Y64434D03*
Y62334D03*
X72057Y70434D03*
Y68334D03*
X75657Y70434D03*
Y68334D03*
X64657Y64434D03*
Y62334D03*
X94057Y70434D03*
Y68334D03*
X86657Y64434D03*
Y62334D03*
X83057Y64434D03*
Y62334D03*
X105057Y64434D03*
Y62334D03*
X108657Y64434D03*
Y62334D03*
X97657Y70434D03*
Y68334D03*
X127057Y64434D03*
Y62334D03*
X119657Y70434D03*
Y68334D03*
X116057Y70434D03*
Y68334D03*
X130657Y64434D03*
Y62334D03*
X141657Y70434D03*
Y68334D03*
X138057Y70434D03*
Y68334D03*
X149057Y64434D03*
Y62334D03*
X152657Y64434D03*
Y62334D03*
X172261Y64434D03*
Y62334D03*
X175861Y64434D03*
Y62334D03*
X164861Y70434D03*
Y68334D03*
X161261Y70434D03*
Y68334D03*
X186861Y70434D03*
Y68334D03*
X183261Y70434D03*
Y68334D03*
X188797Y1583088D03*
X192397D03*
X188797Y1585188D03*
X192397D03*
X194261Y64434D03*
Y62334D03*
X197861Y64434D03*
Y62334D03*
X205395Y70434D03*
Y68334D03*
X200857Y1583088D03*
X204457D03*
X200857Y1585188D03*
X204457D03*
X206157Y1607286D03*
Y1609386D03*
X194097Y1607286D03*
Y1609386D03*
X197697Y1607286D03*
Y1609386D03*
X216395Y64434D03*
Y62334D03*
X219995Y64434D03*
Y62334D03*
X208995Y70434D03*
Y68334D03*
X212917Y1583088D03*
X216517D03*
X212917Y1585188D03*
X216517D03*
X218217Y1607286D03*
Y1609386D03*
X221817Y1607286D03*
Y1609386D03*
X209757Y1607286D03*
Y1609386D03*
X230995Y70434D03*
Y68334D03*
X227395Y70434D03*
Y68334D03*
X224977Y1583088D03*
X228577D03*
X237037D03*
X240637D03*
X224977Y1585188D03*
X228577D03*
X237037D03*
X240637D03*
X230277Y1607286D03*
Y1609386D03*
X233877Y1607286D03*
Y1609386D03*
X249097Y1583088D03*
X252697D03*
X249097Y1585188D03*
X252697D03*
X254397Y1607286D03*
Y1609386D03*
X242337Y1607286D03*
Y1609386D03*
X245937Y1607286D03*
Y1609386D03*
X261157Y1583088D03*
X264757D03*
X273217D03*
X261157Y1585188D03*
X264757D03*
X273217D03*
X266457Y1607286D03*
Y1609386D03*
X270057Y1607286D03*
Y1609386D03*
X257997Y1607286D03*
Y1609386D03*
X276817Y1583088D03*
X285277D03*
X288877D03*
X276817Y1585188D03*
X285277D03*
X288877D03*
X278517Y1607286D03*
Y1609386D03*
X282117Y1607286D03*
Y1609386D03*
X297337Y1583088D03*
X300937D03*
X297337Y1585188D03*
X300937D03*
X302637Y1607286D03*
Y1609386D03*
X306237Y1607286D03*
Y1609386D03*
X290577Y1607286D03*
Y1609386D03*
X294177Y1607286D03*
Y1609386D03*
X309397Y1583088D03*
X312997D03*
X321457D03*
X309397Y1585188D03*
X312997D03*
X321457D03*
X314697Y1607286D03*
Y1609386D03*
X318297Y1607286D03*
Y1609386D03*
X325057Y1583088D03*
X333517D03*
X337117D03*
X325057Y1585188D03*
X333517D03*
X337117D03*
X338817Y1607286D03*
Y1609386D03*
X330357Y1607286D03*
Y1609386D03*
X326757Y1607286D03*
Y1609386D03*
X345577Y1583088D03*
X349177D03*
X345577Y1585188D03*
X349177D03*
X350877Y1607286D03*
Y1609386D03*
X354477Y1607286D03*
Y1609386D03*
X342417Y1607286D03*
Y1609386D03*
X357637Y1583088D03*
X361237D03*
X369697D03*
X357637Y1585188D03*
X361237D03*
X369697D03*
X362937Y1607286D03*
Y1609386D03*
X366537Y1607286D03*
Y1609386D03*
X373297Y1583088D03*
Y1585188D03*
X374997Y1607286D03*
Y1609386D03*
X378597Y1607286D03*
Y1609386D03*
X402781Y1613560D03*
Y1611460D03*
X405919Y1613560D03*
Y1611460D03*
X476551Y1583088D03*
X472951D03*
X485011D03*
X476551Y1585188D03*
X472951D03*
X485011D03*
X478251Y1607286D03*
Y1609386D03*
X481851Y1607286D03*
Y1609386D03*
X488611Y1583088D03*
X500671D03*
X497071D03*
X488611Y1585188D03*
X500671D03*
X497071D03*
X490311Y1607286D03*
Y1609386D03*
X493911Y1607286D03*
Y1609386D03*
X512731Y1583088D03*
X509131D03*
X512731Y1585188D03*
X509131D03*
X502371Y1607286D03*
Y1609386D03*
X505971Y1607286D03*
Y1609386D03*
X514431Y1607286D03*
Y1609386D03*
X524791Y1583088D03*
X521191D03*
X533251D03*
X524791Y1585188D03*
X521191D03*
X533251D03*
X518031Y1607286D03*
Y1609386D03*
X526491Y1607286D03*
Y1609386D03*
X530091Y1607286D03*
Y1609386D03*
X536851Y1583088D03*
X548911D03*
X545311D03*
X536851Y1585188D03*
X548911D03*
X545311D03*
X538551Y1607286D03*
Y1609386D03*
X542151Y1607286D03*
Y1609386D03*
X560971Y1583088D03*
X557371D03*
X560971Y1585188D03*
X557371D03*
X550611Y1607286D03*
Y1609386D03*
X554211Y1607286D03*
Y1609386D03*
X562671Y1607286D03*
Y1609386D03*
X566271Y1607286D03*
Y1609386D03*
X573031Y1583088D03*
X569431D03*
X581491D03*
X573031Y1585188D03*
X569431D03*
X581491D03*
X574731Y1607286D03*
Y1609386D03*
X578331Y1607286D03*
Y1609386D03*
X585091Y1583088D03*
X597151D03*
X593551D03*
X585091Y1585188D03*
X597151D03*
X593551D03*
X586791Y1607286D03*
Y1609386D03*
X590391Y1607286D03*
Y1609386D03*
X598851Y1607286D03*
Y1609386D03*
X609211Y1583088D03*
X605611D03*
X609211Y1585188D03*
X605611D03*
X602451Y1607286D03*
Y1609386D03*
X610911Y1607286D03*
Y1609386D03*
X614511Y1607286D03*
Y1609386D03*
X621271Y1583088D03*
X617671D03*
X629731D03*
X621271Y1585188D03*
X617671D03*
X629731D03*
X622971Y1607286D03*
Y1609386D03*
X626571Y1607286D03*
Y1609386D03*
X633331Y1583088D03*
X645391D03*
X641791D03*
X633331Y1585188D03*
X645391D03*
X641791D03*
X635031Y1607286D03*
Y1609386D03*
X638631Y1607286D03*
Y1609386D03*
X647091Y1607286D03*
Y1609386D03*
X657451Y1583088D03*
X653851D03*
X657451Y1585188D03*
X653851D03*
X650691Y1607286D03*
Y1609386D03*
X662751Y1607286D03*
Y1609386D03*
X659151Y1607286D03*
Y1609386D03*
X1196672Y1583088D03*
X1200272D03*
X1196672Y1585188D03*
X1200272D03*
X1212332Y1583088D03*
X1208732D03*
X1212332Y1585188D03*
X1208732D03*
X1201972Y1607286D03*
Y1609386D03*
X1205572Y1607286D03*
Y1609386D03*
X1214032Y1607286D03*
Y1609386D03*
X1232852Y1583088D03*
X1220792D03*
X1224392D03*
X1232852Y1585188D03*
X1220792D03*
X1224392D03*
X1229692Y1607286D03*
Y1609386D03*
X1226092Y1607286D03*
Y1609386D03*
X1217632Y1607286D03*
Y1609386D03*
X1244912Y1583088D03*
X1248512D03*
X1236452D03*
X1244912Y1585188D03*
X1248512D03*
X1236452D03*
X1241752Y1607286D03*
Y1609386D03*
X1238152Y1607286D03*
Y1609386D03*
X1256972Y1583088D03*
X1260572D03*
X1256972Y1585188D03*
X1260572D03*
X1253812Y1607286D03*
Y1609386D03*
X1250212Y1607286D03*
Y1609386D03*
X1265872Y1607286D03*
Y1609386D03*
X1262272Y1607286D03*
Y1609386D03*
X1281092Y1583088D03*
X1269032D03*
X1272632D03*
X1281092Y1585188D03*
X1269032D03*
X1272632D03*
X1277932Y1607286D03*
Y1609386D03*
X1274332Y1607286D03*
Y1609386D03*
X1293152Y1583088D03*
X1296752D03*
X1284692D03*
X1293152Y1585188D03*
X1296752D03*
X1284692D03*
X1289992Y1607286D03*
Y1609386D03*
X1286392Y1607286D03*
Y1609386D03*
X1298452Y1607286D03*
Y1609386D03*
X1305212Y1583088D03*
X1308812D03*
X1305212Y1585188D03*
X1308812D03*
X1310512Y1607286D03*
Y1609386D03*
X1314112Y1607286D03*
Y1609386D03*
X1302052Y1607286D03*
Y1609386D03*
X1329332Y1583088D03*
X1317272D03*
X1320872D03*
X1329332Y1585188D03*
X1317272D03*
X1320872D03*
X1322572Y1607286D03*
Y1609386D03*
X1326172Y1607286D03*
Y1609386D03*
X1344585Y276790D03*
Y274690D03*
X1341392Y1583088D03*
X1344992D03*
X1332932D03*
X1341392Y1585188D03*
X1344992D03*
X1332932D03*
X1338232Y1607286D03*
Y1609386D03*
X1334632Y1607286D03*
Y1609386D03*
X1346692Y1607286D03*
Y1609386D03*
X1353285Y278690D03*
Y276590D03*
X1356885Y278690D03*
Y276590D03*
X1348185Y276790D03*
Y274690D03*
X1361385Y274160D03*
Y272060D03*
X1353452Y1583088D03*
X1357052D03*
X1353452Y1585188D03*
X1357052D03*
X1350292Y1607286D03*
Y1609386D03*
X1358752Y1607286D03*
Y1609386D03*
X1362352Y1607286D03*
Y1609386D03*
X1364985Y274160D03*
Y272060D03*
X1377572Y1583088D03*
X1365512D03*
X1369112D03*
X1377572Y1585188D03*
X1365512D03*
X1369112D03*
X1374412Y1607286D03*
Y1609386D03*
X1370812Y1607286D03*
Y1609386D03*
X1381172Y1583088D03*
Y1585188D03*
X1386472Y1607286D03*
Y1609386D03*
X1382872Y1607286D03*
Y1609386D03*
X1474255Y1583088D03*
X1465795D03*
X1462195D03*
X1474255Y1585188D03*
X1465795D03*
X1462195D03*
X1467495Y1607286D03*
Y1609386D03*
X1471095Y1607286D03*
Y1609386D03*
X1486315Y1583088D03*
X1489915D03*
X1477855D03*
X1486315Y1585188D03*
X1489915D03*
X1477855D03*
X1479555Y1607286D03*
Y1609386D03*
X1483155Y1607286D03*
Y1609386D03*
X1491615Y1607286D03*
Y1609386D03*
X1501975Y1583088D03*
X1498375D03*
X1501975Y1585188D03*
X1498375D03*
X1495215Y1607286D03*
Y1609386D03*
X1503675Y1607286D03*
Y1609386D03*
X1507275Y1607286D03*
Y1609386D03*
X1526095Y1583088D03*
X1522495D03*
X1514035D03*
X1510435D03*
X1526095Y1585188D03*
X1522495D03*
X1514035D03*
X1510435D03*
X1515735Y1607286D03*
Y1609386D03*
X1519335Y1607286D03*
Y1609386D03*
X1535496Y64391D03*
Y62291D03*
X1539096Y64391D03*
Y62291D03*
X1534555Y1583088D03*
X1538155D03*
X1534555Y1585188D03*
X1538155D03*
X1527795Y1607286D03*
Y1609386D03*
X1531395Y1607286D03*
Y1609386D03*
X1539855Y1607286D03*
Y1609386D03*
X1557496Y64391D03*
Y62291D03*
X1546496Y70391D03*
Y68291D03*
X1550096Y70391D03*
Y68291D03*
X1558675Y1583088D03*
X1546615D03*
X1550215D03*
X1558675Y1585188D03*
X1546615D03*
X1550215D03*
X1543455Y1607286D03*
Y1609386D03*
X1551915Y1607286D03*
Y1609386D03*
X1555515Y1607286D03*
Y1609386D03*
X1568496Y70391D03*
Y68291D03*
X1572096Y70391D03*
Y68291D03*
X1561096Y64391D03*
Y62291D03*
X1574335Y1583088D03*
X1570735D03*
X1562275D03*
X1574335Y1585188D03*
X1570735D03*
X1562275D03*
X1563975Y1607286D03*
Y1609386D03*
X1567575Y1607286D03*
Y1609386D03*
X1579496Y64391D03*
Y62291D03*
X1583096Y64391D03*
Y62291D03*
X1590496Y70391D03*
Y68291D03*
X1582795Y1583088D03*
X1586395D03*
X1582795Y1585188D03*
X1586395D03*
X1576035Y1607286D03*
Y1609386D03*
X1579635Y1607286D03*
Y1609386D03*
X1588095Y1607286D03*
Y1609386D03*
X1601496Y64391D03*
Y62291D03*
X1605096Y64391D03*
Y62291D03*
X1594096Y70391D03*
Y68291D03*
X1606915Y1583088D03*
X1598455D03*
X1594855D03*
X1606915Y1585188D03*
X1598455D03*
X1594855D03*
X1591695Y1607286D03*
Y1609386D03*
X1600155Y1607286D03*
Y1609386D03*
X1603755Y1607286D03*
Y1609386D03*
X1623496Y64391D03*
Y62291D03*
X1616096Y70391D03*
Y68291D03*
X1612496Y70391D03*
Y68291D03*
X1618975Y1583088D03*
X1622575D03*
X1610515D03*
X1618975Y1585188D03*
X1622575D03*
X1610515D03*
X1612215Y1607286D03*
Y1609386D03*
X1615815Y1607286D03*
Y1609386D03*
X1627096Y64391D03*
Y62291D03*
X1635700Y70391D03*
Y68291D03*
X1639300Y70391D03*
Y68291D03*
X1634635Y1583088D03*
X1631035D03*
X1634635Y1585188D03*
X1631035D03*
X1624275Y1607286D03*
Y1609386D03*
X1627875Y1607286D03*
Y1609386D03*
X1636335Y1607286D03*
Y1609386D03*
X1639935Y1607286D03*
Y1609386D03*
X1650300Y64391D03*
Y62291D03*
X1646700Y64391D03*
Y62291D03*
X1643095Y1583088D03*
X1646695D03*
X1643095Y1585188D03*
X1646695D03*
X1651995Y1607286D03*
Y1609386D03*
X1648395Y1607286D03*
Y1609386D03*
X1672300Y64391D03*
Y62291D03*
X1668700Y64391D03*
Y62291D03*
X1661300Y70391D03*
Y68291D03*
X1657700Y70391D03*
Y68291D03*
X1679834Y70391D03*
Y68291D03*
X1683434Y70391D03*
Y68291D03*
X1701834Y70391D03*
Y68291D03*
X1694434Y64391D03*
Y62291D03*
X1690834Y64391D03*
Y62291D03*
X1705434Y70391D03*
Y68291D03*
G54D38*
X68365Y707219D03*
X76265D03*
X68365Y714219D03*
X76265D03*
X185667Y704526D03*
Y697526D03*
X282640Y217602D03*
Y224602D03*
X531220Y295862D03*
Y288862D03*
X764850Y253292D03*
Y260292D03*
X958452Y157603D03*
Y164603D03*
X969390Y212089D03*
Y205089D03*
X979708Y150885D03*
Y157885D03*
X1000582Y273824D03*
Y280824D03*
X1016175Y273690D03*
Y280690D03*
X1008445Y273690D03*
Y280690D03*
X1527618Y296386D03*
Y303386D03*
X1535048Y296386D03*
Y303386D03*
X1667570Y414332D03*
Y421332D03*
X1671306Y584056D03*
Y591056D03*
X1679850Y428172D03*
Y435172D03*
X1689697Y718205D03*
Y711205D03*
X1681797Y718205D03*
Y711205D03*
X1698170Y231982D03*
Y224982D03*
X1747050Y197522D03*
X1740120Y197592D03*
X1747050Y204522D03*
X1740120Y204592D03*
X1784826Y276996D03*
Y283996D03*
X1798926Y273096D03*
Y280096D03*
X1791826Y276996D03*
Y283996D03*
X1790326Y298028D03*
X1797326D03*
X1804326D03*
X1790326Y305028D03*
X1797326D03*
X1804326D03*
X1805986Y273159D03*
Y280159D03*
X1813086Y273159D03*
Y280159D03*
X1811386Y297965D03*
Y304965D03*
X1816784Y1515171D03*
Y1522171D03*
X1823684Y1515171D03*
X1830584D03*
X1823684Y1522171D03*
X1830584D03*
G54D167*
X489429Y1404569D03*
X500453Y1417955D03*
X1465570Y1404569D03*
X1476594Y1417955D03*
G54D284*
X1758539Y298879D03*
X1772319D03*
G54D275*
X1745799Y1516211D03*
X1779963D03*
G54D83*
X163642Y1387393D03*
X201785D03*
X317625Y1345539D03*
X349753Y1322741D03*
X381881Y1309315D03*
X414009D03*
X446137D03*
X478265D03*
X510393Y1322741D03*
X542521Y1345539D03*
X677261Y1387418D03*
X715404D03*
X1136953Y1423722D03*
X1175096D03*
X1293886Y1345775D03*
X1325894Y1322741D03*
X1358022Y1309315D03*
X1390150D03*
X1422278D03*
X1454406D03*
X1486534Y1322741D03*
X1518662Y1345539D03*
X1638427Y1421014D03*
X1676570D03*
G54D56*
X95132Y1534944D03*
G54D47*
X89981Y714088D03*
X1703413Y718214D03*
G54D266*
X1554724Y211909D03*
Y236909D03*
G54D149*
X416155Y1404128D03*
Y1405702D03*
Y1407277D03*
Y1408852D03*
Y1410427D03*
Y1412002D03*
Y1413576D03*
Y1415151D03*
Y1416726D03*
Y1418301D03*
Y1419876D03*
Y1421450D03*
X438793Y1404128D03*
Y1421450D03*
Y1419876D03*
Y1418301D03*
Y1416726D03*
Y1415151D03*
Y1413576D03*
Y1412002D03*
Y1410427D03*
Y1408852D03*
Y1407277D03*
Y1405702D03*
X1392296Y1404128D03*
Y1405702D03*
Y1407277D03*
Y1408852D03*
Y1410427D03*
Y1412002D03*
Y1413576D03*
Y1415151D03*
Y1416726D03*
Y1418301D03*
Y1419876D03*
Y1421450D03*
X1414934Y1404128D03*
Y1421450D03*
Y1419876D03*
Y1418301D03*
Y1416726D03*
Y1415151D03*
Y1413576D03*
Y1412002D03*
Y1410427D03*
Y1408852D03*
Y1407277D03*
Y1405702D03*
G54D257*
X1295929Y166699D03*
Y162999D03*
Y159299D03*
Y185199D03*
Y181499D03*
Y177799D03*
Y174099D03*
Y170399D03*
Y196299D03*
Y192599D03*
Y188899D03*
Y199999D03*
Y214799D03*
Y211099D03*
Y207399D03*
Y203699D03*
Y222199D03*
Y218499D03*
X1305544Y168549D03*
X1311955D03*
X1299134D03*
X1302340Y166699D03*
X1308749D03*
X1305544Y164849D03*
X1311955D03*
X1299134D03*
X1302340Y162999D03*
X1308749D03*
X1305544Y161149D03*
X1311955D03*
X1299134D03*
X1302340Y159299D03*
X1308749D03*
X1305544Y157449D03*
X1311955D03*
X1299134D03*
X1302340Y185199D03*
X1308749D03*
X1305544Y183349D03*
X1311955D03*
X1299134D03*
X1302340Y181499D03*
X1308749D03*
X1305544Y179649D03*
X1311955D03*
X1299134D03*
X1302340Y177799D03*
X1308749D03*
X1305544Y175949D03*
X1311955D03*
X1299134D03*
X1302340Y174099D03*
X1308749D03*
X1305544Y172249D03*
X1311955D03*
X1299134D03*
X1302340Y170399D03*
X1308749D03*
X1302340Y196299D03*
X1308749D03*
X1305544Y194449D03*
X1311955D03*
X1299134D03*
X1302340Y192599D03*
X1308749D03*
X1305544Y190749D03*
X1311955D03*
X1299134D03*
X1302340Y188899D03*
X1308749D03*
X1305544Y187049D03*
X1311955D03*
X1299134D03*
X1302340Y199999D03*
X1308749D03*
X1305544Y198149D03*
X1311955D03*
X1299134D03*
X1305544Y216649D03*
X1311955D03*
X1299134D03*
X1302340Y214799D03*
X1308749D03*
X1305544Y212949D03*
X1311955D03*
X1299134D03*
X1302340Y211099D03*
X1308749D03*
X1305544Y209249D03*
X1311955D03*
X1299134D03*
X1302340Y207399D03*
X1308749D03*
X1305544Y205549D03*
X1311955D03*
X1299134D03*
X1302340Y203699D03*
X1308749D03*
X1305544Y201849D03*
X1311955D03*
X1299134D03*
X1305544Y224049D03*
X1311955D03*
X1299134D03*
X1302340Y222199D03*
X1308749D03*
X1305544Y220349D03*
X1311955D03*
X1299134D03*
X1302340Y218499D03*
X1308749D03*
X1318364Y168549D03*
X1324775D03*
X1315160Y166699D03*
X1321570D03*
X1327979D03*
X1318364Y164849D03*
X1324775D03*
X1315160Y162999D03*
X1321570D03*
X1327979D03*
X1318364Y161149D03*
X1324775D03*
X1315160Y159299D03*
X1321570D03*
X1327979D03*
X1318364Y157449D03*
X1324775D03*
X1316927Y184449D03*
X1320077D03*
X1323227D03*
X1326377D03*
X1329527D03*
X1316927Y181299D03*
X1320077D03*
X1323227D03*
X1326377D03*
X1329527D03*
X1316927Y178149D03*
X1320077D03*
X1323227D03*
X1326377D03*
X1329527D03*
X1315160Y174099D03*
X1321570D03*
X1327979D03*
X1318364Y172249D03*
X1324775D03*
X1315160Y170399D03*
X1321570D03*
X1327979D03*
X1316927Y197049D03*
X1320077D03*
X1323227D03*
X1326377D03*
X1329527D03*
X1316927Y193899D03*
X1320077D03*
X1323227D03*
X1326377D03*
X1329527D03*
X1316927Y190749D03*
X1320077D03*
X1323227D03*
X1326377D03*
X1329527D03*
X1316927Y187599D03*
X1320077D03*
X1323227D03*
X1326377D03*
X1329527D03*
X1316927Y200199D03*
X1320077D03*
X1323227D03*
X1326377D03*
X1329527D03*
X1318364Y216649D03*
X1324775D03*
X1315160Y214799D03*
X1321570D03*
X1327979D03*
X1318364Y212949D03*
X1324775D03*
X1315160Y211099D03*
X1321570D03*
X1327979D03*
X1318364Y209249D03*
X1324775D03*
X1315160Y207399D03*
X1321570D03*
X1327979D03*
X1316927Y203349D03*
X1320077D03*
X1323227D03*
X1326377D03*
X1329527D03*
X1318364Y224049D03*
X1324775D03*
X1315160Y222199D03*
X1321570D03*
X1327979D03*
X1318364Y220349D03*
X1324775D03*
X1315160Y218499D03*
X1321570D03*
X1327979D03*
X1331184Y168549D03*
X1337594D03*
X1344005D03*
X1334390Y166699D03*
X1340799D03*
X1347210D03*
X1331184Y164849D03*
X1337594D03*
X1344005D03*
X1334390Y162999D03*
X1340799D03*
X1347210D03*
X1331184Y161149D03*
X1337594D03*
X1344005D03*
X1334390Y159299D03*
X1340799D03*
X1347210D03*
X1331184Y157449D03*
X1337594D03*
X1344005D03*
X1332677Y184449D03*
X1335827D03*
X1340799Y185199D03*
X1347210D03*
X1344005Y183349D03*
X1332677Y181299D03*
X1335827D03*
X1340799Y181499D03*
X1347210D03*
X1344005Y179649D03*
X1332677Y178149D03*
X1335827D03*
X1340799Y177799D03*
X1347210D03*
X1344005Y175949D03*
X1334390Y174099D03*
X1340799D03*
X1347210D03*
X1331184Y172249D03*
X1337594D03*
X1344005D03*
X1334390Y170399D03*
X1340799D03*
X1347210D03*
X1332677Y197049D03*
X1335827D03*
X1340799Y196299D03*
X1347210D03*
X1332677Y193899D03*
X1335827D03*
X1344005Y194449D03*
X1340799Y192599D03*
X1347210D03*
X1332677Y190749D03*
X1335827D03*
X1344005D03*
X1340799Y188899D03*
X1347210D03*
X1332677Y187599D03*
X1335827D03*
X1344005Y187049D03*
X1332677Y200199D03*
X1335827D03*
X1340799Y199999D03*
X1347210D03*
X1344005Y198149D03*
X1331184Y216649D03*
X1337594D03*
X1344005D03*
X1334390Y214799D03*
X1340799D03*
X1347210D03*
X1331184Y212949D03*
X1337594D03*
X1344005D03*
X1334390Y211099D03*
X1340799D03*
X1347210D03*
X1331184Y209249D03*
X1337594D03*
X1344005D03*
X1334390Y207399D03*
X1340799D03*
X1347210D03*
X1344005Y205549D03*
X1332677Y203349D03*
X1335827D03*
X1340799Y203699D03*
X1347210D03*
X1344005Y201849D03*
X1331184Y224049D03*
X1337594D03*
X1344005D03*
X1334390Y222199D03*
X1340799D03*
X1347210D03*
X1331184Y220349D03*
X1337594D03*
X1344005D03*
X1334390Y218499D03*
X1340799D03*
X1347210D03*
X1350414Y168549D03*
X1356825D03*
X1353620Y166699D03*
X1350414Y164849D03*
X1356825D03*
X1353620Y162999D03*
X1350414Y161149D03*
X1356825D03*
X1353620Y159299D03*
X1350414Y157449D03*
X1356825D03*
X1353620Y185199D03*
X1350414Y183349D03*
X1356825D03*
X1353620Y181499D03*
X1350414Y179649D03*
X1356825D03*
X1353620Y177799D03*
X1350414Y175949D03*
X1356825D03*
X1353620Y174099D03*
X1350414Y172249D03*
X1356825D03*
X1353620Y170399D03*
Y196299D03*
X1350414Y194449D03*
X1356825D03*
X1353620Y192599D03*
X1350414Y190749D03*
X1356825D03*
X1353620Y188899D03*
X1350414Y187049D03*
X1356825D03*
X1353620Y199999D03*
X1350414Y198149D03*
X1356825D03*
X1350414Y216649D03*
X1356825D03*
X1353620Y214799D03*
X1350414Y212949D03*
X1356825D03*
X1353620Y211099D03*
X1350414Y209249D03*
X1356825D03*
X1353620Y207399D03*
X1350414Y205549D03*
X1356825D03*
X1353620Y203699D03*
X1350414Y201849D03*
X1356825D03*
X1350414Y224049D03*
X1356825D03*
X1353620Y222199D03*
X1350414Y220349D03*
X1356825D03*
X1353620Y218499D03*
G54D158*
X464818Y303145D03*
Y305114D03*
Y307082D03*
Y309051D03*
X470654D03*
Y307082D03*
Y305114D03*
X498218Y302445D03*
Y304414D03*
Y306382D03*
Y308351D03*
X504054D03*
Y306382D03*
Y304414D03*
G54D239*
X1126004Y1537244D03*
X1180926D03*
G54D39*
X77416Y1534944D03*
G54D249*
X1270142Y134311D03*
G54D276*
X1766878Y222028D03*
Y266320D03*
G54D159*
X467150Y1422842D03*
X463410Y1431504D03*
X470890D03*
X854820Y430793D03*
X858560Y422131D03*
X851080D03*
X1067070Y365631D03*
X1059590D03*
X1063330Y374293D03*
X1443482Y1423962D03*
X1439742Y1432624D03*
X1447222D03*
G54D267*
X1595750Y128005D03*
Y159305D03*
X1613466Y128005D03*
Y159305D03*
G54D177*
X611000Y491201D03*
Y503799D03*
X627000Y491201D03*
X619000D03*
X627000Y503799D03*
X619000D03*
X635000Y491201D03*
Y503799D03*
G54D66*
X110757Y388071D03*
Y392071D03*
X113907Y388071D03*
D03*
X117057D03*
X113907Y392071D03*
D03*
X117057D03*
X155226Y425383D03*
X158376D03*
D03*
X155226Y421383D03*
X158376D03*
D03*
X155226Y417383D03*
X158376D03*
D03*
X155226Y443319D03*
X158376D03*
D03*
Y439397D03*
X155226D03*
X158376D03*
Y435383D03*
X155226D03*
X158376D03*
X155226Y430883D03*
X158376D03*
D03*
X161526Y425383D03*
Y421383D03*
Y417383D03*
Y443319D03*
Y439397D03*
Y435383D03*
Y430883D03*
X235147Y127118D03*
X238297D03*
X1013620Y226423D03*
X1016770D03*
X1671605Y201670D03*
X1674755D03*
X1710268Y128242D03*
X1713418D03*
G54D84*
X157638Y1390937D03*
X195781D03*
X311621Y1349083D03*
X343749Y1326285D03*
X375877Y1312859D03*
X408005D03*
X440133D03*
X472261D03*
X504389Y1326285D03*
X536517Y1349083D03*
X671257Y1390962D03*
X709400D03*
X1130949Y1427266D03*
X1169092D03*
X1287882Y1349319D03*
X1319890Y1326285D03*
X1352018Y1312859D03*
X1384146D03*
X1416274D03*
X1448402D03*
X1480530Y1326285D03*
X1512658Y1349083D03*
X1632423Y1424558D03*
X1670566D03*
G54D75*
X109960Y1687921D03*
Y1685362D03*
Y1682803D03*
X102480D03*
Y1685362D03*
Y1687921D03*
X109960Y1696362D03*
Y1693803D03*
X102480D03*
Y1696362D03*
X109960Y1698921D03*
X102480D03*
X462060Y1645841D03*
Y1643282D03*
Y1640723D03*
X454580D03*
Y1643282D03*
Y1645841D03*
X558240Y311616D03*
Y309057D03*
Y306498D03*
X550760D03*
Y309057D03*
Y311616D03*
X658960Y1722921D03*
Y1720362D03*
Y1717803D03*
X651480D03*
Y1720362D03*
Y1722921D03*
X674880Y1668303D03*
Y1670862D03*
Y1673421D03*
X682360D03*
Y1670862D03*
Y1668303D03*
X1408250Y1600723D03*
Y1603282D03*
Y1605841D03*
X1415730Y1600723D03*
Y1605841D03*
Y1603282D03*
G54D258*
X1285767Y165146D03*
Y161207D03*
Y184841D03*
Y180902D03*
Y176963D03*
Y173024D03*
Y169085D03*
Y196657D03*
Y192718D03*
Y188780D03*
Y200596D03*
Y216352D03*
Y212413D03*
Y208474D03*
Y204535D03*
Y220291D03*
X1366987Y165146D03*
Y161207D03*
Y184841D03*
Y180902D03*
Y176963D03*
Y173024D03*
Y169085D03*
Y196657D03*
Y192718D03*
Y188780D03*
Y200596D03*
Y216352D03*
Y212413D03*
Y208474D03*
Y204535D03*
Y220291D03*
G54D57*
X93361Y1533173D03*
G54D48*
X91949Y714088D03*
X1705381Y718214D03*
G54D195*
X777283Y317392D03*
X771377D03*
X808793Y264580D03*
X802887D03*
G54D93*
X174685Y637367D03*
X174393Y668511D03*
X205159Y1430034D03*
X393067Y1354446D03*
X422833D03*
X453169D03*
X468443Y1379662D03*
X482543Y1353962D03*
X526478Y1439952D03*
X718638Y1429579D03*
X1077638Y133866D03*
X1178470Y1466363D03*
X1369208Y1353946D03*
X1398974D03*
X1429310D03*
X1444043Y1379362D03*
X1459076Y1353946D03*
X1502956Y1439530D03*
X1682882Y618174D03*
Y669109D03*
X1679944Y1463655D03*
X1769790Y194789D03*
X1799350D03*
X1836248Y269763D03*
Y299056D03*
G54D186*
X719199Y1579320D03*
Y1581092D03*
Y1582864D03*
Y1584635D03*
Y1586407D03*
Y1588178D03*
Y1589950D03*
Y1591722D03*
X744691Y1582864D03*
Y1581092D03*
Y1579320D03*
Y1591722D03*
Y1589950D03*
Y1588178D03*
Y1586407D03*
Y1584635D03*
G54D168*
X489626Y1417955D03*
X1465767D03*
G54D285*
X1795857Y1510765D03*
G54D58*
X91786Y1533173D03*
X90211D03*
X88636D03*
X87061D03*
X85487D03*
X83912D03*
X82337D03*
X80762D03*
G54D277*
X1765429Y287264D03*
G54D196*
X771066Y440803D03*
X764374D03*
Y445921D03*
X771066D03*
G54D76*
X145624Y386885D03*
Y389385D03*
Y391885D03*
Y394385D03*
Y396885D03*
Y399385D03*
Y401885D03*
Y404385D03*
X166530Y396885D03*
Y394385D03*
Y391885D03*
Y389385D03*
Y386885D03*
Y404385D03*
Y401885D03*
Y399385D03*
G54D178*
X615480Y520299D03*
X629480Y512425D03*
X619220D03*
X622960Y520299D03*
X633220D03*
X636960Y512425D03*
X759289Y143438D03*
X763029Y151312D03*
X766769Y143438D03*
X805480Y425425D03*
X809220Y433299D03*
X812960Y425425D03*
X1194713Y118101D03*
X1198453Y110227D03*
X1190973D03*
X1656896Y187187D03*
X1660636Y179313D03*
X1664376Y187187D03*
G54D49*
X94311Y710347D03*
Y706411D03*
Y708379D03*
X87619Y706411D03*
Y710347D03*
X1701051Y710537D03*
Y714473D03*
X1707743D03*
Y710537D03*
Y712505D03*
G54D67*
X102982Y405071D03*
X109982D03*
X141545Y694807D03*
X141339Y702835D03*
X141363Y710840D03*
X141387Y717660D03*
X148545Y694807D03*
X148339Y702835D03*
X155187Y717660D03*
X155163Y710840D03*
X148363D03*
X148387Y717660D03*
X162187D03*
X162163Y710840D03*
X177043Y1409915D03*
X187866Y410549D03*
X180866D03*
X184043Y1409915D03*
X225347Y1420975D03*
X218347D03*
X225086Y1409915D03*
X218086D03*
X225347Y1427783D03*
X218347D03*
X255965Y70636D03*
X255669Y78930D03*
X244518Y667750D03*
X251518D03*
X262965Y70636D03*
X262669Y78930D03*
X286300Y210812D03*
X293300D03*
X411430Y1157520D03*
X418430D03*
X411430Y1165570D03*
X418430D03*
X430930Y1157520D03*
X423930D03*
X436430D03*
Y1165570D03*
X430930D03*
X423930D03*
X443430Y1157520D03*
X448930D03*
X443430Y1165570D03*
X448930D03*
X455930Y1157520D03*
X461430D03*
X468430D03*
X455930Y1165570D03*
X461430D03*
X468430D03*
X501082Y1381027D03*
X494082D03*
X501123Y1389027D03*
X494123D03*
X501123Y1397027D03*
X494123D03*
X507350Y97542D03*
X514350D03*
X685720Y83362D03*
X692720D03*
X697662Y1409940D03*
X690662D03*
X740860Y1401205D03*
X733860D03*
X739210Y1418365D03*
X732210D03*
X739200Y1410025D03*
X732200D03*
X855576Y234068D03*
X862576D03*
X1119440Y1566630D03*
X1111440D03*
X1115440Y1575430D03*
X1150354Y1446244D03*
X1157354D03*
X1195500Y182362D03*
X1188500D03*
X1195000Y198362D03*
X1188000D03*
X1200582Y1436732D03*
X1193582D03*
X1198552Y1453022D03*
X1191552D03*
X1198592Y1446212D03*
X1191592D03*
X1292008Y54121D03*
X1285008D03*
X1292008Y62321D03*
X1285008D03*
X1387720Y1157520D03*
X1394720D03*
X1387720Y1165570D03*
X1394720D03*
X1407220Y1157520D03*
X1400220D03*
X1412720D03*
X1407220Y1165570D03*
X1400220D03*
X1412720D03*
X1425220Y1157520D03*
X1419720D03*
Y1165570D03*
X1425220D03*
X1432220Y1157520D03*
X1437720D03*
X1444720D03*
X1437720Y1165570D03*
X1444720D03*
X1432220D03*
X1478658Y316356D03*
X1477223Y1381027D03*
X1470223D03*
X1477264Y1389027D03*
X1470264D03*
X1477264Y1397027D03*
X1470264D03*
X1485658Y316356D03*
X1602455Y620832D03*
X1609455D03*
X1651828Y1443536D03*
X1658828D03*
X1702057Y1435332D03*
X1695057D03*
X1700597Y1451935D03*
X1693597D03*
X1700317Y1443505D03*
X1693317D03*
X1718649Y1501870D03*
Y1509920D03*
X1729326Y71930D03*
X1736326D03*
X1729100Y80474D03*
X1736100D03*
X1725649Y1501870D03*
Y1509920D03*
X1755295Y716472D03*
X1755271Y708121D03*
X1755319Y724523D03*
X1747245Y1457671D03*
X1740245D03*
X1753145Y1482171D03*
Y1489371D03*
X1762477Y699940D03*
X1755477D03*
X1762295Y716472D03*
X1762271Y708121D03*
X1762319Y724523D03*
X1760145Y1482171D03*
Y1489371D03*
G54D286*
X1803633Y1521592D03*
G54D259*
X1302744Y148170D03*
X1306683D03*
X1310621D03*
X1298805D03*
X1302744Y233328D03*
X1306683D03*
X1310621D03*
X1298805D03*
X1314560Y148170D03*
X1318499D03*
X1322438D03*
X1326377D03*
X1330316D03*
X1314560Y233328D03*
X1318499D03*
X1322438D03*
X1326377D03*
X1330316D03*
X1334255Y148170D03*
X1338194D03*
X1342133D03*
X1346071D03*
X1334255Y233328D03*
X1338194D03*
X1342133D03*
X1346071D03*
X1350010Y148170D03*
X1353949D03*
X1350010Y233328D03*
X1353949D03*
G54D268*
X1633305Y638527D03*
Y672527D03*
Y706527D03*
G54D94*
X174685Y647210D03*
X174393Y678354D03*
X195316Y1430034D03*
X383224Y1354446D03*
X412990D03*
X443326D03*
X458600Y1379662D03*
X472700Y1353962D03*
X526478Y1449795D03*
X708795Y1429579D03*
X1168627Y1466363D03*
X1359365Y1353946D03*
X1389131D03*
X1419467D03*
X1434200Y1379362D03*
X1449233Y1353946D03*
X1502956Y1449373D03*
X1670101Y1463655D03*
X1682882Y628017D03*
Y678952D03*
X1769790Y204632D03*
X1799350D03*
X1826405Y269763D03*
Y299056D03*
G54D85*
X155807Y1403338D03*
X157579D03*
X159351D03*
X171752D03*
X169981D03*
X168209D03*
X166437D03*
X164666D03*
X161122D03*
X162894D03*
X207183Y572606D03*
Y606606D03*
Y640606D03*
X208124Y1403338D03*
X206352D03*
X204580D03*
X202809D03*
X193950D03*
X195722D03*
X197494D03*
X199265D03*
X201037D03*
X216042Y572606D03*
X214270D03*
X212498D03*
X210727D03*
X208955D03*
X216042Y606606D03*
X214270D03*
X212498D03*
X210727D03*
X208955D03*
X216042Y640606D03*
X214270D03*
X212498D03*
X210727D03*
X208955D03*
X209895Y1403338D03*
X289206Y149291D03*
X287237D03*
X285269D03*
X283300D03*
Y160315D03*
X285269D03*
X287237D03*
X289206D03*
X322192Y1361484D03*
X320420D03*
X318649D03*
X309790D03*
X311562D03*
X313334D03*
X315105D03*
X316877D03*
X325735D03*
X323964D03*
X354320Y1338686D03*
X352548D03*
X350777D03*
X341918D03*
X343690D03*
X345462D03*
X347233D03*
X349005D03*
X357863D03*
X356092D03*
X386448Y1325260D03*
X384676D03*
X382905D03*
X374046D03*
X375818D03*
X377590D03*
X379361D03*
X381133D03*
X389991D03*
X388220D03*
X418576D03*
X416804D03*
X415033D03*
X406174D03*
X407946D03*
X409718D03*
X411489D03*
X413261D03*
X422119D03*
X420348D03*
X450704D03*
X448932D03*
X447161D03*
X438302D03*
X440074D03*
X441846D03*
X443617D03*
X445389D03*
X454247D03*
X452476D03*
X484604D03*
X482832D03*
X481060D03*
X479289D03*
X470430D03*
X472202D03*
X473974D03*
X475745D03*
X477517D03*
X486375D03*
X516732Y1338686D03*
X514960D03*
X513188D03*
X511417D03*
X502558D03*
X504330D03*
X506102D03*
X507873D03*
X509645D03*
X518503D03*
X548860Y1361484D03*
X547088D03*
X545316D03*
X543545D03*
X534686D03*
X536458D03*
X538230D03*
X540001D03*
X541773D03*
X550631D03*
X598203Y200466D03*
Y211490D03*
X604109Y200466D03*
X602140D03*
X600172D03*
Y211490D03*
X602140D03*
X604109D03*
X680056Y1403363D03*
X678285D03*
X669426D03*
X671198D03*
X672970D03*
X674741D03*
X676513D03*
X685371D03*
X683600D03*
X681828D03*
X707569D03*
X709341D03*
X711113D03*
X723514D03*
X721743D03*
X719971D03*
X718199D03*
X716428D03*
X712884D03*
X714656D03*
X826467Y131386D03*
X824498D03*
X822530D03*
X820561D03*
Y142410D03*
X822530D03*
X824498D03*
X826467D03*
X850432Y208879D03*
X848463D03*
X846495D03*
X844526D03*
Y219903D03*
X846495D03*
X848463D03*
X850432D03*
X1129118Y1439667D03*
X1130890D03*
X1132662D03*
X1134433D03*
X1145063D03*
X1143292D03*
X1141520D03*
X1139748D03*
X1137977D03*
X1136205D03*
X1167261D03*
X1183206D03*
X1181435D03*
X1179663D03*
X1177891D03*
X1176120D03*
X1169033D03*
X1170805D03*
X1172576D03*
X1174348D03*
X1171728Y1630732D03*
X1173697D03*
X1175665D03*
X1177634D03*
Y1619708D03*
X1175665D03*
X1173697D03*
X1171728D03*
X1296681Y1361720D03*
X1294910D03*
X1286051D03*
X1287823D03*
X1289595D03*
X1291366D03*
X1293138D03*
X1301996D03*
X1300225D03*
X1298453D03*
X1330461Y1338686D03*
X1328689D03*
X1326918D03*
X1318059D03*
X1319831D03*
X1321603D03*
X1323374D03*
X1325146D03*
X1334004D03*
X1332233D03*
X1362589Y1325260D03*
X1360817D03*
X1359046D03*
X1350187D03*
X1351959D03*
X1353731D03*
X1355502D03*
X1357274D03*
X1366132D03*
X1364361D03*
X1394717D03*
X1392945D03*
X1391174D03*
X1382315D03*
X1384087D03*
X1385859D03*
X1387630D03*
X1389402D03*
X1398260D03*
X1396489D03*
X1426845D03*
X1425073D03*
X1423302D03*
X1414443D03*
X1416215D03*
X1417987D03*
X1419758D03*
X1421530D03*
X1430388D03*
X1428617D03*
X1460745D03*
X1458973D03*
X1457201D03*
X1455430D03*
X1446571D03*
X1448343D03*
X1450115D03*
X1451886D03*
X1453658D03*
X1462516D03*
X1492873Y1338686D03*
X1491101D03*
X1489329D03*
X1487558D03*
X1478699D03*
X1480471D03*
X1482243D03*
X1484014D03*
X1485786D03*
X1494644D03*
X1525001Y1361484D03*
X1523229D03*
X1521457D03*
X1519686D03*
X1510827D03*
X1512599D03*
X1514371D03*
X1516142D03*
X1517914D03*
X1526772D03*
X1637931Y647976D03*
X1639703D03*
X1637931Y681976D03*
X1639703D03*
X1637931Y715976D03*
X1639703D03*
X1639451Y1436959D03*
X1630592D03*
X1632364D03*
X1634136D03*
X1635907D03*
X1637679D03*
X1641475Y647976D03*
X1643246D03*
X1645018D03*
X1646790D03*
X1641475Y681976D03*
X1643246D03*
X1645018D03*
X1646790D03*
X1641475Y715976D03*
X1643246D03*
X1645018D03*
X1646790D03*
X1646537Y1436959D03*
X1644766D03*
X1642994D03*
X1641222D03*
X1668735D03*
X1670507D03*
X1672279D03*
X1684680D03*
X1682909D03*
X1681137D03*
X1679365D03*
X1677594D03*
X1674050D03*
X1675822D03*
X1735976Y364872D03*
X1734008D03*
X1732039D03*
Y375896D03*
X1734008D03*
X1735976D03*
X1737945Y364872D03*
Y375896D03*
G54D187*
X728402Y1576712D03*
X726630D03*
X724858D03*
X723087D03*
X721315D03*
Y1594330D03*
X723087D03*
X724858D03*
X726630D03*
X728402D03*
X742575Y1576712D03*
X740803D03*
X739032D03*
X737260D03*
X735488D03*
X733717D03*
X731945D03*
X730173D03*
Y1594330D03*
X731945D03*
X733717D03*
X735488D03*
X737260D03*
X739032D03*
X740803D03*
X742575D03*
G54D169*
X489429Y1406538D03*
Y1408112D03*
Y1409687D03*
Y1411262D03*
Y1412837D03*
Y1414412D03*
Y1415986D03*
X1465570Y1406538D03*
Y1408112D03*
Y1409687D03*
Y1411262D03*
Y1412837D03*
Y1414412D03*
Y1415986D03*
G54D86*
X160197Y1396941D03*
X198340D03*
X314180Y1355087D03*
X346308Y1332289D03*
X378436Y1318863D03*
X410564D03*
X442692D03*
X474820D03*
X506948Y1332289D03*
X539076Y1355087D03*
X673816Y1396966D03*
X711959D03*
X1133508Y1433270D03*
X1171651D03*
X1290441Y1355323D03*
X1322449Y1332289D03*
X1354577Y1318863D03*
X1386705D03*
X1418833D03*
X1450961D03*
X1483089Y1332289D03*
X1515217Y1355087D03*
X1634982Y1430562D03*
X1673125D03*
G54D95*
X168666Y716471D03*
X180084D03*
X290586Y624181D03*
X302004D03*
X1575511Y735362D03*
Y744362D03*
X1586929Y735362D03*
Y744362D03*
G54D188*
X726010Y1627615D03*
X722270D03*
X718530D03*
Y1638245D03*
X726010D03*
X803540Y372315D03*
X799800D03*
X796060D03*
Y382945D03*
X803540D03*
X842940Y430185D03*
X839200D03*
X835460D03*
Y440815D03*
X842940D03*
X956404Y1558189D03*
X951404D03*
X946404D03*
X961404D03*
X969770D03*
X984770D03*
X979770D03*
X974770D03*
X1003136D03*
X998136D03*
X993136D03*
X1008136D03*
X1021502D03*
X1016502D03*
X1031502D03*
X1026502D03*
X1054868D03*
X1049868D03*
X1044868D03*
X1039868D03*
X1068234D03*
X1063234D03*
X1078234D03*
X1073234D03*
X1086600D03*
X1101600D03*
X1096600D03*
X1091600D03*
X1735111Y1467176D03*
X1730111D03*
X1745111D03*
X1740111D03*
G54D68*
X105967Y421490D03*
Y424049D03*
Y426608D03*
Y429167D03*
Y431727D03*
Y434286D03*
Y436845D03*
Y439404D03*
X128015Y429167D03*
Y426608D03*
Y424049D03*
Y421490D03*
Y439404D03*
Y436845D03*
Y434286D03*
Y431727D03*
G54D269*
X1645030Y185952D03*
X1641290Y196188D03*
X1648770D03*
G54D197*
X793000Y1576714D03*
X791032D03*
X789063D03*
X787095D03*
X785126D03*
X783158D03*
Y1594332D03*
X785126D03*
X787095D03*
X789063D03*
X791032D03*
X793000D03*
X825158Y1576714D03*
Y1594332D03*
X835000Y1576714D03*
X833032D03*
X831063D03*
X829095D03*
X827126D03*
Y1594332D03*
X829095D03*
X831063D03*
X833032D03*
X835000D03*
X875032Y1576714D03*
X873063D03*
X871095D03*
X869126D03*
X867158D03*
Y1594332D03*
X869126D03*
X871095D03*
X873063D03*
X875032D03*
X877000Y1576714D03*
Y1594332D03*
X919000Y1576714D03*
X917032D03*
X915063D03*
X913095D03*
X911126D03*
X909158D03*
Y1594332D03*
X911126D03*
X913095D03*
X915063D03*
X917032D03*
X919000D03*
G54D59*
X79187Y1533173D03*
G54D77*
X139961Y514305D03*
X484294Y1415339D03*
X1460804Y1415333D03*
X1653854Y644285D03*
X1689755Y541673D03*
G54D179*
X640246Y197466D03*
Y221966D03*
X791526Y125647D03*
Y150147D03*
X882183Y213783D03*
Y238283D03*
G54D278*
X1765429Y276192D03*
G54D287*
X1806657Y1502389D03*
G54D96*
X169744Y1396960D03*
X207887D03*
X323727Y1355106D03*
X355855Y1332308D03*
X387983Y1318882D03*
X420111D03*
X452239D03*
X484367D03*
X516495Y1332308D03*
X548623Y1355106D03*
X683363Y1396985D03*
X721506D03*
X1143055Y1433289D03*
X1181198D03*
X1299988Y1355342D03*
X1331996Y1332308D03*
X1364124Y1318882D03*
X1396252D03*
X1428380D03*
X1460508D03*
X1492636Y1332308D03*
X1524764Y1355106D03*
X1644529Y1430581D03*
X1682672D03*
G54D78*
X144883Y1725289D03*
Y1727848D03*
Y1730408D03*
Y1732967D03*
X170829Y1707678D03*
Y1710237D03*
Y1712797D03*
Y1715356D03*
X162461Y1730408D03*
Y1727848D03*
Y1725289D03*
Y1732967D03*
X188407Y1712797D03*
Y1710237D03*
Y1707678D03*
Y1715356D03*
X1422534Y1562932D03*
Y1565491D03*
Y1568051D03*
Y1570610D03*
X1440112Y1568051D03*
Y1565491D03*
Y1562932D03*
Y1570610D03*
G54D69*
X112578Y517044D03*
X115704Y635278D03*
X1662285Y543813D03*
X1702700Y498681D03*
G54D189*
X726830Y1659065D03*
X719350D03*
X723090Y1668395D03*
X785400Y365335D03*
X781660Y374665D03*
X789140D03*
X824800Y434035D03*
X821060Y443365D03*
X828540D03*
G54D198*
X781189Y1576664D03*
Y1594382D03*
X794969Y1576664D03*
Y1594382D03*
X823189Y1576664D03*
Y1594382D03*
X836969Y1576664D03*
Y1594382D03*
X865189Y1576664D03*
Y1594382D03*
X878969Y1576664D03*
Y1594382D03*
X907189Y1576664D03*
Y1594382D03*
X920969Y1576664D03*
Y1594382D03*
G54D279*
X1772468Y284558D03*
G54D87*
X154193Y1392019D03*
Y1393791D03*
Y1395563D03*
Y1397334D03*
Y1399106D03*
Y1400878D03*
X192336Y1392019D03*
Y1393791D03*
Y1395563D03*
Y1397334D03*
Y1399106D03*
Y1400878D03*
X204723Y574220D03*
Y590165D03*
Y588394D03*
Y586622D03*
Y584850D03*
Y583079D03*
Y575992D03*
Y577764D03*
Y579535D03*
Y581307D03*
Y608220D03*
Y624165D03*
Y622394D03*
Y620622D03*
Y618850D03*
Y617079D03*
Y609992D03*
Y611764D03*
Y613535D03*
Y615307D03*
Y656394D03*
Y654622D03*
Y652850D03*
Y651079D03*
Y642220D03*
Y643992D03*
Y645764D03*
Y647535D03*
Y649307D03*
Y658165D03*
X280741Y151850D03*
Y153819D03*
Y155787D03*
Y157756D03*
X291765Y151850D03*
Y157756D03*
Y155787D03*
Y153819D03*
X308176Y1350165D03*
Y1351937D03*
Y1353709D03*
Y1355480D03*
Y1357252D03*
Y1359024D03*
X340304Y1327367D03*
Y1329139D03*
Y1330911D03*
Y1332682D03*
Y1334454D03*
Y1336226D03*
X372432Y1313941D03*
Y1315713D03*
Y1317485D03*
Y1319256D03*
Y1321028D03*
Y1322800D03*
X404560Y1313941D03*
Y1315713D03*
Y1317485D03*
Y1319256D03*
Y1321028D03*
Y1322800D03*
X436688Y1313941D03*
Y1315713D03*
Y1317485D03*
Y1319256D03*
Y1321028D03*
Y1322800D03*
X468816Y1313941D03*
Y1315713D03*
Y1317485D03*
Y1319256D03*
Y1321028D03*
Y1322800D03*
X500944Y1327367D03*
Y1329139D03*
Y1330911D03*
Y1332682D03*
Y1334454D03*
Y1336226D03*
X533072Y1350165D03*
Y1351937D03*
Y1353709D03*
Y1355480D03*
Y1357252D03*
Y1359024D03*
X595644Y203025D03*
Y204994D03*
Y206962D03*
Y208931D03*
X606668D03*
Y206962D03*
Y204994D03*
Y203025D03*
X667812Y1392044D03*
Y1393816D03*
Y1395588D03*
Y1397359D03*
Y1399131D03*
Y1400903D03*
X705955Y1392044D03*
Y1393816D03*
Y1395588D03*
Y1397359D03*
Y1399131D03*
Y1400903D03*
X818002Y133945D03*
Y135914D03*
Y137882D03*
Y139851D03*
X829026Y135914D03*
Y133945D03*
Y139851D03*
Y137882D03*
X841967Y211438D03*
Y213407D03*
Y215375D03*
Y217344D03*
X852991D03*
Y215375D03*
Y213407D03*
Y211438D03*
X1127504Y1428348D03*
Y1430120D03*
Y1431892D03*
Y1433663D03*
Y1435435D03*
Y1437207D03*
X1165647Y1428348D03*
Y1430120D03*
Y1431892D03*
Y1433663D03*
Y1435435D03*
Y1437207D03*
X1180193Y1628173D03*
Y1626204D03*
Y1624236D03*
Y1622267D03*
X1169169D03*
Y1624236D03*
Y1626204D03*
Y1628173D03*
X1284437Y1350401D03*
Y1352173D03*
Y1353945D03*
Y1355716D03*
Y1357488D03*
Y1359260D03*
X1316445Y1327367D03*
Y1329139D03*
Y1330911D03*
Y1332682D03*
Y1334454D03*
Y1336226D03*
X1348573Y1313941D03*
Y1315713D03*
Y1317485D03*
Y1319256D03*
Y1321028D03*
Y1322800D03*
X1380701Y1313941D03*
Y1315713D03*
Y1317485D03*
Y1319256D03*
Y1321028D03*
Y1322800D03*
X1412829Y1313941D03*
Y1315713D03*
Y1317485D03*
Y1319256D03*
Y1321028D03*
Y1322800D03*
X1444957Y1313941D03*
Y1315713D03*
Y1317485D03*
Y1319256D03*
Y1321028D03*
Y1322800D03*
X1477085Y1327367D03*
Y1329139D03*
Y1330911D03*
Y1332682D03*
Y1334454D03*
Y1336226D03*
X1509213Y1350165D03*
Y1351937D03*
Y1353709D03*
Y1355480D03*
Y1357252D03*
Y1359024D03*
X1628978Y1425640D03*
Y1427412D03*
Y1429184D03*
Y1430955D03*
Y1432727D03*
Y1434499D03*
X1649250Y630417D03*
Y632188D03*
Y633960D03*
Y635732D03*
Y637503D03*
Y639275D03*
Y646362D03*
Y644590D03*
Y642818D03*
Y641047D03*
Y664417D03*
Y666188D03*
Y667960D03*
Y669732D03*
Y671503D03*
Y673275D03*
Y680362D03*
Y678590D03*
Y676818D03*
Y675047D03*
Y698417D03*
Y700188D03*
Y701960D03*
Y703732D03*
Y705503D03*
Y714362D03*
Y712590D03*
Y710818D03*
Y709047D03*
Y707275D03*
X1667121Y1425640D03*
Y1427412D03*
Y1429184D03*
Y1430955D03*
Y1432727D03*
Y1434499D03*
X1729480Y367431D03*
Y369400D03*
Y371368D03*
Y373337D03*
X1740504D03*
Y371368D03*
Y369400D03*
Y367431D03*
G54D288*
X1809624Y1502387D03*
G54D289*
G01X-6350Y-464479D02*
Y-539479D01*
X493650D01*
Y-464479D01*
X-6350D01*
G01X5650Y-529479D02*
Y-534479D01*
G01X4193Y-529479D02*
X7107D01*
G01X12017Y-534479D02*
X9483D01*
Y-529479D01*
X12017D01*
G01X11003Y-531896D02*
X9483D01*
G01X14583Y-529479D02*
Y-534479D01*
X17117D01*
G01X20950Y-534646D02*
X20823Y-534562D01*
Y-534396D01*
X20950Y-534312D01*
X21077Y-534396D01*
Y-534562D01*
X20950Y-534646D01*
G01Y-532396D02*
X20823Y-532312D01*
Y-532146D01*
X20950Y-532062D01*
X21077Y-532146D01*
Y-532312D01*
X20950Y-532396D01*
G01X25733Y-536146D02*
X25100Y-535312D01*
X24783Y-534479D01*
Y-531146D01*
X25100Y-530312D01*
X25733Y-529479D01*
G01X31150D02*
X30643Y-529646D01*
X30263Y-530062D01*
X30010Y-530562D01*
X29820Y-531229D01*
X29757Y-531979D01*
X29820Y-532729D01*
X30010Y-533396D01*
X30263Y-533896D01*
X30643Y-534312D01*
X31150Y-534479D01*
X31657Y-534312D01*
X32037Y-533896D01*
X32290Y-533396D01*
X32480Y-532729D01*
X32543Y-531979D01*
X32480Y-531229D01*
X32290Y-530562D01*
X32037Y-530062D01*
X31657Y-529646D01*
X31150Y-529479D01*
G01X34857Y-533479D02*
X35237Y-534062D01*
X35743Y-534396D01*
X36313Y-534479D01*
X36820Y-534396D01*
X37327Y-533979D01*
X37643Y-533479D01*
X37707Y-532979D01*
X37580Y-532396D01*
X37137Y-531979D01*
X36693Y-531812D01*
X36123D01*
G01X36693D02*
X37073Y-531562D01*
X37390Y-531146D01*
X37517Y-530646D01*
X37390Y-530146D01*
X37073Y-529729D01*
X36503Y-529479D01*
X35933Y-529562D01*
X35363Y-529896D01*
G01X41667Y-536146D02*
X42300Y-535312D01*
X42617Y-534479D01*
Y-531146D01*
X42300Y-530312D01*
X41667Y-529479D01*
G01X45057Y-533479D02*
X45437Y-534062D01*
X45943Y-534396D01*
X46513Y-534479D01*
X47020Y-534396D01*
X47527Y-533979D01*
X47843Y-533479D01*
X47907Y-532979D01*
X47780Y-532396D01*
X47337Y-531979D01*
X46893Y-531812D01*
X46323D01*
G01X46893D02*
X47273Y-531562D01*
X47590Y-531146D01*
X47717Y-530646D01*
X47590Y-530146D01*
X47273Y-529729D01*
X46703Y-529479D01*
X46133Y-529562D01*
X45563Y-529896D01*
G01X50347Y-530312D02*
X50727Y-529812D01*
X51170Y-529562D01*
X51677Y-529479D01*
X52310Y-529646D01*
X52753Y-530062D01*
X52880Y-530562D01*
X52817Y-531062D01*
X52563Y-531479D01*
X51297Y-532312D01*
X50727Y-532896D01*
X50347Y-533729D01*
X50220Y-534479D01*
X52880D01*
G01X56523D02*
X56650Y-533396D01*
X56840Y-532479D01*
X57093Y-531646D01*
X57410Y-530729D01*
X57917Y-529479D01*
X55383D01*
G01X60927Y-532812D02*
X62573D01*
G01X65647Y-530312D02*
X66027Y-529812D01*
X66470Y-529562D01*
X66977Y-529479D01*
X67610Y-529646D01*
X68053Y-530062D01*
X68180Y-530562D01*
X68117Y-531062D01*
X67863Y-531479D01*
X66597Y-532312D01*
X66027Y-532896D01*
X65647Y-533729D01*
X65520Y-534479D01*
X68180D01*
G01X70557Y-533479D02*
X70937Y-534062D01*
X71443Y-534396D01*
X72013Y-534479D01*
X72520Y-534396D01*
X73027Y-533979D01*
X73343Y-533479D01*
X73407Y-532979D01*
X73280Y-532396D01*
X72837Y-531979D01*
X72393Y-531812D01*
X71823D01*
G01X72393D02*
X72773Y-531562D01*
X73090Y-531146D01*
X73217Y-530646D01*
X73090Y-530146D01*
X72773Y-529729D01*
X72203Y-529479D01*
X71633Y-529562D01*
X71063Y-529896D01*
G01X77810Y-534479D02*
Y-529479D01*
X75467Y-533062D01*
X78633D01*
G01X80757Y-533729D02*
X81137Y-534146D01*
X81580Y-534396D01*
X82150Y-534479D01*
X82720Y-534312D01*
X83163Y-533979D01*
X83480Y-533396D01*
X83543Y-532729D01*
X83417Y-532062D01*
X83100Y-531646D01*
X82657Y-531312D01*
X82213Y-531229D01*
X81770Y-531312D01*
X81200Y-531646D01*
X81390Y-529479D01*
X83100D01*
G01X91147Y-534479D02*
Y-529479D01*
X93553D01*
G01X92667Y-531896D02*
X91147D01*
G01X95867Y-534479D02*
X97450Y-529479D01*
X99033Y-534479D01*
G01X98463Y-532729D02*
X96437D01*
G01X101220Y-534479D02*
X103880Y-529479D01*
G01X101220D02*
X103880Y-534479D01*
G01X107650Y-534646D02*
X107523Y-534562D01*
Y-534396D01*
X107650Y-534312D01*
X107777Y-534396D01*
Y-534562D01*
X107650Y-534646D01*
G01Y-532396D02*
X107523Y-532312D01*
Y-532146D01*
X107650Y-532062D01*
X107777Y-532146D01*
Y-532312D01*
X107650Y-532396D01*
G01X112433Y-536146D02*
X111800Y-535312D01*
X111483Y-534479D01*
Y-531146D01*
X111800Y-530312D01*
X112433Y-529479D01*
G01X117850D02*
X117343Y-529646D01*
X116963Y-530062D01*
X116710Y-530562D01*
X116520Y-531229D01*
X116457Y-531979D01*
X116520Y-532729D01*
X116710Y-533396D01*
X116963Y-533896D01*
X117343Y-534312D01*
X117850Y-534479D01*
X118357Y-534312D01*
X118737Y-533896D01*
X118990Y-533396D01*
X119180Y-532729D01*
X119243Y-531979D01*
X119180Y-531229D01*
X118990Y-530562D01*
X118737Y-530062D01*
X118357Y-529646D01*
X117850Y-529479D01*
G01X121557Y-533479D02*
X121937Y-534062D01*
X122443Y-534396D01*
X123013Y-534479D01*
X123520Y-534396D01*
X124027Y-533979D01*
X124343Y-533479D01*
X124407Y-532979D01*
X124280Y-532396D01*
X123837Y-531979D01*
X123393Y-531812D01*
X122823D01*
G01X123393D02*
X123773Y-531562D01*
X124090Y-531146D01*
X124217Y-530646D01*
X124090Y-530146D01*
X123773Y-529729D01*
X123203Y-529479D01*
X122633Y-529562D01*
X122063Y-529896D01*
G01X128367Y-536146D02*
X129000Y-535312D01*
X129317Y-534479D01*
Y-531146D01*
X129000Y-530312D01*
X128367Y-529479D01*
G01X131757Y-533479D02*
X132137Y-534062D01*
X132643Y-534396D01*
X133213Y-534479D01*
X133720Y-534396D01*
X134227Y-533979D01*
X134543Y-533479D01*
X134607Y-532979D01*
X134480Y-532396D01*
X134037Y-531979D01*
X133593Y-531812D01*
X133023D01*
G01X133593D02*
X133973Y-531562D01*
X134290Y-531146D01*
X134417Y-530646D01*
X134290Y-530146D01*
X133973Y-529729D01*
X133403Y-529479D01*
X132833Y-529562D01*
X132263Y-529896D01*
G01X137173Y-533896D02*
X137617Y-534312D01*
X138123Y-534479D01*
X138630Y-534312D01*
X139073Y-533812D01*
X139390Y-533062D01*
X139517Y-532312D01*
Y-531396D01*
X139390Y-530646D01*
X139073Y-529979D01*
X138693Y-529646D01*
X138250Y-529479D01*
X137743Y-529646D01*
X137363Y-529979D01*
X137110Y-530479D01*
X136983Y-531146D01*
X137110Y-531729D01*
X137427Y-532312D01*
X137807Y-532646D01*
X138250Y-532729D01*
X138757Y-532562D01*
X139137Y-532146D01*
X139517Y-531396D01*
G01X143223Y-534479D02*
X143350Y-533396D01*
X143540Y-532479D01*
X143793Y-531646D01*
X144110Y-530729D01*
X144617Y-529479D01*
X142083D01*
G01X147627Y-532812D02*
X149273D01*
G01X152157Y-533479D02*
X152537Y-534062D01*
X153043Y-534396D01*
X153613Y-534479D01*
X154120Y-534396D01*
X154627Y-533979D01*
X154943Y-533479D01*
X155007Y-532979D01*
X154880Y-532396D01*
X154437Y-531979D01*
X153993Y-531812D01*
X153423D01*
G01X153993D02*
X154373Y-531562D01*
X154690Y-531146D01*
X154817Y-530646D01*
X154690Y-530146D01*
X154373Y-529729D01*
X153803Y-529479D01*
X153233Y-529562D01*
X152663Y-529896D01*
G01X157447Y-532396D02*
X157890Y-531812D01*
X158270Y-531479D01*
X158777Y-531312D01*
X159220Y-531479D01*
X159537Y-531812D01*
X159790Y-532312D01*
X159853Y-532896D01*
X159790Y-533396D01*
X159537Y-533896D01*
X159157Y-534312D01*
X158713Y-534479D01*
X158207Y-534312D01*
X157763Y-533812D01*
X157510Y-533062D01*
X157447Y-532229D01*
X157573Y-531146D01*
X157763Y-530562D01*
X158080Y-529979D01*
X158523Y-529562D01*
X158967Y-529479D01*
X159410Y-529646D01*
X159727Y-530062D01*
G01X163750Y-534479D02*
Y-529479D01*
X162990Y-530479D01*
G01Y-534479D02*
X164510D01*
G01X169610D02*
Y-529479D01*
X167267Y-533062D01*
X170433D01*
G01X188650Y-464479D02*
Y-539479D01*
G01Y-514479D02*
X291650D01*
Y-489479D01*
G01X188650D02*
X291650D01*
G01Y-464479D02*
Y-539479D01*
G01X293650Y-464479D02*
Y-539479D01*
G01X299157Y-524479D02*
Y-519479D01*
X300423D01*
X300930Y-519729D01*
X301310Y-520062D01*
X301627Y-520562D01*
X301880Y-521146D01*
X301943Y-521979D01*
X301880Y-522812D01*
X301627Y-523396D01*
X301310Y-523896D01*
X300930Y-524229D01*
X300423Y-524479D01*
X299157D01*
G01X304067D02*
X305650Y-519479D01*
X307233Y-524479D01*
G01X306663Y-522729D02*
X304637D01*
G01X310750Y-519479D02*
Y-524479D01*
G01X309293Y-519479D02*
X312207D01*
G01X317117Y-524479D02*
X314583D01*
Y-519479D01*
X317117D01*
G01X316103Y-521896D02*
X314583D01*
G01X320950Y-524646D02*
X320823Y-524562D01*
Y-524396D01*
X320950Y-524312D01*
X321077Y-524396D01*
Y-524562D01*
X320950Y-524646D01*
G01Y-522396D02*
X320823Y-522312D01*
Y-522146D01*
X320950Y-522062D01*
X321077Y-522146D01*
Y-522312D01*
X320950Y-522396D01*
G01X299283Y-499479D02*
Y-494479D01*
X300803D01*
X301310Y-494729D01*
X301690Y-495312D01*
X301817Y-495979D01*
X301690Y-496646D01*
X301373Y-497146D01*
X300803Y-497396D01*
X299283D01*
G01X304510Y-499646D02*
X306790Y-494479D01*
G01X309293Y-499479D02*
Y-494479D01*
X312207Y-499479D01*
Y-494479D01*
G01X315850Y-499646D02*
X315723Y-499562D01*
Y-499396D01*
X315850Y-499312D01*
X315977Y-499396D01*
Y-499562D01*
X315850Y-499646D01*
G01Y-497396D02*
X315723Y-497312D01*
Y-497146D01*
X315850Y-497062D01*
X315977Y-497146D01*
Y-497312D01*
X315850Y-497396D01*
G01X293650Y-514479D02*
X493650D01*
G01X293650Y-489479D02*
X493650D01*
G01X299283Y-474479D02*
Y-469479D01*
X300803D01*
X301310Y-469729D01*
X301690Y-470312D01*
X301817Y-470979D01*
X301690Y-471646D01*
X301373Y-472146D01*
X300803Y-472396D01*
X299283D01*
G01X304383Y-474479D02*
Y-469479D01*
X305967D01*
X306473Y-469729D01*
X306790Y-470062D01*
X306917Y-470729D01*
X306790Y-471396D01*
X306410Y-471812D01*
X305967Y-472062D01*
X304383D01*
G01X305967D02*
X306917Y-474479D01*
G01X310750D02*
X310243Y-474396D01*
X309800Y-474062D01*
X309420Y-473562D01*
X309167Y-472979D01*
X309040Y-472312D01*
Y-471646D01*
X309167Y-470979D01*
X309420Y-470396D01*
X309800Y-469896D01*
X310243Y-469562D01*
X310750Y-469479D01*
X311257Y-469562D01*
X311700Y-469896D01*
X312080Y-470396D01*
X312333Y-470979D01*
X312460Y-471646D01*
Y-472312D01*
X312333Y-472979D01*
X312080Y-473562D01*
X311700Y-474062D01*
X311257Y-474396D01*
X310750Y-474479D01*
G01X314583Y-473479D02*
X314900Y-473979D01*
X315280Y-474312D01*
X315723Y-474479D01*
X316230Y-474312D01*
X316610Y-473979D01*
X316990Y-473479D01*
X317117Y-472812D01*
Y-469479D01*
G01X322217Y-474479D02*
X319683D01*
Y-469479D01*
X322217D01*
G01X321203Y-471896D02*
X319683D01*
G01X327443Y-469896D02*
X327063Y-469646D01*
X326620Y-469479D01*
X326113D01*
X325543Y-469729D01*
X325100Y-470146D01*
X324783Y-470646D01*
X324530Y-471479D01*
X324467Y-472229D01*
X324593Y-472979D01*
X324783Y-473479D01*
X325163Y-473979D01*
X325607Y-474312D01*
X326050Y-474479D01*
X326493D01*
X326937Y-474312D01*
X327317Y-474062D01*
X327633Y-473729D01*
G01X331150Y-469479D02*
Y-474479D01*
G01X329693Y-469479D02*
X332607D01*
G01X336250Y-474646D02*
X336123Y-474562D01*
Y-474396D01*
X336250Y-474312D01*
X336377Y-474396D01*
Y-474562D01*
X336250Y-474646D01*
G01Y-472396D02*
X336123Y-472312D01*
Y-472146D01*
X336250Y-472062D01*
X336377Y-472146D01*
Y-472312D01*
X336250Y-472396D01*
G01X408650Y-514479D02*
Y-539479D01*
G01X411283Y-516979D02*
Y-521979D01*
X413817D01*
G01X416890Y-516979D02*
X418410D01*
G01X417650D02*
Y-521979D01*
G01X416890D02*
X418410D01*
G01X423257Y-519312D02*
X423510Y-519062D01*
X423700Y-518646D01*
X423827Y-518062D01*
X423700Y-517562D01*
X423447Y-517229D01*
X423003Y-516979D01*
X421293D01*
Y-521979D01*
X423383D01*
X423827Y-521646D01*
X424080Y-521146D01*
X424207Y-520562D01*
X424080Y-519979D01*
X423700Y-519479D01*
X423257Y-519312D01*
X421293D01*
G01X427850Y-522146D02*
X427723Y-522062D01*
Y-521896D01*
X427850Y-521812D01*
X427977Y-521896D01*
Y-522062D01*
X427850Y-522146D01*
G01Y-519896D02*
X427723Y-519812D01*
Y-519646D01*
X427850Y-519562D01*
X427977Y-519646D01*
Y-519812D01*
X427850Y-519896D01*
G01X451650Y-514479D02*
Y-539479D01*
G01Y-489479D02*
Y-514479D01*
G01X456663Y-541646D02*
X456770Y-541521D01*
X456850Y-541312D01*
X456903Y-541021D01*
X456850Y-540771D01*
X456743Y-540604D01*
X456557Y-540479D01*
X455837D01*
Y-542979D01*
X456717D01*
X456903Y-542812D01*
X457010Y-542562D01*
X457063Y-542271D01*
X457010Y-541979D01*
X456850Y-541729D01*
X456663Y-541646D01*
X455837D01*
G01X459130Y-542979D02*
Y-541312D01*
G01Y-541604D02*
X459023Y-541437D01*
X458863Y-541354D01*
X458677Y-541312D01*
X458490Y-541396D01*
X458330Y-541562D01*
X458223Y-541812D01*
X458170Y-542146D01*
X458223Y-542479D01*
X458330Y-542729D01*
X458490Y-542896D01*
X458677Y-542979D01*
X458863Y-542937D01*
X459023Y-542812D01*
X459130Y-542646D01*
G01X460450Y-542687D02*
X460583Y-542854D01*
X460770Y-542979D01*
X460930D01*
X461090Y-542896D01*
X461197Y-542771D01*
X461250Y-542604D01*
X461223Y-542354D01*
X461117Y-542229D01*
X460637Y-541979D01*
X460530Y-541687D01*
X460583Y-541479D01*
X460690Y-541354D01*
X460850Y-541312D01*
X461010Y-541354D01*
X461170Y-541479D01*
G01X462650Y-541854D02*
X463503D01*
X463423Y-541562D01*
X463290Y-541396D01*
X463103Y-541312D01*
X462917Y-541354D01*
X462757Y-541479D01*
X462650Y-541771D01*
X462597Y-542021D01*
Y-542271D01*
X462650Y-542521D01*
X462783Y-542771D01*
X462943Y-542937D01*
X463130Y-542979D01*
X463317Y-542896D01*
X463503Y-542646D01*
G01X464770Y-542979D02*
Y-540479D01*
G01Y-541729D02*
X464903Y-541479D01*
X465063Y-541354D01*
X465223Y-541312D01*
X465463Y-541396D01*
X465623Y-541562D01*
X465730Y-541854D01*
Y-542187D01*
X465677Y-542521D01*
X465570Y-542771D01*
X465383Y-542937D01*
X465223Y-542979D01*
X465063Y-542937D01*
X464903Y-542812D01*
X464770Y-542604D01*
G01X467450Y-542979D02*
X467290Y-542937D01*
X467130Y-542771D01*
X467023Y-542479D01*
X466970Y-542146D01*
X467023Y-541812D01*
X467130Y-541521D01*
X467290Y-541354D01*
X467450Y-541312D01*
X467610Y-541354D01*
X467770Y-541521D01*
X467877Y-541812D01*
X467903Y-542146D01*
X467877Y-542479D01*
X467770Y-542771D01*
X467610Y-542937D01*
X467450Y-542979D01*
G01X470130D02*
Y-541312D01*
G01Y-541604D02*
X470023Y-541437D01*
X469863Y-541354D01*
X469677Y-541312D01*
X469490Y-541396D01*
X469330Y-541562D01*
X469223Y-541812D01*
X469170Y-542146D01*
X469223Y-542479D01*
X469330Y-542729D01*
X469490Y-542896D01*
X469677Y-542979D01*
X469863Y-542937D01*
X470023Y-542812D01*
X470130Y-542646D01*
G01X471477Y-542979D02*
Y-541312D01*
G01Y-541646D02*
X471610Y-541479D01*
X471743Y-541354D01*
X471930Y-541312D01*
X472063Y-541354D01*
X472223Y-541479D01*
G01X474530Y-540479D02*
Y-542979D01*
G01Y-542604D02*
X474423Y-542812D01*
X474263Y-542937D01*
X474077Y-542979D01*
X473863Y-542896D01*
X473703Y-542687D01*
X473597Y-542437D01*
X473570Y-542146D01*
X473597Y-541854D01*
X473703Y-541604D01*
X473863Y-541396D01*
X474077Y-541312D01*
X474263Y-541354D01*
X474397Y-541437D01*
X474530Y-541604D01*
G01X477917Y-542979D02*
Y-540479D01*
X478583D01*
X478797Y-540604D01*
X478930Y-540771D01*
X478983Y-541104D01*
X478930Y-541437D01*
X478770Y-541646D01*
X478583Y-541771D01*
X477917D01*
G01X478583D02*
X478983Y-542979D01*
G01X480250Y-541854D02*
X481103D01*
X481023Y-541562D01*
X480890Y-541396D01*
X480703Y-541312D01*
X480517Y-541354D01*
X480357Y-541479D01*
X480250Y-541771D01*
X480197Y-542021D01*
Y-542271D01*
X480250Y-542521D01*
X480383Y-542771D01*
X480543Y-542937D01*
X480730Y-542979D01*
X480917Y-542896D01*
X481103Y-542646D01*
G01X482370Y-541312D02*
X482850Y-542979D01*
X483330Y-541312D01*
G01X485050Y-543062D02*
X484997Y-543021D01*
Y-542937D01*
X485050Y-542896D01*
X485103Y-542937D01*
Y-543021D01*
X485050Y-543062D01*
G01X487250Y-542979D02*
X487437Y-542937D01*
X487650Y-542812D01*
X487783Y-542604D01*
X487837Y-542312D01*
X487783Y-542021D01*
X487623Y-541771D01*
X487383Y-541646D01*
X487117D01*
X486957Y-541562D01*
X486823Y-541354D01*
X486770Y-541062D01*
X486850Y-540771D01*
X487037Y-540562D01*
X487250Y-540479D01*
X487463Y-540562D01*
X487650Y-540771D01*
X487730Y-541062D01*
X487677Y-541354D01*
X487543Y-541562D01*
X487383Y-541646D01*
X487117D01*
X486877Y-541771D01*
X486717Y-542021D01*
X486663Y-542312D01*
X486717Y-542604D01*
X486850Y-542812D01*
X487063Y-542937D01*
X487250Y-542979D01*
G01X489663Y-541646D02*
X489770Y-541521D01*
X489850Y-541312D01*
X489903Y-541021D01*
X489850Y-540771D01*
X489743Y-540604D01*
X489557Y-540479D01*
X488837D01*
Y-542979D01*
X489717D01*
X489903Y-542812D01*
X490010Y-542562D01*
X490063Y-542271D01*
X490010Y-541979D01*
X489850Y-541729D01*
X489663Y-541646D01*
X488837D01*
G01X455550Y-516979D02*
Y-521979D01*
G01X454093Y-516979D02*
X457007D01*
G01X460650Y-521979D02*
X460270Y-521896D01*
X459890Y-521562D01*
X459637Y-520979D01*
X459510Y-520312D01*
X459637Y-519646D01*
X459890Y-519062D01*
X460270Y-518729D01*
X460650Y-518646D01*
X461030Y-518729D01*
X461410Y-519062D01*
X461663Y-519646D01*
X461727Y-520312D01*
X461663Y-520979D01*
X461410Y-521562D01*
X461030Y-521896D01*
X460650Y-521979D01*
G01X465750D02*
X465370Y-521896D01*
X464990Y-521562D01*
X464737Y-520979D01*
X464610Y-520312D01*
X464737Y-519646D01*
X464990Y-519062D01*
X465370Y-518729D01*
X465750Y-518646D01*
X466130Y-518729D01*
X466510Y-519062D01*
X466763Y-519646D01*
X466827Y-520312D01*
X466763Y-520979D01*
X466510Y-521562D01*
X466130Y-521896D01*
X465750Y-521979D01*
G01X470850D02*
Y-516979D01*
G01X475950Y-522146D02*
X475823Y-522062D01*
Y-521896D01*
X475950Y-521812D01*
X476077Y-521896D01*
Y-522062D01*
X475950Y-522146D01*
G01Y-519896D02*
X475823Y-519812D01*
Y-519646D01*
X475950Y-519562D01*
X476077Y-519646D01*
Y-519812D01*
X475950Y-519896D01*
G01X454283Y-496979D02*
Y-491979D01*
X455867D01*
X456373Y-492229D01*
X456690Y-492562D01*
X456817Y-493229D01*
X456690Y-493896D01*
X456310Y-494312D01*
X455867Y-494562D01*
X454283D01*
G01X455867D02*
X456817Y-496979D01*
G01X461917D02*
X459383D01*
Y-491979D01*
X461917D01*
G01X460903Y-494396D02*
X459383D01*
G01X464167Y-491979D02*
X465750Y-496979D01*
X467333Y-491979D01*
G01X470850Y-497146D02*
X470723Y-497062D01*
Y-496896D01*
X470850Y-496812D01*
X470977Y-496896D01*
Y-497062D01*
X470850Y-497146D01*
G01Y-494896D02*
X470723Y-494812D01*
Y-494646D01*
X470850Y-494562D01*
X470977Y-494646D01*
Y-494812D01*
X470850Y-494896D01*
G01X-984580Y-698988D02*
Y4193602D01*
X5868320D01*
Y-698988D01*
X-984580D01*
G01X7723Y-521204D02*
X7253Y-520889D01*
X6705Y-520679D01*
X6078D01*
X5373Y-520994D01*
X4825Y-521519D01*
X4433Y-522149D01*
X4120Y-523199D01*
X4042Y-524144D01*
X4198Y-525089D01*
X4433Y-525719D01*
X4903Y-526349D01*
X5452Y-526769D01*
X6000Y-526979D01*
X6548D01*
X7097Y-526769D01*
X7567Y-526454D01*
X7958Y-526034D01*
G01X11360Y-520679D02*
X13240D01*
G01X12300D02*
Y-526979D01*
G01X11360D02*
X13240D01*
G01X18600Y-520679D02*
Y-526979D01*
G01X16798Y-520679D02*
X20402D01*
G01X24900Y-526979D02*
Y-524144D01*
X23333Y-520679D01*
G01X26467D02*
X24900Y-524144D01*
G01X35777Y-525719D02*
X36247Y-526454D01*
X36873Y-526874D01*
X37578Y-526979D01*
X38205Y-526874D01*
X38832Y-526349D01*
X39223Y-525719D01*
X39302Y-525089D01*
X39145Y-524354D01*
X38597Y-523829D01*
X38048Y-523619D01*
X37343D01*
G01X38048D02*
X38518Y-523304D01*
X38910Y-522779D01*
X39067Y-522149D01*
X38910Y-521519D01*
X38518Y-520994D01*
X37813Y-520679D01*
X37108Y-520784D01*
X36403Y-521204D01*
G01X42077Y-525719D02*
X42547Y-526454D01*
X43173Y-526874D01*
X43878Y-526979D01*
X44505Y-526874D01*
X45132Y-526349D01*
X45523Y-525719D01*
X45602Y-525089D01*
X45445Y-524354D01*
X44897Y-523829D01*
X44348Y-523619D01*
X43643D01*
G01X44348D02*
X44818Y-523304D01*
X45210Y-522779D01*
X45367Y-522149D01*
X45210Y-521519D01*
X44818Y-520994D01*
X44113Y-520679D01*
X43408Y-520784D01*
X42703Y-521204D01*
G01X48377Y-525719D02*
X48847Y-526454D01*
X49473Y-526874D01*
X50178Y-526979D01*
X50805Y-526874D01*
X51432Y-526349D01*
X51823Y-525719D01*
X51902Y-525089D01*
X51745Y-524354D01*
X51197Y-523829D01*
X50648Y-523619D01*
X49943D01*
G01X50648D02*
X51118Y-523304D01*
X51510Y-522779D01*
X51667Y-522149D01*
X51510Y-521519D01*
X51118Y-520994D01*
X50413Y-520679D01*
X49708Y-520784D01*
X49003Y-521204D01*
G01X56243Y-526979D02*
X56400Y-525614D01*
X56635Y-524459D01*
X56948Y-523409D01*
X57340Y-522254D01*
X57967Y-520679D01*
X54833D01*
G01X62543Y-526979D02*
X62700Y-525614D01*
X62935Y-524459D01*
X63248Y-523409D01*
X63640Y-522254D01*
X64267Y-520679D01*
X61133D01*
G01X68843Y-528134D02*
X69157Y-526769D01*
G01X75300Y-520679D02*
Y-526979D01*
G01X73498Y-520679D02*
X77102D01*
G01X79642Y-526979D02*
X81600Y-520679D01*
X83558Y-526979D01*
G01X82853Y-524774D02*
X80347D01*
G01X86960Y-520679D02*
X88840D01*
G01X87900D02*
Y-526979D01*
G01X86960D02*
X88840D01*
G01X91850Y-520679D02*
X92947Y-526979D01*
X94200Y-520679D01*
X95453Y-526979D01*
X96550Y-520679D01*
G01X98542Y-526979D02*
X100500Y-520679D01*
X102458Y-526979D01*
G01X101753Y-524774D02*
X99247D01*
G01X104998Y-526979D02*
Y-520679D01*
X108602Y-526979D01*
Y-520679D01*
G01X119008Y-529079D02*
X118225Y-528029D01*
X117833Y-526979D01*
Y-522779D01*
X118225Y-521729D01*
X119008Y-520679D01*
G01X130433Y-526979D02*
Y-520679D01*
X132392D01*
X133018Y-520994D01*
X133410Y-521414D01*
X133567Y-522254D01*
X133410Y-523094D01*
X132940Y-523619D01*
X132392Y-523934D01*
X130433D01*
G01X132392D02*
X133567Y-526979D01*
G01X138300Y-527189D02*
X138143Y-527084D01*
Y-526874D01*
X138300Y-526769D01*
X138457Y-526874D01*
Y-527084D01*
X138300Y-527189D01*
G01X144600Y-526979D02*
X143973Y-526874D01*
X143425Y-526454D01*
X142955Y-525824D01*
X142642Y-525089D01*
X142485Y-524249D01*
Y-523409D01*
X142642Y-522569D01*
X142955Y-521834D01*
X143425Y-521204D01*
X143973Y-520784D01*
X144600Y-520679D01*
X145227Y-520784D01*
X145775Y-521204D01*
X146245Y-521834D01*
X146558Y-522569D01*
X146715Y-523409D01*
Y-524249D01*
X146558Y-525089D01*
X146245Y-525824D01*
X145775Y-526454D01*
X145227Y-526874D01*
X144600Y-526979D01*
G01X150900Y-527189D02*
X150743Y-527084D01*
Y-526874D01*
X150900Y-526769D01*
X151057Y-526874D01*
Y-527084D01*
X150900Y-527189D01*
G01X158923Y-521204D02*
X158453Y-520889D01*
X157905Y-520679D01*
X157278D01*
X156573Y-520994D01*
X156025Y-521519D01*
X155633Y-522149D01*
X155320Y-523199D01*
X155242Y-524144D01*
X155398Y-525089D01*
X155633Y-525719D01*
X156103Y-526349D01*
X156652Y-526769D01*
X157200Y-526979D01*
X157748D01*
X158297Y-526769D01*
X158767Y-526454D01*
X159158Y-526034D01*
G01X163500Y-527189D02*
X163343Y-527084D01*
Y-526874D01*
X163500Y-526769D01*
X163657Y-526874D01*
Y-527084D01*
X163500Y-527189D01*
G01X170192Y-529079D02*
X170975Y-528029D01*
X171367Y-526979D01*
Y-522779D01*
X170975Y-521729D01*
X170192Y-520679D01*
G01X6470Y-513829D02*
X8037D01*
Y-515719D01*
X7567Y-516349D01*
X7018Y-516769D01*
X6235Y-516979D01*
X5452Y-516769D01*
X4903Y-516349D01*
X4433Y-515719D01*
X4120Y-514984D01*
X3963Y-514144D01*
Y-513409D01*
X4120Y-512779D01*
X4433Y-512044D01*
X4903Y-511414D01*
X5373Y-510994D01*
X6000Y-510679D01*
X6548D01*
X7175Y-510889D01*
X7645Y-511309D01*
G01X10577Y-510679D02*
Y-515194D01*
X10890Y-516139D01*
X11517Y-516769D01*
X12300Y-516979D01*
X13083Y-516769D01*
X13710Y-516139D01*
X14023Y-515194D01*
Y-510679D01*
G01X17660D02*
X19540D01*
G01X18600D02*
Y-516979D01*
G01X17660D02*
X19540D01*
G01X23255Y-516139D02*
X23882Y-516664D01*
X24587Y-516979D01*
X25213D01*
X25840Y-516664D01*
X26310Y-516139D01*
X26545Y-515404D01*
X26388Y-514669D01*
X25997Y-514039D01*
X25292Y-513619D01*
X24352Y-513409D01*
X23803Y-512989D01*
X23568Y-512254D01*
X23725Y-511519D01*
X24117Y-510994D01*
X24665Y-510679D01*
X25213D01*
X25762Y-510889D01*
X26232Y-511414D01*
G01X29555Y-516979D02*
Y-510679D01*
G01X32845D02*
Y-516979D01*
G01Y-513829D02*
X29555D01*
G01X35542Y-516979D02*
X37500Y-510679D01*
X39458Y-516979D01*
G01X38753Y-514774D02*
X36247D01*
G01X41998Y-516979D02*
Y-510679D01*
X45602Y-516979D01*
Y-510679D01*
G01X54677Y-516979D02*
Y-510679D01*
X56243D01*
X56870Y-510994D01*
X57340Y-511414D01*
X57732Y-512044D01*
X58045Y-512779D01*
X58123Y-513829D01*
X58045Y-514879D01*
X57732Y-515614D01*
X57340Y-516244D01*
X56870Y-516664D01*
X56243Y-516979D01*
X54677D01*
G01X61760Y-510679D02*
X63640D01*
G01X62700D02*
Y-516979D01*
G01X61760D02*
X63640D01*
G01X67355Y-516139D02*
X67982Y-516664D01*
X68687Y-516979D01*
X69313D01*
X69940Y-516664D01*
X70410Y-516139D01*
X70645Y-515404D01*
X70488Y-514669D01*
X70097Y-514039D01*
X69392Y-513619D01*
X68452Y-513409D01*
X67903Y-512989D01*
X67668Y-512254D01*
X67825Y-511519D01*
X68217Y-510994D01*
X68765Y-510679D01*
X69313D01*
X69862Y-510889D01*
X70332Y-511414D01*
G01X75300Y-510679D02*
Y-516979D01*
G01X73498Y-510679D02*
X77102D01*
G01X81600Y-517189D02*
X81443Y-517084D01*
Y-516874D01*
X81600Y-516769D01*
X81757Y-516874D01*
Y-517084D01*
X81600Y-517189D01*
G01X87743Y-518134D02*
X88057Y-516769D01*
G01X94200Y-510679D02*
Y-516979D01*
G01X92398Y-510679D02*
X96002D01*
G01X98542Y-516979D02*
X100500Y-510679D01*
X102458Y-516979D01*
G01X101753Y-514774D02*
X99247D01*
G01X106800Y-516979D02*
X106173Y-516874D01*
X105625Y-516454D01*
X105155Y-515824D01*
X104842Y-515089D01*
X104685Y-514249D01*
Y-513409D01*
X104842Y-512569D01*
X105155Y-511834D01*
X105625Y-511204D01*
X106173Y-510784D01*
X106800Y-510679D01*
X107427Y-510784D01*
X107975Y-511204D01*
X108445Y-511834D01*
X108758Y-512569D01*
X108915Y-513409D01*
Y-514249D01*
X108758Y-515089D01*
X108445Y-515824D01*
X107975Y-516454D01*
X107427Y-516874D01*
X106800Y-516979D01*
G01X113100D02*
Y-514144D01*
X111533Y-510679D01*
G01X114667D02*
X113100Y-514144D01*
G01X117677Y-510679D02*
Y-515194D01*
X117990Y-516139D01*
X118617Y-516769D01*
X119400Y-516979D01*
X120183Y-516769D01*
X120810Y-516139D01*
X121123Y-515194D01*
Y-510679D01*
G01X123742Y-516979D02*
X125700Y-510679D01*
X127658Y-516979D01*
G01X126953Y-514774D02*
X124447D01*
G01X130198Y-516979D02*
Y-510679D01*
X133802Y-516979D01*
Y-510679D01*
G01X4198Y-506979D02*
Y-500679D01*
X7802Y-506979D01*
Y-500679D01*
G01X12300Y-506979D02*
X11673Y-506874D01*
X11125Y-506454D01*
X10655Y-505824D01*
X10342Y-505089D01*
X10185Y-504249D01*
Y-503409D01*
X10342Y-502569D01*
X10655Y-501834D01*
X11125Y-501204D01*
X11673Y-500784D01*
X12300Y-500679D01*
X12927Y-500784D01*
X13475Y-501204D01*
X13945Y-501834D01*
X14258Y-502569D01*
X14415Y-503409D01*
Y-504249D01*
X14258Y-505089D01*
X13945Y-505824D01*
X13475Y-506454D01*
X12927Y-506874D01*
X12300Y-506979D01*
G01X18600Y-507189D02*
X18443Y-507084D01*
Y-506874D01*
X18600Y-506769D01*
X18757Y-506874D01*
Y-507084D01*
X18600Y-507189D01*
G01X23412Y-501729D02*
X23882Y-501099D01*
X24430Y-500784D01*
X25057Y-500679D01*
X25840Y-500889D01*
X26388Y-501414D01*
X26545Y-502044D01*
X26467Y-502674D01*
X26153Y-503199D01*
X24587Y-504249D01*
X23882Y-504984D01*
X23412Y-506034D01*
X23255Y-506979D01*
X26545D01*
G01X31200D02*
Y-500679D01*
X30260Y-501939D01*
G01Y-506979D02*
X32140D01*
G01X37500D02*
Y-500679D01*
X36560Y-501939D01*
G01Y-506979D02*
X38440D01*
G01X43643Y-508134D02*
X43957Y-506769D01*
G01X47750Y-500679D02*
X48847Y-506979D01*
X50100Y-500679D01*
X51353Y-506979D01*
X52450Y-500679D01*
G01X57967Y-506979D02*
X54833D01*
Y-500679D01*
X57967D01*
G01X56713Y-503724D02*
X54833D01*
G01X60898Y-506979D02*
Y-500679D01*
X64502Y-506979D01*
Y-500679D01*
G01X67355Y-506979D02*
Y-500679D01*
G01X70645D02*
Y-506979D01*
G01Y-503829D02*
X67355D01*
G01X73577Y-500679D02*
Y-505194D01*
X73890Y-506139D01*
X74517Y-506769D01*
X75300Y-506979D01*
X76083Y-506769D01*
X76710Y-506139D01*
X77023Y-505194D01*
Y-500679D01*
G01X79642Y-506979D02*
X81600Y-500679D01*
X83558Y-506979D01*
G01X82853Y-504774D02*
X80347D01*
G01X92712Y-501729D02*
X93182Y-501099D01*
X93730Y-500784D01*
X94357Y-500679D01*
X95140Y-500889D01*
X95688Y-501414D01*
X95845Y-502044D01*
X95767Y-502674D01*
X95453Y-503199D01*
X93887Y-504249D01*
X93182Y-504984D01*
X92712Y-506034D01*
X92555Y-506979D01*
X95845D01*
G01X98698D02*
Y-500679D01*
X102302Y-506979D01*
Y-500679D01*
G01X105077Y-506979D02*
Y-500679D01*
X106643D01*
X107270Y-500994D01*
X107740Y-501414D01*
X108132Y-502044D01*
X108445Y-502779D01*
X108523Y-503829D01*
X108445Y-504879D01*
X108132Y-505614D01*
X107740Y-506244D01*
X107270Y-506664D01*
X106643Y-506979D01*
X105077D01*
G01X117833D02*
Y-500679D01*
X119792D01*
X120418Y-500994D01*
X120810Y-501414D01*
X120967Y-502254D01*
X120810Y-503094D01*
X120340Y-503619D01*
X119792Y-503934D01*
X117833D01*
G01X119792D02*
X120967Y-506979D01*
G01X123977D02*
Y-500679D01*
X125543D01*
X126170Y-500994D01*
X126640Y-501414D01*
X127032Y-502044D01*
X127345Y-502779D01*
X127423Y-503829D01*
X127345Y-504879D01*
X127032Y-505614D01*
X126640Y-506244D01*
X126170Y-506664D01*
X125543Y-506979D01*
X123977D01*
G01X132000Y-507189D02*
X131843Y-507084D01*
Y-506874D01*
X132000Y-506769D01*
X132157Y-506874D01*
Y-507084D01*
X132000Y-507189D01*
G01X28300Y-494279D02*
X25780Y-493862D01*
X23575Y-492196D01*
X21685Y-489696D01*
X20425Y-486779D01*
X19795Y-483446D01*
Y-480112D01*
X20425Y-476779D01*
X21685Y-473862D01*
X23575Y-471363D01*
X25780Y-469696D01*
X28300Y-469279D01*
X30820Y-469696D01*
X33025Y-471363D01*
X34915Y-473862D01*
X36175Y-476779D01*
X36805Y-480112D01*
Y-483446D01*
X36175Y-486779D01*
X34915Y-489696D01*
X33025Y-492196D01*
X30820Y-493862D01*
X28300Y-494279D01*
G01X30820Y-487612D02*
X34600Y-494279D01*
G01X48145Y-477613D02*
Y-489279D01*
X49405Y-492196D01*
X51295Y-493862D01*
X53500Y-494279D01*
X55705Y-493862D01*
X57595Y-492196D01*
X58855Y-489279D01*
G01Y-494279D02*
Y-477613D01*
G01X84370Y-494279D02*
Y-477613D01*
G01Y-480529D02*
X83110Y-478863D01*
X81220Y-478029D01*
X79015Y-477613D01*
X76810Y-478446D01*
X74920Y-480112D01*
X73660Y-482613D01*
X73030Y-485946D01*
X73660Y-489279D01*
X74920Y-491780D01*
X76810Y-493446D01*
X79015Y-494279D01*
X81220Y-493862D01*
X83110Y-492613D01*
X84370Y-490946D01*
G01X98545Y-494279D02*
Y-477613D01*
G01Y-481779D02*
X99805Y-479696D01*
X101695Y-478029D01*
X104215Y-477613D01*
X106420Y-478029D01*
X108310Y-479696D01*
X109255Y-482613D01*
Y-494279D01*
G01X129100Y-469279D02*
Y-494279D01*
G01X124690Y-477613D02*
X133510D01*
G01X159970Y-494279D02*
Y-477613D01*
G01Y-480529D02*
X158710Y-478863D01*
X156820Y-478029D01*
X154615Y-477613D01*
X152410Y-478446D01*
X150520Y-480112D01*
X149260Y-482613D01*
X148630Y-485946D01*
X149260Y-489279D01*
X150520Y-491780D01*
X152410Y-493446D01*
X154615Y-494279D01*
X156820Y-493862D01*
X158710Y-492613D01*
X159970Y-490946D01*
G01X204679Y-508436D02*
Y-500436D01*
X207079D01*
X207879Y-500836D01*
X208479Y-501769D01*
X208679Y-502836D01*
X208479Y-503903D01*
X207979Y-504703D01*
X207079Y-505103D01*
X204679D01*
G01X212179Y-508436D02*
X214679Y-500436D01*
X217179Y-508436D01*
G01X216279Y-505636D02*
X213079D01*
G01X220579Y-507370D02*
X221379Y-508036D01*
X222279Y-508436D01*
X223079D01*
X223879Y-508036D01*
X224479Y-507370D01*
X224779Y-506436D01*
X224579Y-505503D01*
X224079Y-504703D01*
X223179Y-504169D01*
X221979Y-503903D01*
X221279Y-503369D01*
X220979Y-502436D01*
X221179Y-501503D01*
X221679Y-500836D01*
X222379Y-500436D01*
X223079D01*
X223779Y-500703D01*
X224379Y-501369D01*
G01X230679Y-500436D02*
Y-508436D01*
G01X228379Y-500436D02*
X232979D01*
G01X237379Y-505769D02*
X239979D01*
G01X246679Y-500436D02*
Y-508436D01*
G01X244379Y-500436D02*
X248979D01*
G01X254679Y-508436D02*
X253879Y-508303D01*
X253179Y-507769D01*
X252579Y-506969D01*
X252179Y-506036D01*
X251979Y-504969D01*
Y-503903D01*
X252179Y-502836D01*
X252579Y-501903D01*
X253179Y-501103D01*
X253879Y-500569D01*
X254679Y-500436D01*
X255479Y-500569D01*
X256179Y-501103D01*
X256779Y-501903D01*
X257179Y-502836D01*
X257379Y-503903D01*
Y-504969D01*
X257179Y-506036D01*
X256779Y-506969D01*
X256179Y-507769D01*
X255479Y-508303D01*
X254679Y-508436D01*
G01X260679D02*
Y-500436D01*
X263079D01*
X263879Y-500836D01*
X264479Y-501769D01*
X264679Y-502836D01*
X264479Y-503903D01*
X263979Y-504703D01*
X263079Y-505103D01*
X260679D01*
G01X199650Y-473979D02*
Y-481979D01*
X203650D01*
G01X211450D02*
Y-476646D01*
G01Y-477579D02*
X211050Y-477046D01*
X210450Y-476779D01*
X209750Y-476646D01*
X209050Y-476912D01*
X208450Y-477446D01*
X208050Y-478246D01*
X207850Y-479312D01*
X208050Y-480379D01*
X208450Y-481179D01*
X209050Y-481712D01*
X209750Y-481979D01*
X210450Y-481846D01*
X211050Y-481446D01*
X211450Y-480913D01*
G01X215550Y-484379D02*
X216150Y-484646D01*
X216950Y-484379D01*
X217450Y-483846D01*
X217850Y-483179D01*
X218450Y-481046D01*
X219750Y-476646D01*
G01X216550D02*
X218450Y-481046D01*
G01X224150Y-478379D02*
X227350D01*
X227050Y-477446D01*
X226550Y-476912D01*
X225850Y-476646D01*
X225150Y-476779D01*
X224550Y-477179D01*
X224150Y-478112D01*
X223950Y-478913D01*
Y-479712D01*
X224150Y-480512D01*
X224650Y-481312D01*
X225250Y-481846D01*
X225950Y-481979D01*
X226650Y-481712D01*
X227350Y-480913D01*
G01X232250Y-481979D02*
Y-476646D01*
G01Y-477712D02*
X232750Y-477179D01*
X233250Y-476779D01*
X233950Y-476646D01*
X234450Y-476779D01*
X235050Y-477179D01*
G01X223350Y-531979D02*
Y-523979D01*
X227950Y-531979D01*
Y-523979D01*
G01X233650Y-526646D02*
Y-531979D01*
G01Y-524512D02*
X233450Y-524379D01*
Y-524112D01*
X233650Y-523979D01*
X233850Y-524112D01*
Y-524379D01*
X233650Y-524512D01*
G01X239950Y-531979D02*
Y-526646D01*
G01Y-527979D02*
X240350Y-527312D01*
X240950Y-526779D01*
X241750Y-526646D01*
X242450Y-526779D01*
X243050Y-527312D01*
X243350Y-528246D01*
Y-531979D01*
G01X251450D02*
Y-526646D01*
G01Y-527579D02*
X251050Y-527046D01*
X250450Y-526779D01*
X249750Y-526646D01*
X249050Y-526912D01*
X248450Y-527446D01*
X248050Y-528246D01*
X247850Y-529312D01*
X248050Y-530379D01*
X248450Y-531179D01*
X249050Y-531712D01*
X249750Y-531979D01*
X250450Y-531846D01*
X251050Y-531446D01*
X251450Y-530913D01*
G01X326250Y-525312D02*
X326850Y-524512D01*
X327550Y-524112D01*
X328350Y-523979D01*
X329350Y-524246D01*
X330050Y-524912D01*
X330250Y-525712D01*
X330150Y-526513D01*
X329750Y-527179D01*
X327750Y-528512D01*
X326850Y-529446D01*
X326250Y-530779D01*
X326050Y-531979D01*
X330250D01*
G01X336150Y-523979D02*
X335350Y-524246D01*
X334750Y-524912D01*
X334350Y-525712D01*
X334050Y-526779D01*
X333950Y-527979D01*
X334050Y-529179D01*
X334350Y-530246D01*
X334750Y-531046D01*
X335350Y-531712D01*
X336150Y-531979D01*
X336950Y-531712D01*
X337550Y-531046D01*
X337950Y-530246D01*
X338250Y-529179D01*
X338350Y-527979D01*
X338250Y-526779D01*
X337950Y-525712D01*
X337550Y-524912D01*
X336950Y-524246D01*
X336150Y-523979D01*
G01X342250Y-525312D02*
X342850Y-524512D01*
X343550Y-524112D01*
X344350Y-523979D01*
X345350Y-524246D01*
X346050Y-524912D01*
X346250Y-525712D01*
X346150Y-526513D01*
X345750Y-527179D01*
X343750Y-528512D01*
X342850Y-529446D01*
X342250Y-530779D01*
X342050Y-531979D01*
X346250D01*
G01X349950Y-530379D02*
X350550Y-531312D01*
X351350Y-531846D01*
X352250Y-531979D01*
X353050Y-531846D01*
X353850Y-531179D01*
X354350Y-530379D01*
X354450Y-529579D01*
X354250Y-528646D01*
X353550Y-527979D01*
X352850Y-527712D01*
X351950D01*
G01X352850D02*
X353450Y-527312D01*
X353950Y-526646D01*
X354150Y-525846D01*
X353950Y-525046D01*
X353450Y-524379D01*
X352550Y-523979D01*
X351650Y-524112D01*
X350750Y-524646D01*
G01X358350Y-532246D02*
X361950Y-523979D01*
G01X368150D02*
X367350Y-524246D01*
X366750Y-524912D01*
X366350Y-525712D01*
X366050Y-526779D01*
X365950Y-527979D01*
X366050Y-529179D01*
X366350Y-530246D01*
X366750Y-531046D01*
X367350Y-531712D01*
X368150Y-531979D01*
X368950Y-531712D01*
X369550Y-531046D01*
X369950Y-530246D01*
X370250Y-529179D01*
X370350Y-527979D01*
X370250Y-526779D01*
X369950Y-525712D01*
X369550Y-524912D01*
X368950Y-524246D01*
X368150Y-523979D01*
G01X373950Y-530379D02*
X374550Y-531312D01*
X375350Y-531846D01*
X376250Y-531979D01*
X377050Y-531846D01*
X377850Y-531179D01*
X378350Y-530379D01*
X378450Y-529579D01*
X378250Y-528646D01*
X377550Y-527979D01*
X376850Y-527712D01*
X375950D01*
G01X376850D02*
X377450Y-527312D01*
X377950Y-526646D01*
X378150Y-525846D01*
X377950Y-525046D01*
X377450Y-524379D01*
X376550Y-523979D01*
X375650Y-524112D01*
X374750Y-524646D01*
G01X382350Y-532246D02*
X385950Y-523979D01*
G01X390250Y-525312D02*
X390850Y-524512D01*
X391550Y-524112D01*
X392350Y-523979D01*
X393350Y-524246D01*
X394050Y-524912D01*
X394250Y-525712D01*
X394150Y-526513D01*
X393750Y-527179D01*
X391750Y-528512D01*
X390850Y-529446D01*
X390250Y-530779D01*
X390050Y-531979D01*
X394250D01*
G01X401350D02*
Y-523979D01*
X397650Y-529712D01*
X402650D01*
G01X325950Y-506979D02*
Y-498979D01*
X327950D01*
X328750Y-499379D01*
X329350Y-499912D01*
X329850Y-500712D01*
X330250Y-501646D01*
X330350Y-502979D01*
X330250Y-504312D01*
X329850Y-505246D01*
X329350Y-506046D01*
X328750Y-506579D01*
X327950Y-506979D01*
X325950D01*
G01X333650D02*
X336150Y-498979D01*
X338650Y-506979D01*
G01X337750Y-504179D02*
X334550D01*
G01X344150Y-498979D02*
X343350Y-499246D01*
X342750Y-499912D01*
X342350Y-500712D01*
X342050Y-501779D01*
X341950Y-502979D01*
X342050Y-504179D01*
X342350Y-505246D01*
X342750Y-506046D01*
X343350Y-506712D01*
X344150Y-506979D01*
X344950Y-506712D01*
X345550Y-506046D01*
X345950Y-505246D01*
X346250Y-504179D01*
X346350Y-502979D01*
X346250Y-501779D01*
X345950Y-500712D01*
X345550Y-499912D01*
X344950Y-499246D01*
X344150Y-498979D01*
G01X350250Y-506979D02*
Y-498979D01*
X354050D01*
G01X352650Y-502846D02*
X350250D01*
G01X360150Y-498979D02*
X359350Y-499246D01*
X358750Y-499912D01*
X358350Y-500712D01*
X358050Y-501779D01*
X357950Y-502979D01*
X358050Y-504179D01*
X358350Y-505246D01*
X358750Y-506046D01*
X359350Y-506712D01*
X360150Y-506979D01*
X360950Y-506712D01*
X361550Y-506046D01*
X361950Y-505246D01*
X362250Y-504179D01*
X362350Y-502979D01*
X362250Y-501779D01*
X361950Y-500712D01*
X361550Y-499912D01*
X360950Y-499246D01*
X360150Y-498979D01*
G01X368150D02*
Y-506979D01*
G01X365850Y-498979D02*
X370450D01*
G01X373550Y-506979D02*
Y-498979D01*
X376150Y-505646D01*
X378750Y-498979D01*
Y-506979D01*
G01X384950Y-502712D02*
X385350Y-502312D01*
X385650Y-501646D01*
X385850Y-500712D01*
X385650Y-499912D01*
X385250Y-499379D01*
X384550Y-498979D01*
X381850D01*
Y-506979D01*
X385150D01*
X385850Y-506446D01*
X386250Y-505646D01*
X386450Y-504712D01*
X386250Y-503779D01*
X385650Y-502979D01*
X384950Y-502712D01*
X381850D01*
G01X390950Y-498979D02*
X393350D01*
G01X392150D02*
Y-506979D01*
G01X390950D02*
X393350D01*
G01X398150Y-505379D02*
X398650Y-506179D01*
X399250Y-506712D01*
X399950Y-506979D01*
X400750Y-506712D01*
X401350Y-506179D01*
X401950Y-505379D01*
X402150Y-504312D01*
Y-498979D01*
G01X408150D02*
X407350Y-499246D01*
X406750Y-499912D01*
X406350Y-500712D01*
X406050Y-501779D01*
X405950Y-502979D01*
X406050Y-504179D01*
X406350Y-505246D01*
X406750Y-506046D01*
X407350Y-506712D01*
X408150Y-506979D01*
X408950Y-506712D01*
X409550Y-506046D01*
X409950Y-505246D01*
X410250Y-504179D01*
X410350Y-502979D01*
X410250Y-501779D01*
X409950Y-500712D01*
X409550Y-499912D01*
X408950Y-499246D01*
X408150Y-498979D01*
G01X343750Y-481979D02*
Y-473979D01*
X347550D01*
G01X346150Y-477846D02*
X343750D01*
G01X353650Y-473979D02*
X352850Y-474246D01*
X352250Y-474912D01*
X351850Y-475712D01*
X351550Y-476779D01*
X351450Y-477979D01*
X351550Y-479179D01*
X351850Y-480246D01*
X352250Y-481046D01*
X352850Y-481712D01*
X353650Y-481979D01*
X354450Y-481712D01*
X355050Y-481046D01*
X355450Y-480246D01*
X355750Y-479179D01*
X355850Y-477979D01*
X355750Y-476779D01*
X355450Y-475712D01*
X355050Y-474912D01*
X354450Y-474246D01*
X353650Y-473979D01*
G01X361650D02*
Y-481979D01*
G01X359350Y-473979D02*
X363950D01*
G01X366650Y-484646D02*
X372650D01*
G01X375050Y-481979D02*
Y-473979D01*
X377650Y-480646D01*
X380250Y-473979D01*
Y-481979D01*
G01X386450Y-477712D02*
X386850Y-477312D01*
X387150Y-476646D01*
X387350Y-475712D01*
X387150Y-474912D01*
X386750Y-474379D01*
X386050Y-473979D01*
X383350D01*
Y-481979D01*
X386650D01*
X387350Y-481446D01*
X387750Y-480646D01*
X387950Y-479712D01*
X387750Y-478779D01*
X387150Y-477979D01*
X386450Y-477712D01*
X383350D01*
G01X390650Y-484646D02*
X396650D01*
G01X403650Y-481979D02*
X399650D01*
Y-473979D01*
X403650D01*
G01X402050Y-477846D02*
X399650D01*
G01X407050Y-481979D02*
Y-473979D01*
X409650Y-480646D01*
X412250Y-473979D01*
Y-481979D01*
G01X417650D02*
X418350Y-481846D01*
X419150Y-481446D01*
X419650Y-480779D01*
X419850Y-479846D01*
X419650Y-478913D01*
X419050Y-478112D01*
X418150Y-477712D01*
X417150D01*
X416550Y-477446D01*
X416050Y-476779D01*
X415850Y-475846D01*
X416150Y-474912D01*
X416850Y-474246D01*
X417650Y-473979D01*
X418450Y-474246D01*
X419150Y-474912D01*
X419450Y-475846D01*
X419250Y-476779D01*
X418750Y-477446D01*
X418150Y-477712D01*
X417150D01*
X416250Y-478112D01*
X415650Y-478913D01*
X415450Y-479846D01*
X415650Y-480779D01*
X416150Y-481446D01*
X416950Y-481846D01*
X417650Y-481979D01*
G01X423950Y-481046D02*
X424650Y-481712D01*
X425450Y-481979D01*
X426250Y-481712D01*
X426950Y-480913D01*
X427450Y-479712D01*
X427650Y-478512D01*
Y-477046D01*
X427450Y-475846D01*
X426950Y-474779D01*
X426350Y-474246D01*
X425650Y-473979D01*
X424850Y-474246D01*
X424250Y-474779D01*
X423850Y-475579D01*
X423650Y-476646D01*
X423850Y-477579D01*
X424350Y-478512D01*
X424950Y-479046D01*
X425650Y-479179D01*
X426450Y-478913D01*
X427050Y-478246D01*
X427650Y-477046D01*
G01X433650Y-473979D02*
X432850Y-474246D01*
X432250Y-474912D01*
X431850Y-475712D01*
X431550Y-476779D01*
X431450Y-477979D01*
X431550Y-479179D01*
X431850Y-480246D01*
X432250Y-481046D01*
X432850Y-481712D01*
X433650Y-481979D01*
X434450Y-481712D01*
X435050Y-481046D01*
X435450Y-480246D01*
X435750Y-479179D01*
X435850Y-477979D01*
X435750Y-476779D01*
X435450Y-475712D01*
X435050Y-474912D01*
X434450Y-474246D01*
X433650Y-473979D01*
G01X439450Y-481979D02*
Y-473979D01*
G01X443250D02*
X439450Y-478913D01*
G01X443850Y-481979D02*
X441150Y-476646D01*
G01X414650Y-534979D02*
Y-526979D01*
X413450Y-528579D01*
G01Y-534979D02*
X415850D01*
G01X420750Y-531646D02*
X421450Y-530712D01*
X422050Y-530179D01*
X422850Y-529912D01*
X423550Y-530179D01*
X424050Y-530712D01*
X424450Y-531512D01*
X424550Y-532446D01*
X424450Y-533246D01*
X424050Y-534046D01*
X423450Y-534712D01*
X422750Y-534979D01*
X421950Y-534712D01*
X421250Y-533913D01*
X420850Y-532712D01*
X420750Y-531379D01*
X420950Y-529646D01*
X421250Y-528712D01*
X421750Y-527779D01*
X422450Y-527112D01*
X423150Y-526979D01*
X423850Y-527246D01*
X424350Y-527912D01*
G01X430650Y-535246D02*
X430450Y-535112D01*
Y-534846D01*
X430650Y-534712D01*
X430850Y-534846D01*
Y-535112D01*
X430650Y-535246D01*
G01X436750Y-531646D02*
X437450Y-530712D01*
X438050Y-530179D01*
X438850Y-529912D01*
X439550Y-530179D01*
X440050Y-530712D01*
X440450Y-531512D01*
X440550Y-532446D01*
X440450Y-533246D01*
X440050Y-534046D01*
X439450Y-534712D01*
X438750Y-534979D01*
X437950Y-534712D01*
X437250Y-533913D01*
X436850Y-532712D01*
X436750Y-531379D01*
X436950Y-529646D01*
X437250Y-528712D01*
X437750Y-527779D01*
X438450Y-527112D01*
X439150Y-526979D01*
X439850Y-527246D01*
X440350Y-527912D01*
G01X459650Y-534979D02*
Y-526979D01*
X458450Y-528579D01*
G01Y-534979D02*
X460850D01*
G01X467450D02*
X467650Y-533246D01*
X467950Y-531779D01*
X468350Y-530446D01*
X468850Y-528979D01*
X469650Y-526979D01*
X465650D01*
G01X475650Y-535246D02*
X475450Y-535112D01*
Y-534846D01*
X475650Y-534712D01*
X475850Y-534846D01*
Y-535112D01*
X475650Y-535246D01*
G01X481750Y-528312D02*
X482350Y-527512D01*
X483050Y-527112D01*
X483850Y-526979D01*
X484850Y-527246D01*
X485550Y-527912D01*
X485750Y-528712D01*
X485650Y-529513D01*
X485250Y-530179D01*
X483250Y-531512D01*
X482350Y-532446D01*
X481750Y-533779D01*
X481550Y-534979D01*
X485750D01*
G01X479650Y-508379D02*
X480150Y-509179D01*
X480750Y-509712D01*
X481450Y-509979D01*
X482250Y-509712D01*
X482850Y-509179D01*
X483450Y-508379D01*
X483650Y-507312D01*
Y-501979D01*
G54D97*
X164470Y1430123D03*
X178840D03*
X678299Y1430118D03*
X692669D03*
X990710Y288546D03*
X976340D03*
X1152361Y1466422D03*
X1137991D03*
X1639465Y1463714D03*
X1653835D03*
X1682863Y648743D03*
X1697233D03*
G54D199*
X779220Y1578633D03*
Y1592413D03*
X796938Y1578633D03*
Y1592413D03*
X821220Y1578633D03*
Y1592413D03*
X838938Y1578633D03*
Y1592413D03*
X863220Y1578633D03*
Y1592413D03*
X880938Y1578633D03*
Y1592413D03*
X905220Y1578633D03*
Y1592413D03*
X922938Y1578633D03*
Y1592413D03*
G36*
G01X160230Y1545395D02*
X162047D01*
G03X162244Y1545592I0J197D01*
G01Y1549725D01*
G03X162047Y1549922I-197J0D01*
G01X157914D01*
G03X157717Y1549725I0J-197D01*
G01Y1545592D01*
G03X157914Y1545395I197J0D01*
G01X159730D01*
Y1544607D01*
X157914D01*
G03X157717Y1544410I0J-197D01*
G01Y1542594D01*
X156929D01*
Y1544410D01*
G03X156732Y1544607I-197J0D01*
G01X154916D01*
Y1545395D01*
X156732D01*
G03X156929Y1545592I0J197D01*
G01Y1549725D01*
G03X156732Y1549922I-197J0D01*
G01X152599D01*
G03X152402Y1549725I0J-197D01*
G01Y1545592D01*
G03X152599Y1545395I197J0D01*
G01X154416D01*
Y1544607D01*
X152599D01*
G03X152402Y1544410I0J-197D01*
G01Y1540277D01*
G03X152599Y1540080I197J0D01*
G01X156732D01*
G03X156929Y1540277I0J197D01*
G01Y1542094D01*
X157717D01*
Y1540277D01*
G03X157914Y1540080I197J0D01*
G01X162047D01*
G03X162244Y1540277I0J197D01*
G01Y1544410D01*
G03X162047Y1544607I-197J0D01*
G01X160230D01*
Y1545395D01*
G37*
G54D79*
X159474Y1320753D03*
X183847Y1320778D03*
X208247D03*
X275289Y575702D03*
Y599861D03*
Y624015D03*
Y648169D03*
X278126Y676260D03*
Y700414D03*
X395771Y1242785D03*
X420171D03*
X444493D03*
X468893D03*
X493293D03*
X673093Y1320778D03*
X697466Y1320803D03*
X721866D03*
X1100800Y251488D03*
X1100700Y275788D03*
X1131100Y1357088D03*
X1155500D03*
X1179900D03*
X1371912Y1242785D03*
X1396312D03*
X1420634D03*
X1445034D03*
X1469434D03*
X1577000Y591888D03*
Y616388D03*
Y640888D03*
Y665288D03*
Y689788D03*
Y714288D03*
X1634259Y1354374D03*
X1658632Y1354399D03*
X1683032D03*
G54D98*
X211120Y578610D03*
Y612610D03*
Y646610D03*
X1642853Y641972D03*
Y675972D03*
Y709972D03*
G54D89*
X158307Y1537521D03*
X156339D03*
X154370D03*
X152402D03*
Y1552481D03*
X154370D03*
X156339D03*
X158307D03*
X162244Y1537521D03*
X160276D03*
Y1552481D03*
X162244D03*
G54D99*
X211101Y588157D03*
Y622157D03*
Y656157D03*
X1642872Y632425D03*
Y666425D03*
Y700425D03*
M02*
